G04 ================== begin FILE IDENTIFICATION RECORD ==================*
G04 Layout Name:  9127_F0T_Expander_BD_F_v02_0110_1240.brd*
G04 Film Name:    sst*
G04 File Format:  Gerber RS274X*
G04 File Origin:  Cadence Allegro 17.2-S081*
G04 Origin Date:  Wed Jan 11 16:06:35 2023*
G04 *
G04 Layer:  DRAWING FORMAT/TITLE_BLOCK_A*
G04 Layer:  BOARD GEOMETRY/DESIGN_OUTLINE*
G04 Layer:  BOARD GEOMETRY/CUTOUT*
G04 Layer:  DRAWING FORMAT/TITLE_BLOCK*
G04 Layer:  MANUFACTURING/TP_TEXT_TOP*
G04 Layer:  REF DES/SILKSCREEN_TOP*
G04 Layer:  PACKAGE GEOMETRY/SILKSCREEN_TOP*
G04 Layer:  MANUFACTURING/PHOTOPLOT_OUTLINE*
G04 Layer:  DRAWING FORMAT/TITLE_DATA_SST*
G04 Layer:  BOARD GEOMETRY/SILKSCREEN_TOP*
G04 *
G04 Offset:    (0.00 0.00)*
G04 Mirror:    No*
G04 Mode:      Positive*
G04 Rotation:  0*
G04 FullContactRelief:  No*
G04 UndefLineWidth:     6.00*
G04 ================== end FILE IDENTIFICATION RECORD ====================*
%FSLAX25Y25*MOIN*%
%IR0*IPPOS*OFA0.00000B0.00000*MIA0B0*SFA1.00000B1.00000*%
%ADD10C,.01*%
%ADD11C,.006*%
G75*
%LPD*%
G75*
G36*
G01X4522Y108343D02*
X7110Y109205D01*
X6247Y106617D01*
X4522Y108343D01*
G37*
G36*
G01X8275Y165215D02*
X5446Y162386D01*
X9689Y160972D01*
X8275Y165215D01*
G37*
G36*
G01X15807Y254386D02*
X14747Y257568D01*
X12625Y255447D01*
X15807Y254386D01*
G37*
G36*
G01X16680Y273524D02*
X15620Y276706D01*
X13498Y274585D01*
X16680Y273524D01*
G37*
G36*
G01X16751Y286607D02*
X14369Y285416D01*
Y287798D01*
X16751Y286607D01*
G37*
G36*
G01X7548Y1489517D02*
X3248Y1491817D01*
Y1487617D01*
X7548Y1489517D01*
G37*
G36*
G01X37820Y71149D02*
X36157Y66159D01*
X32830Y69486D01*
X37820Y71149D01*
G37*
G36*
G01X21028Y211197D02*
Y214197D01*
X19728D01*
Y211197D01*
X21028D01*
G37*
G36*
G01X24166Y1501428D02*
Y1503728D01*
X21866D01*
Y1501428D01*
X24166D01*
G37*
G36*
G01X38828Y195583D02*
Y184087D01*
X35679D01*
Y195583D01*
X38828D01*
G37*
G36*
G01X50612Y462415D02*
X53794Y463476D01*
X51672Y465597D01*
X50612Y462415D01*
G37*
G36*
G01X37958Y518777D02*
Y503265D01*
X35358D01*
Y518777D01*
X37958D01*
G37*
G36*
G01X52181Y533338D02*
X49181D01*
Y532038D01*
X52181D01*
Y533338D01*
G37*
G36*
G01X51843Y1197141D02*
Y1201141D01*
X47843Y1199141D01*
X51843Y1197141D01*
G37*
G36*
G01X65596Y203452D02*
X54100D01*
Y206601D01*
X65596D01*
Y203452D01*
G37*
G36*
G01X65365Y262744D02*
X53869D01*
Y265893D01*
X65365D01*
Y262744D01*
G37*
G36*
G01X56407Y462419D02*
X53578Y459591D01*
X57821Y458177D01*
X56407Y462419D01*
G37*
G36*
G01X62012Y486594D02*
X59012D01*
Y485294D01*
X62012D01*
Y486594D01*
G37*
G36*
G01X67795Y550138D02*
X79291D01*
Y546989D01*
X67795D01*
Y550138D01*
G37*
G36*
G01X56133Y591861D02*
Y580365D01*
X52984D01*
Y591861D01*
X56133D01*
G37*
G36*
G01X58708Y626012D02*
X59893Y629568D01*
X62264Y627198D01*
X58708Y626012D01*
G37*
G36*
G01X60401Y1076493D02*
X63229Y1079322D01*
X58987Y1080736D01*
X60401Y1076493D01*
G37*
G36*
G01X63318Y1592190D02*
X66146Y1589362D01*
X67560Y1593604D01*
X63318Y1592190D01*
G37*
G36*
G01X59247Y1750941D02*
X65247Y1747941D01*
Y1753941D01*
X59247Y1750941D01*
G37*
G36*
G01Y1796941D02*
X65247Y1793941D01*
Y1799941D01*
X59247Y1796941D01*
G37*
G36*
G01X80776Y153690D02*
X79716Y156872D01*
X77594Y154751D01*
X80776Y153690D01*
G37*
G36*
G01X81210Y220252D02*
X84210D01*
Y221552D01*
X81210D01*
Y220252D01*
G37*
G36*
G01X77626Y504394D02*
X89122D01*
Y501245D01*
X77626D01*
Y504394D01*
G37*
G36*
G01X81735Y595630D02*
X78906Y598459D01*
X77492Y594216D01*
X81735Y595630D01*
G37*
G36*
G01X67936Y612215D02*
X83448D01*
Y609615D01*
X67936D01*
Y612215D01*
G37*
G36*
G01X72998Y669880D02*
X72320Y667846D01*
X70964Y669202D01*
X72998Y669880D01*
G37*
G36*
G01X71346Y829672D02*
X70165Y826128D01*
X72527D01*
X71346Y829672D01*
G37*
G36*
G01X82472Y1015163D02*
X79472Y1016663D01*
Y1013663D01*
X82472Y1015163D01*
G37*
G36*
G01X97611Y173632D02*
X100440Y176461D01*
X96197Y177875D01*
X97611Y173632D01*
G37*
G36*
G01X95433Y234813D02*
Y250325D01*
X98033D01*
Y234813D01*
X95433D01*
G37*
G36*
G01X93077Y267235D02*
X108589D01*
Y264635D01*
X93077D01*
Y267235D01*
G37*
G36*
G01X88193Y268332D02*
X91021Y271161D01*
X86779Y272575D01*
X88193Y268332D01*
G37*
G36*
G01X104729Y123906D02*
X101901Y121078D01*
X106143Y119664D01*
X104729Y123906D01*
G37*
G36*
G01X106489Y142689D02*
X104107Y141498D01*
Y143880D01*
X106489Y142689D01*
G37*
G36*
G01X118262Y253908D02*
X117201Y257090D01*
X115080Y254969D01*
X118262Y253908D01*
G37*
G36*
G01X106032Y870295D02*
X110032Y868295D01*
Y872295D01*
X106032Y870295D01*
G37*
G36*
G01X101246D02*
X106217Y872780D01*
Y867810D01*
X101246Y870295D01*
G37*
G36*
G01X100382Y1624402D02*
Y1620402D01*
X104382Y1622402D01*
X100382Y1624402D01*
G37*
G36*
G01X123390Y211197D02*
Y214197D01*
X122090D01*
Y211197D01*
X123390D01*
G37*
G36*
G01X140448Y71557D02*
X138785Y66566D01*
X135458Y69893D01*
X140448Y71557D01*
G37*
G36*
G01X141190Y195583D02*
Y184087D01*
X138041D01*
Y195583D01*
X141190D01*
G37*
G36*
G01X148818Y1258464D02*
Y1261464D01*
X138338D01*
Y1250984D01*
X141338D01*
Y1258464D01*
X148818D01*
G37*
G36*
G01X167958Y203452D02*
X156462D01*
Y206601D01*
X167958D01*
Y203452D01*
G37*
G36*
G01X167727Y262744D02*
X156231D01*
Y265893D01*
X167727D01*
Y262744D01*
G37*
G36*
G01X182816Y153697D02*
X181755Y156879D01*
X179634Y154758D01*
X182816Y153697D01*
G37*
G36*
G01X183572Y220252D02*
X186572D01*
Y221552D01*
X183572D01*
Y220252D01*
G37*
G36*
G01X195439Y267235D02*
X210951D01*
Y264635D01*
X195439D01*
Y267235D01*
G37*
G36*
G01X190132Y268894D02*
X192961Y271723D01*
X188718Y273137D01*
X190132Y268894D01*
G37*
G36*
G01X201774Y59585D02*
X202994Y62025D01*
X204214Y59585D01*
X201774D01*
G37*
G36*
G01X206849Y123543D02*
X204021Y120715D01*
X208264Y119301D01*
X206849Y123543D01*
G37*
G36*
G01X208851Y142689D02*
X206469Y141498D01*
Y143880D01*
X208851Y142689D01*
G37*
G36*
G01X199706Y172775D02*
X202534Y175603D01*
X198292Y177018D01*
X199706Y172775D01*
G37*
G36*
G01X197795Y234813D02*
Y250325D01*
X200395D01*
Y234813D01*
X197795D01*
G37*
G36*
G01X208880Y573453D02*
Y577453D01*
X204880Y575453D01*
X208880Y573453D01*
G37*
G36*
G01X225752Y211197D02*
Y214197D01*
X224452D01*
Y211197D01*
X225752D01*
G37*
G36*
G01X220235Y254659D02*
X219174Y257841D01*
X217053Y255719D01*
X220235Y254659D01*
G37*
G36*
G01X241802Y70459D02*
X240139Y65468D01*
X236812Y68795D01*
X241802Y70459D01*
G37*
G36*
G01X243552Y195583D02*
Y184087D01*
X240403D01*
Y195583D01*
X243552D01*
G37*
G36*
G01X240659Y632129D02*
X237477Y631068D01*
X239598Y628947D01*
X240659Y632129D01*
G37*
G36*
G01X249614Y848900D02*
Y844900D01*
X245614Y846900D01*
X249614Y848900D01*
G37*
G36*
G01Y916200D02*
Y912200D01*
X245614Y914200D01*
X249614Y916200D01*
G37*
G36*
G01X270320Y203452D02*
X258824D01*
Y206601D01*
X270320D01*
Y203452D01*
G37*
G36*
G01X270089Y262744D02*
X258593D01*
Y265893D01*
X270089D01*
Y262744D01*
G37*
G36*
G01X260805Y432059D02*
Y428059D01*
X264805Y430059D01*
X260805Y432059D01*
G37*
G36*
G01X273610Y1624402D02*
Y1620402D01*
X277610Y1622402D01*
X273610Y1624402D01*
G37*
G36*
G01X289995Y34140D02*
X287167Y31312D01*
X291409Y29898D01*
X289995Y34140D01*
G37*
G36*
G01X284725Y153836D02*
X283665Y157018D01*
X281543Y154896D01*
X284725Y153836D01*
G37*
G36*
G01X285934Y220252D02*
X288934D01*
Y221552D01*
X285934D01*
Y220252D01*
G37*
G36*
G01X292937Y268113D02*
X295766Y270942D01*
X291523Y272356D01*
X292937Y268113D01*
G37*
G36*
G01X304136Y59585D02*
X305356Y62025D01*
X306576Y59585D01*
X304136D01*
G37*
G36*
G01X309294Y123944D02*
X306466Y121115D01*
X310709Y119701D01*
X309294Y123944D01*
G37*
G36*
G01X311213Y142689D02*
X308831Y141498D01*
Y143880D01*
X311213Y142689D01*
G37*
G36*
G01X301963Y173933D02*
X304791Y176762D01*
X300549Y178176D01*
X301963Y173933D01*
G37*
G36*
G01X300157Y234813D02*
Y250325D01*
X302757D01*
Y234813D01*
X300157D01*
G37*
G36*
G01X297801Y267235D02*
X313313D01*
Y264635D01*
X297801D01*
Y267235D01*
G37*
G36*
G01X295923Y322716D02*
X297658Y321849D01*
X295923Y320982D01*
Y322716D01*
G37*
G36*
G01X297233Y348437D02*
Y346437D01*
X300233Y347437D01*
X297233Y348437D01*
G37*
G36*
G01X305449Y1760941D02*
X299449Y1763941D01*
Y1757941D01*
X305449Y1760941D01*
G37*
G36*
G01X305349Y1806941D02*
X299349Y1809941D01*
Y1803941D01*
X305349Y1806941D01*
G37*
G36*
G01X328114Y211197D02*
Y214197D01*
X326814D01*
Y211197D01*
X328114D01*
G37*
G36*
G01X322845Y253947D02*
X321784Y257129D01*
X319663Y255008D01*
X322845Y253947D01*
G37*
G36*
G01X326131Y329752D02*
Y327292D01*
X323951Y328584D01*
X326131Y329752D01*
G37*
G36*
G01X330014Y880900D02*
Y876900D01*
X326014Y878900D01*
X330014Y880900D01*
G37*
G36*
G01X331014Y951400D02*
Y947400D01*
X327014Y949400D01*
X331014Y951400D01*
G37*
G36*
G01X344975Y71206D02*
X343312Y66215D01*
X339985Y69542D01*
X344975Y71206D01*
G37*
G36*
G01X345914Y195583D02*
Y184087D01*
X342765D01*
Y195583D01*
X345914D01*
G37*
G36*
G01X338707Y1149853D02*
X336707Y1145853D01*
X340707D01*
X338707Y1149853D01*
G37*
G36*
G01X350375Y386758D02*
X353203Y383930D01*
X354617Y388173D01*
X350375Y386758D01*
G37*
G36*
G01X355369Y448993D02*
X358197Y446164D01*
X359611Y450407D01*
X355369Y448993D01*
G37*
G36*
G01X362202Y1169105D02*
X360982Y1166665D01*
X359762Y1169105D01*
X362202D01*
G37*
G36*
G01X346285Y1728583D02*
X352285Y1725583D01*
Y1731583D01*
X346285Y1728583D01*
G37*
G36*
G01X346211Y1774624D02*
X352211Y1771624D01*
Y1777624D01*
X346211Y1774624D01*
G37*
G36*
G01X372683Y203452D02*
X361187D01*
Y206601D01*
X372683D01*
Y203452D01*
G37*
G36*
G01X372682D02*
X361186D01*
Y206601D01*
X372682D01*
Y203452D01*
G37*
G36*
G01X372451Y262744D02*
X360955D01*
Y265893D01*
X372451D01*
Y262744D01*
G37*
G36*
G01X367132Y483629D02*
X370132D01*
Y484929D01*
X367132D01*
Y483629D01*
G37*
G36*
G01X387684Y35242D02*
X390124Y34022D01*
X387684Y32802D01*
Y35242D01*
G37*
G36*
G01X388296Y220252D02*
X391296D01*
Y221552D01*
X388296D01*
Y220252D01*
G37*
G36*
G01X390484Y397590D02*
Y394590D01*
X391784D01*
Y397590D01*
X390484D01*
G37*
G36*
G01X384500Y779564D02*
Y775564D01*
X388500Y777564D01*
X384500Y779564D01*
G37*
G36*
G01X377895Y963510D02*
X381349Y962359D01*
X380198Y965813D01*
X377895Y963510D01*
G37*
G36*
G01X404700Y174810D02*
X407528Y177638D01*
X403285Y179053D01*
X404700Y174810D01*
G37*
G36*
G01X402519Y234813D02*
Y250325D01*
X405119D01*
Y234813D01*
X402519D01*
G37*
G36*
G01X400163Y267235D02*
X415675D01*
Y264635D01*
X400163D01*
Y267235D01*
G37*
G36*
G01X394865Y268907D02*
X397693Y271735D01*
X393451Y273149D01*
X394865Y268907D01*
G37*
G36*
G01X408172Y476907D02*
X407111Y480089D01*
X404990Y477968D01*
X408172Y476907D01*
G37*
G36*
G01X409052Y884485D02*
X407552Y887485D01*
X410552D01*
X409052Y884485D01*
G37*
G36*
G01X404850Y885491D02*
Y881491D01*
X408850Y883491D01*
X404850Y885491D01*
G37*
G36*
G01X395697Y1533604D02*
X399108Y1531899D01*
X395697Y1530193D01*
Y1533604D01*
G37*
G36*
G01X411500Y345647D02*
Y348676D01*
X414529Y347161D01*
X411500Y345647D01*
G37*
G36*
G01X425138Y487943D02*
X413642D01*
Y491092D01*
X425138D01*
Y487943D01*
G37*
G36*
G01X434746Y153821D02*
X433685Y157003D01*
X431564Y154882D01*
X434746Y153821D01*
G37*
G36*
G01X431120Y432227D02*
X434473Y433903D01*
Y430551D01*
X431120Y432227D01*
G37*
G36*
G01X440752Y504743D02*
X443752D01*
Y506043D01*
X440752D01*
Y504743D01*
G37*
G36*
G01X440387Y625689D02*
X442063Y622336D01*
X438711Y622337D01*
X440387Y625689D01*
G37*
G36*
G01X444175Y624268D02*
Y628268D01*
X440175Y626268D01*
X444175Y624268D01*
G37*
G36*
G01X448797Y927099D02*
Y930481D01*
X430481D01*
Y927099D01*
X448797D01*
G37*
G36*
G01X425550Y1105471D02*
X429550D01*
X427550Y1109471D01*
X425550Y1105471D01*
G37*
G36*
G01X436070Y1567758D02*
X432070D01*
X434070Y1563758D01*
X436070Y1567758D01*
G37*
G36*
G01X459611Y123057D02*
X456783Y120229D01*
X461026Y118815D01*
X459611Y123057D01*
G37*
G36*
G01X446839Y1624402D02*
Y1620402D01*
X450839Y1622402D01*
X446839Y1624402D01*
G37*
G36*
G01X461214Y142689D02*
X458832Y141498D01*
Y143880D01*
X461214Y142689D01*
G37*
G36*
G01X461904Y463203D02*
X464732Y460375D01*
X466146Y464617D01*
X461904Y463203D01*
G37*
G36*
G01X468408Y1005803D02*
X469556Y1003507D01*
X467260D01*
X468408Y1005803D01*
G37*
G36*
G01X458156Y1106153D02*
X462156D01*
X460156Y1110153D01*
X458156Y1106153D01*
G37*
G36*
G01X492350Y70669D02*
X490687Y65678D01*
X487360Y69005D01*
X492350Y70669D01*
G37*
G36*
G01X478115Y211197D02*
Y214197D01*
X476815D01*
Y211197D01*
X478115D01*
G37*
G36*
G01X477238Y254969D02*
X480420Y256029D01*
X478298Y258151D01*
X477238Y254969D01*
G37*
G36*
G01X495915Y195583D02*
Y184087D01*
X492766D01*
Y195583D01*
X495915D01*
G37*
G36*
G01X493945Y386805D02*
Y382805D01*
X497945Y384805D01*
X493945Y386805D01*
G37*
G36*
G01X490591Y429548D02*
X493773Y430609D01*
X491652Y432730D01*
X490591Y429548D01*
G37*
G36*
G01X505819Y459728D02*
X509001Y460789D01*
X506880Y462910D01*
X505819Y459728D01*
G37*
G36*
G01X495044Y518777D02*
Y503265D01*
X492444D01*
Y518777D01*
X495044D01*
G37*
G36*
G01X509267Y533338D02*
X506267D01*
Y532038D01*
X509267D01*
Y533338D01*
G37*
G36*
G01X496754Y671758D02*
X499754Y673258D01*
Y670258D01*
X496754Y671758D01*
G37*
G36*
G01X506024Y712238D02*
Y708238D01*
X510024Y710238D01*
X506024Y712238D01*
G37*
G36*
G01X492041Y1107554D02*
X496041D01*
X494041Y1111554D01*
X492041Y1107554D01*
G37*
G36*
G01X522683Y203452D02*
X511187D01*
Y206601D01*
X522683D01*
Y203452D01*
G37*
G36*
G01X522452Y262744D02*
X510956D01*
Y265893D01*
X522452D01*
Y262744D01*
G37*
G36*
G01X511035Y459467D02*
X508207Y456639D01*
X512449Y455225D01*
X511035Y459467D01*
G37*
G36*
G01X519098Y486594D02*
X516098D01*
Y485294D01*
X519098D01*
Y486594D01*
G37*
G36*
G01X513219Y591861D02*
Y580365D01*
X510070D01*
Y591861D01*
X513219D01*
G37*
G36*
G01X515515Y625957D02*
X516701Y629513D01*
X519071Y627142D01*
X515515Y625957D01*
G37*
G36*
G01X519753Y780896D02*
X518253Y783896D01*
X521253D01*
X519753Y780896D01*
G37*
G36*
G01X537744Y152692D02*
X536683Y155874D01*
X534562Y153752D01*
X537744Y152692D01*
G37*
G36*
G01X538297Y220252D02*
X541297D01*
Y221552D01*
X538297D01*
Y220252D01*
G37*
G36*
G01X534712Y504394D02*
X546208D01*
Y501245D01*
X534712D01*
Y504394D01*
G37*
G36*
G01X524881Y550138D02*
X536377D01*
Y546989D01*
X524881D01*
Y550138D01*
G37*
G36*
G01X538765Y595577D02*
X535937Y598406D01*
X534523Y594163D01*
X538765Y595577D01*
G37*
G36*
G01X525022Y612215D02*
X540534D01*
Y609615D01*
X525022D01*
Y612215D01*
G37*
G36*
G01X538075Y757378D02*
X535775Y753078D01*
X539975D01*
X538075Y757378D01*
G37*
G36*
G01X528813Y785463D02*
X531642Y782634D01*
X533056Y786877D01*
X528813Y785463D01*
G37*
G36*
G01X539559Y1015163D02*
X536559Y1016663D01*
Y1013663D01*
X539559Y1015163D01*
G37*
G36*
G01X523309Y1106727D02*
X527308D01*
X525309Y1110727D01*
X523309Y1106727D01*
G37*
G36*
G01X554740Y174993D02*
X557568Y177821D01*
X553325Y179236D01*
X554740Y174993D01*
G37*
G36*
G01X552520Y234813D02*
Y250325D01*
X555120D01*
Y234813D01*
X552520D01*
G37*
G36*
G01X550164Y267235D02*
X565676D01*
Y264635D01*
X550164D01*
Y267235D01*
G37*
G36*
G01X544245Y269786D02*
X547073Y272614D01*
X542831Y274029D01*
X544245Y269786D01*
G37*
G36*
G01X550195Y749717D02*
X547195Y748217D01*
Y751217D01*
X550195Y749717D01*
G37*
G36*
G01X544420Y994854D02*
Y990854D01*
X540420Y992854D01*
X544420Y994854D01*
G37*
G36*
G01X556499Y59585D02*
X557719Y62025D01*
X558939Y59585D01*
X556499D01*
G37*
G36*
G01X561655Y123072D02*
X558826Y120243D01*
X563069Y118829D01*
X561655Y123072D01*
G37*
G36*
G01X563576Y142689D02*
X561194Y141498D01*
Y143880D01*
X563576Y142689D01*
G37*
G36*
G01X562972Y870295D02*
X566972Y868295D01*
Y872295D01*
X562972Y870295D01*
G37*
G36*
G01X558186D02*
X563157Y872780D01*
Y867810D01*
X558186Y870295D01*
G37*
G36*
G01X580477Y211197D02*
Y214197D01*
X579177D01*
Y211197D01*
X580477D01*
G37*
G36*
G01X575453Y253801D02*
X574393Y256983D01*
X572271Y254862D01*
X575453Y253801D01*
G37*
G36*
G01X588477Y943789D02*
X587296Y940245D01*
X589658D01*
X588477Y943789D01*
G37*
G36*
G01X592387Y1738583D02*
X586387Y1741583D01*
Y1735583D01*
X592387Y1738583D01*
G37*
G36*
G01X592313Y1784624D02*
X586313Y1787624D01*
Y1781624D01*
X592313Y1784624D01*
G37*
G36*
G01X597317Y70955D02*
X595654Y65964D01*
X592327Y69291D01*
X597317Y70955D01*
G37*
G36*
G01X598277Y195583D02*
Y184087D01*
X595128D01*
Y195583D01*
X598277D01*
G37*
G36*
G01X605905Y1258464D02*
Y1261464D01*
X595425D01*
Y1250984D01*
X598425D01*
Y1258464D01*
X605905D01*
G37*
G36*
G01X625045Y203452D02*
X613549D01*
Y206601D01*
X625045D01*
Y203452D01*
G37*
G36*
G01X624814Y262744D02*
X613318D01*
Y265893D01*
X624814D01*
Y262744D01*
G37*
G36*
G01X620067Y1624402D02*
Y1620402D01*
X624067Y1622402D01*
X620067Y1624402D01*
G37*
G36*
G01X633082Y1728286D02*
X639082Y1725286D01*
Y1731286D01*
X633082Y1728286D01*
G37*
G36*
G01X632710Y1775438D02*
X638710Y1772438D01*
Y1778438D01*
X632710Y1775438D01*
G37*
G36*
G01X640117Y152935D02*
X639056Y156117D01*
X636935Y153996D01*
X640117Y152935D01*
G37*
G36*
G01X640659Y220252D02*
X643659D01*
Y221552D01*
X640659D01*
Y220252D01*
G37*
G36*
G01X652526Y267235D02*
X668038D01*
Y264635D01*
X652526D01*
Y267235D01*
G37*
G36*
G01X647305Y268467D02*
X650133Y271295D01*
X645890Y272710D01*
X647305Y268467D01*
G37*
G36*
G01X637881Y659279D02*
Y657279D01*
X640881Y658279D01*
X637881Y659279D01*
G37*
G36*
G01X658861Y59585D02*
X660081Y62025D01*
X661301Y59585D01*
X658861D01*
G37*
G36*
G01X664210Y124824D02*
X661381Y121996D01*
X665624Y120581D01*
X664210Y124824D01*
G37*
G36*
G01X665938Y142689D02*
X663556Y141498D01*
Y143880D01*
X665938Y142689D01*
G37*
G36*
G01X657104Y174751D02*
X659933Y177579D01*
X655690Y178993D01*
X657104Y174751D01*
G37*
G36*
G01X654882Y234813D02*
Y250325D01*
X657482D01*
Y234813D01*
X654882D01*
G37*
G36*
G01X665966Y573453D02*
Y577453D01*
X661966Y575453D01*
X665966Y573453D01*
G37*
G36*
G01X657530Y687863D02*
X659990D01*
X658698Y685683D01*
X657530Y687863D01*
G37*
G36*
G01X665396Y705408D02*
X663557Y704794D01*
X664170Y706634D01*
X665396Y705408D01*
G37*
G36*
G01X682839Y211197D02*
Y214197D01*
X681539D01*
Y211197D01*
X682839D01*
G37*
G36*
G01X677893Y253881D02*
X676833Y257063D01*
X674711Y254942D01*
X677893Y253881D01*
G37*
G36*
G01X679370Y775575D02*
Y779575D01*
X683370Y777575D01*
X679370Y775575D01*
G37*
G36*
G01X685270Y813326D02*
X684770Y813876D01*
X688905Y818174D01*
X688416Y823604D01*
X684570Y827576D01*
X684820Y828276D01*
X685520Y828376D01*
X688241Y825548D01*
X688133Y826744D01*
X689373Y827744D01*
X690373Y827794D01*
X691323Y828244D01*
X693473D01*
X694023Y827994D01*
X695173Y827144D01*
X695373D01*
X695773Y827544D01*
X696573Y827444D01*
X696923Y827044D01*
Y826508D01*
X698720Y828376D01*
X699420Y828276D01*
X699670Y827576D01*
X696923Y824739D01*
Y823694D01*
X696673Y823394D01*
X696073D01*
X695477Y818027D01*
X695571Y817929D01*
X695623Y817894D01*
G02X696246Y817227I-1089J-1641D01*
G01X699470Y813876D01*
X698970Y813326D01*
X698320Y813376D01*
X696326Y815435D01*
G02X692873Y815194I-1792J818D01*
G01X689173D01*
X689046Y816604D01*
X685920Y813376D01*
X685270Y813326D01*
G37*
G36*
G01X699267Y70334D02*
X697604Y65343D01*
X694277Y68670D01*
X699267Y70334D01*
G37*
G36*
G01X700639Y195583D02*
Y184087D01*
X697490D01*
Y195583D01*
X700639D01*
G37*
G36*
G01X698410Y631276D02*
X695228Y630215D01*
X697349Y628094D01*
X698410Y631276D01*
G37*
G36*
G01X696026Y702212D02*
X693026Y700712D01*
Y703712D01*
X696026Y702212D01*
G37*
G36*
G01X685548Y812944D02*
X698698D01*
Y810644D01*
X685548D01*
Y812944D01*
G37*
G36*
G01X727407Y203452D02*
X715911D01*
Y206601D01*
X727407D01*
Y203452D01*
G37*
G36*
G01X727176Y262744D02*
X715680D01*
Y265893D01*
X727176D01*
Y262744D01*
G37*
G36*
G01X717891Y432059D02*
Y428059D01*
X721891Y430059D01*
X717891Y432059D01*
G37*
G36*
G01X725515Y1453659D02*
X729515Y1451659D01*
X725515Y1449659D01*
Y1453659D01*
G37*
G36*
G01X742363Y154279D02*
X741302Y157461D01*
X739181Y155339D01*
X742363Y154279D01*
G37*
G36*
G01X743021Y220252D02*
X746021D01*
Y221552D01*
X743021D01*
Y220252D01*
G37*
G36*
G01X749676Y268832D02*
X752505Y271660D01*
X748262Y273074D01*
X749676Y268832D01*
G37*
G36*
G01X745722Y737612D02*
Y735152D01*
X743542Y736444D01*
X745722Y737612D01*
G37*
G36*
G01X739298Y1586860D02*
X736470Y1589688D01*
X740712Y1591102D01*
X739298Y1586860D01*
G37*
G36*
G01X757823Y61550D02*
X760411Y62413D01*
X759548Y59825D01*
X757823Y61550D01*
G37*
G36*
G01X764114Y122427D02*
Y118427D01*
X768114Y120427D01*
X764114Y122427D01*
G37*
G36*
G01X768300Y142689D02*
X765918Y141498D01*
Y143880D01*
X768300Y142689D01*
G37*
G36*
G01X758949Y173887D02*
X761777Y176715D01*
X757534Y178129D01*
X758949Y173887D01*
G37*
G36*
G01X757244Y234813D02*
Y250325D01*
X759844D01*
Y234813D01*
X757244D01*
G37*
G36*
G01X754888Y267235D02*
X770400D01*
Y264635D01*
X754888D01*
Y267235D01*
G37*
G36*
G01X753009Y322716D02*
X754744Y321849D01*
X753009Y320982D01*
Y322716D01*
G37*
G36*
G01X754319Y348437D02*
Y346437D01*
X757319Y347437D01*
X754319Y348437D01*
G37*
G36*
G01X757514Y1588839D02*
X755774Y1590579D01*
X758229Y1591207D01*
X757514Y1588839D01*
G37*
G36*
G01X768516Y1640375D02*
X764516D01*
X766516Y1636375D01*
X768516Y1640375D01*
G37*
G36*
G01X780738Y254720D02*
X779678Y257902D01*
X777556Y255780D01*
X780738Y254720D01*
G37*
G36*
G01X783217Y329752D02*
Y327292D01*
X781037Y328584D01*
X783217Y329752D01*
G37*
G36*
G01X777402Y1429617D02*
Y1425617D01*
X773402Y1427617D01*
X777402Y1429617D01*
G37*
G36*
G01X773290Y1595290D02*
X775130Y1595904D01*
X774516Y1594064D01*
X773290Y1595290D01*
G37*
G36*
G01X801647Y70212D02*
X799984Y65221D01*
X796657Y68548D01*
X801647Y70212D01*
G37*
G36*
G01X785201Y211197D02*
Y214197D01*
X783901D01*
Y211197D01*
X785201D01*
G37*
G36*
G01X797147Y1142257D02*
X799147D01*
X798147Y1145257D01*
X797147Y1142257D01*
G37*
G36*
G01X795794Y1149853D02*
X793794Y1145853D01*
X797794D01*
X795794Y1149853D01*
G37*
G36*
G01X803001Y195583D02*
Y184087D01*
X799852D01*
Y195583D01*
X803001D01*
G37*
G36*
G01X812785Y442874D02*
X815614Y440046D01*
X817028Y444288D01*
X812785Y442874D01*
G37*
G36*
G01X811163Y462810D02*
X799667D01*
Y465959D01*
X811163D01*
Y462810D01*
G37*
G36*
G01X803313Y895294D02*
Y891294D01*
X799313Y893294D01*
X803313Y895294D01*
G37*
G36*
G01X804527Y945808D02*
Y941808D01*
X800527Y943808D01*
X804527Y945808D01*
G37*
G36*
G01X812890Y1403368D02*
X815350D01*
X814058Y1401188D01*
X812890Y1403368D01*
G37*
G36*
G01X829769Y203452D02*
X818273D01*
Y206601D01*
X829769D01*
Y203452D01*
G37*
G36*
G01X829538Y262744D02*
X818042D01*
Y265893D01*
X829538D01*
Y262744D01*
G37*
G36*
G01X825777Y339836D02*
Y335836D01*
X829777Y337836D01*
X825777Y339836D01*
G37*
G36*
G01X824218Y478629D02*
X827218D01*
Y479929D01*
X824218D01*
Y478629D01*
G37*
G36*
G01X834279Y767474D02*
X831097Y768535D01*
X833219Y770656D01*
X834279Y767474D01*
G37*
G36*
G01X834091Y785624D02*
X830909Y786684D01*
X833031Y788806D01*
X834091Y785624D01*
G37*
G36*
G01X834171Y803374D02*
X830989Y804434D01*
X833110Y806556D01*
X834171Y803374D01*
G37*
G36*
G01X834220Y821197D02*
X831038Y822258D01*
X833160Y824379D01*
X834220Y821197D01*
G37*
G36*
G01X834071Y864966D02*
X830071D01*
X832071Y860966D01*
X834071Y864966D01*
G37*
G36*
G01X821975Y864884D02*
X817975D01*
X819975Y860884D01*
X821975Y864884D01*
G37*
G36*
G01X825804Y872452D02*
X827804D01*
X826804Y875452D01*
X825804Y872452D01*
G37*
G36*
G01X824379Y889822D02*
X822964Y891236D01*
X821550Y888408D01*
X824379Y889822D01*
G37*
G36*
G01X826213Y935571D02*
X828653Y934351D01*
X826213Y933131D01*
Y935571D01*
G37*
G36*
G01X819111Y1169105D02*
X817891Y1166665D01*
X816671Y1169105D01*
X819111D01*
G37*
G36*
G01X819289D02*
X818069Y1166665D01*
X816849Y1169105D01*
X819289D01*
G37*
G36*
G01X825110Y1464512D02*
X822282Y1467341D01*
X820867Y1463098D01*
X825110Y1464512D01*
G37*
G36*
G01X845383Y220252D02*
X848383D01*
Y221552D01*
X845383D01*
Y220252D01*
G37*
G36*
G01X837710Y737844D02*
X840710Y739344D01*
Y736344D01*
X837710Y737844D01*
G37*
G36*
G01X863585Y59585D02*
X864805Y62025D01*
X866025Y59585D01*
X863585D01*
G37*
G36*
G01X860801Y173096D02*
X863630Y175924D01*
X859387Y177338D01*
X860801Y173096D01*
G37*
G36*
G01X859606Y234813D02*
Y250325D01*
X862206D01*
Y234813D01*
X859606D01*
G37*
G36*
G01X857250Y267235D02*
X872762D01*
Y264635D01*
X857250D01*
Y267235D01*
G37*
G36*
G01X852272Y268598D02*
X855101Y271426D01*
X850858Y272840D01*
X852272Y268598D01*
G37*
G36*
G01X858722Y392467D02*
X857298Y395314D01*
X855875Y392467D01*
X858722D01*
G37*
G36*
G01X852445Y691802D02*
Y694262D01*
X854625Y692970D01*
X852445Y691802D01*
G37*
G36*
G01X853276Y736126D02*
X856276Y737626D01*
Y734626D01*
X853276Y736126D01*
G37*
G36*
G01X869010Y426545D02*
Y438041D01*
X872159D01*
Y426545D01*
X869010D01*
G37*
G36*
G01X872003Y488505D02*
X870942Y491687D01*
X868821Y489565D01*
X872003Y488505D01*
G37*
G36*
G01X866411Y716596D02*
X868146Y715729D01*
X866411Y714862D01*
Y716596D01*
G37*
G36*
G01X865080Y729401D02*
X866819Y731140D01*
X867447Y728685D01*
X865080Y729401D01*
G37*
G36*
G01X880028Y779287D02*
X882028Y783287D01*
X878028D01*
X880028Y779287D01*
G37*
G36*
G01X876591Y1440065D02*
X879419Y1442893D01*
X875177Y1444308D01*
X876591Y1440065D01*
G37*
G36*
G01X879184Y1738286D02*
X873184Y1741286D01*
Y1735286D01*
X879184Y1738286D01*
G37*
G36*
G01X878762Y1785438D02*
X872762Y1788438D01*
Y1782438D01*
X878762Y1785438D01*
G37*
G36*
G01X892732Y154948D02*
X891672Y158130D01*
X889550Y156008D01*
X892732Y154948D01*
G37*
G36*
G01X885810Y410931D02*
Y407931D01*
X887110D01*
Y410931D01*
X885810D01*
G37*
G36*
G01X891549Y445501D02*
X880053D01*
Y448650D01*
X891549D01*
Y445501D01*
G37*
G36*
G01X881841Y560859D02*
X884670Y558031D01*
X886084Y562274D01*
X881841Y560859D01*
G37*
G36*
G01X885332Y699452D02*
X882118Y700523D01*
X884260Y702665D01*
X885332Y699452D01*
G37*
G36*
G01X880571Y947467D02*
Y949927D01*
X882751Y948635D01*
X880571Y947467D01*
G37*
G36*
G01X890320Y1204510D02*
X891540Y1206950D01*
X892760Y1204510D01*
X890320D01*
G37*
G36*
G01X895533Y1206144D02*
Y1210144D01*
X891533Y1208144D01*
X895533Y1206144D01*
G37*
G36*
G01X910711Y315248D02*
X909580Y316380D01*
X909014Y314683D01*
X910711Y315248D01*
G37*
G36*
G01X911426Y351902D02*
X914380Y352888D01*
X913395Y349933D01*
X911426Y351902D01*
G37*
G36*
G01X900371Y392708D02*
X915883D01*
Y390108D01*
X900371D01*
Y392708D01*
G37*
G36*
G01X904543Y1085375D02*
X908543D01*
X906543Y1089375D01*
X904543Y1085375D01*
G37*
G36*
G01X917523Y124562D02*
X914695Y121734D01*
X918938Y120319D01*
X917523Y124562D01*
G37*
G36*
G01X918300Y142689D02*
X915918Y141498D01*
Y143880D01*
X918300Y142689D01*
G37*
G36*
G01X926446Y448568D02*
X929799Y450244D01*
Y446892D01*
X926446Y448568D01*
G37*
G36*
G01X925561Y547717D02*
X927973Y545305D01*
X924355Y544099D01*
X925561Y547717D01*
G37*
G36*
G01X932203Y840568D02*
Y832253D01*
X923888D01*
Y835253D01*
X929203D01*
Y840568D01*
X932203D01*
G37*
G36*
G01X918347Y1438073D02*
X921175Y1440901D01*
X916933Y1442316D01*
X918347Y1438073D01*
G37*
G36*
G01X920278Y1728990D02*
X926278Y1725990D01*
Y1731990D01*
X920278Y1728990D01*
G37*
G36*
G01X920072Y1776014D02*
X926072Y1773014D01*
Y1779014D01*
X920072Y1776014D01*
G37*
G36*
G01X935867Y196368D02*
Y199368D01*
X934567D01*
Y196368D01*
X935867D01*
G37*
G36*
G01X933860Y229496D02*
Y233496D01*
X929860Y231496D01*
X933860Y229496D01*
G37*
G36*
G01X939985Y241146D02*
X938485Y238146D01*
X941485D01*
X939985Y241146D01*
G37*
G36*
G01X928797Y422969D02*
Y438481D01*
X931397D01*
Y422969D01*
X928797D01*
G37*
G36*
G01X938847Y518429D02*
Y514429D01*
X934847Y516429D01*
X938847Y518429D01*
G37*
G36*
G01X931504Y702740D02*
X933964D01*
X932672Y700560D01*
X931504Y702740D01*
G37*
G36*
G01X940269Y704502D02*
X937809D01*
X939101Y706682D01*
X940269Y704502D01*
G37*
G36*
G01X933613Y1437465D02*
X931963Y1433365D01*
X935113D01*
X933613Y1437465D01*
G37*
G36*
G01X952364Y70654D02*
X950701Y65663D01*
X947374Y68990D01*
X952364Y70654D01*
G37*
G36*
G01X953667Y180754D02*
Y169258D01*
X950518D01*
Y180754D01*
X953667D01*
G37*
G36*
G01X946452Y353466D02*
X950452D01*
X948452Y357466D01*
X946452Y353466D01*
G37*
G36*
G01X952131Y518777D02*
Y503265D01*
X949531D01*
Y518777D01*
X952131D01*
G37*
G36*
G01X960595Y726660D02*
X963055D01*
X961763Y724480D01*
X960595Y726660D01*
G37*
G36*
G01X948064Y804123D02*
X950892Y801294D01*
X946650Y799880D01*
X948064Y804123D01*
G37*
G36*
G01X964746Y974639D02*
X960746D01*
X962746Y970639D01*
X964746Y974639D01*
G37*
G36*
G01X954677Y1204404D02*
X955897Y1206844D01*
X957117Y1204404D01*
X954677D01*
G37*
G36*
G01X959510Y1206144D02*
Y1210144D01*
X955510Y1208144D01*
X959510Y1206144D01*
G37*
G36*
G01X949468Y1369717D02*
Y1365717D01*
X953468Y1367717D01*
X949468Y1369717D01*
G37*
G36*
G01X960268Y1437657D02*
X958618Y1433557D01*
X961768D01*
X960268Y1437657D01*
G37*
G36*
G01X979769Y203452D02*
X968273D01*
Y206601D01*
X979769D01*
Y203452D01*
G37*
G36*
G01X979538Y262744D02*
X968042D01*
Y265893D01*
X979538D01*
Y262744D01*
G37*
G36*
G01X965025Y462453D02*
X968207Y463514D01*
X966086Y465635D01*
X965025Y462453D01*
G37*
G36*
G01X970259Y462415D02*
X967430Y459587D01*
X971673Y458173D01*
X970259Y462415D01*
G37*
G36*
G01X976185Y486594D02*
X973185D01*
Y485294D01*
X976185D01*
Y486594D01*
G37*
G36*
G01X966354Y533338D02*
X963354D01*
Y532038D01*
X966354D01*
Y533338D01*
G37*
G36*
G01X970306Y591861D02*
Y580365D01*
X967157D01*
Y591861D01*
X970306D01*
G37*
G36*
G01X972963Y626099D02*
X974149Y629655D01*
X976519Y627285D01*
X972963Y626099D01*
G37*
G36*
G01X967915Y1084564D02*
X971915D01*
X969915Y1088564D01*
X967915Y1084564D01*
G37*
G36*
G01X994661Y154305D02*
X993600Y157487D01*
X991479Y155365D01*
X994661Y154305D01*
G37*
G36*
G01X990750Y306679D02*
X988338Y304267D01*
X987133Y307886D01*
X990750Y306679D01*
G37*
G36*
G01X991799Y504394D02*
X1003295D01*
Y501245D01*
X991799D01*
Y504394D01*
G37*
G36*
G01X981968Y550138D02*
X993464D01*
Y546989D01*
X981968D01*
Y550138D01*
G37*
G36*
G01X995894Y595624D02*
X993065Y598452D01*
X991651Y594210D01*
X995894Y595624D01*
G37*
G36*
G01X982109Y612215D02*
X997621D01*
Y609615D01*
X982109D01*
Y612215D01*
G37*
G36*
G01X991635Y775465D02*
X989175D01*
X990467Y777645D01*
X991635Y775465D01*
G37*
G36*
G01X996645Y1015163D02*
X993645Y1016663D01*
Y1013663D01*
X996645Y1015163D01*
G37*
G36*
G01X983396Y1437408D02*
X981746Y1433308D01*
X984896D01*
X983396Y1437408D01*
G37*
G36*
G01X995383Y220252D02*
X998383D01*
Y221552D01*
X995383D01*
Y220252D01*
G37*
G36*
G01X1009606Y234813D02*
Y250325D01*
X1012206D01*
Y234813D01*
X1009606D01*
G37*
G36*
G01X1007250Y267235D02*
X1022762D01*
Y264635D01*
X1007250D01*
Y267235D01*
G37*
G36*
G01X1001794Y265564D02*
X1004622Y268393D01*
X1000379Y269807D01*
X1001794Y265564D01*
G37*
G36*
G01X1001050Y346710D02*
Y342710D01*
X1005050Y344710D01*
X1001050Y346710D01*
G37*
G36*
G01D02*
Y342710D01*
X1005050Y344710D01*
X1001050Y346710D01*
G37*
G36*
G01X1012743Y717383D02*
Y713383D01*
X1008743Y715383D01*
X1012743Y717383D01*
G37*
G36*
G01X995344Y849104D02*
X996525Y852648D01*
X994163D01*
X995344Y849104D01*
G37*
G36*
G01X1006366Y1441667D02*
X1004716Y1437567D01*
X1007866D01*
X1006366Y1441667D01*
G37*
G36*
G01X1010869Y61040D02*
X1013457Y61902D01*
X1012594Y59314D01*
X1010869Y61040D01*
G37*
G36*
G01X1019916Y122812D02*
X1017088Y119984D01*
X1021330Y118570D01*
X1019916Y122812D01*
G37*
G36*
G01X1020662Y142689D02*
X1018280Y141498D01*
Y143880D01*
X1020662Y142689D01*
G37*
G36*
G01X1011878Y173415D02*
X1014706Y176244D01*
X1010463Y177658D01*
X1011878Y173415D01*
G37*
G36*
G01X1019731Y870295D02*
X1023731Y868295D01*
Y872295D01*
X1019731Y870295D01*
G37*
G36*
G01X1015575D02*
X1020546Y872780D01*
Y867810D01*
X1015575Y870295D01*
G37*
G36*
G01X1025010Y1325092D02*
Y1321092D01*
X1029010Y1323092D01*
X1025010Y1325092D01*
G37*
G36*
G01X1021862Y1388523D02*
X1025862D01*
X1023862Y1392523D01*
X1021862Y1388523D01*
G37*
G36*
G01X1037563Y211197D02*
Y214197D01*
X1036263D01*
Y211197D01*
X1037563D01*
G37*
G36*
G01X1032218Y254266D02*
X1031157Y257448D01*
X1029036Y255326D01*
X1032218Y254266D01*
G37*
G36*
G01X1028167Y835371D02*
X1033197D01*
X1030682Y830342D01*
X1028167Y835371D01*
G37*
G36*
G01X1029369Y940781D02*
X1032913Y939600D01*
Y941962D01*
X1029369Y940781D01*
G37*
G36*
G01X1045526Y1346460D02*
Y1342460D01*
X1041526Y1344460D01*
X1045526Y1346460D01*
G37*
G36*
G01X1029252Y1441783D02*
X1027602Y1437683D01*
X1030752D01*
X1029252Y1441783D01*
G37*
G36*
G01X1054413Y71221D02*
X1052750Y66230D01*
X1049423Y69557D01*
X1054413Y71221D01*
G37*
G36*
G01X1055363Y195583D02*
Y184087D01*
X1052214D01*
Y195583D01*
X1055363D01*
G37*
G36*
G01X1062991Y1258464D02*
Y1261464D01*
X1052511D01*
Y1250984D01*
X1055511D01*
Y1258464D01*
X1062991D01*
G37*
G36*
G01X1082131Y203452D02*
X1070635D01*
Y206601D01*
X1082131D01*
Y203452D01*
G37*
G36*
G01X1081900Y262744D02*
X1070404D01*
Y265893D01*
X1081900D01*
Y262744D01*
G37*
G36*
G01X1068216Y1620787D02*
Y1624787D01*
X1064216Y1622787D01*
X1068216Y1620787D01*
G37*
G36*
G01X1089398Y1524798D02*
Y1527798D01*
X1088098D01*
Y1524798D01*
X1089398D01*
G37*
G36*
G01X1097063Y153156D02*
X1096002Y156338D01*
X1093881Y154216D01*
X1097063Y153156D01*
G37*
G36*
G01X1097745Y220252D02*
X1100745D01*
Y221552D01*
X1097745D01*
Y220252D01*
G37*
G36*
G01X1104000Y270058D02*
X1106828Y272886D01*
X1102586Y274301D01*
X1104000Y270058D01*
G37*
G36*
G01X1094968Y659279D02*
Y657279D01*
X1097968Y658279D01*
X1094968Y659279D01*
G37*
G36*
G01X1093705Y1563170D02*
X1095205Y1560170D01*
X1092205D01*
X1093705Y1563170D01*
G37*
G36*
G01X1098846Y1624904D02*
X1100846Y1628904D01*
X1096846D01*
X1098846Y1624904D01*
G37*
G36*
G01X1115596Y59655D02*
X1116816Y62095D01*
X1118036Y59655D01*
X1115596D01*
G37*
G36*
G01X1121061Y123577D02*
X1118233Y120748D01*
X1122476Y119334D01*
X1121061Y123577D01*
G37*
G36*
G01X1123024Y142689D02*
X1120642Y141498D01*
Y143880D01*
X1123024Y142689D01*
G37*
G36*
G01X1113080Y171868D02*
X1115909Y174696D01*
X1111666Y176110D01*
X1113080Y171868D01*
G37*
G36*
G01X1111968Y234813D02*
Y250325D01*
X1114568D01*
Y234813D01*
X1111968D01*
G37*
G36*
G01X1109612Y267235D02*
X1125124D01*
Y264635D01*
X1109612D01*
Y267235D01*
G37*
G36*
G01X1123053Y573453D02*
Y577453D01*
X1119053Y575453D01*
X1123053Y573453D01*
G37*
G36*
G01X1114617Y687863D02*
X1117077D01*
X1115785Y685683D01*
X1114617Y687863D01*
G37*
G36*
G01X1122013Y705253D02*
X1120173Y704639D01*
X1120787Y706479D01*
X1122013Y705253D01*
G37*
G36*
G01X1122350Y1624402D02*
Y1620402D01*
X1126350Y1622402D01*
X1122350Y1624402D01*
G37*
G36*
G01X1139925Y211197D02*
Y214197D01*
X1138625D01*
Y211197D01*
X1139925D01*
G37*
G36*
G01X1135022Y254891D02*
X1133961Y258073D01*
X1131840Y255952D01*
X1135022Y254891D01*
G37*
G36*
G01X1155961Y71210D02*
X1154298Y66219D01*
X1150971Y69546D01*
X1155961Y71210D01*
G37*
G36*
G01X1157725Y195583D02*
Y184087D01*
X1154576D01*
Y195583D01*
X1157725D01*
G37*
G36*
G01X1144347Y338866D02*
X1141347Y337366D01*
Y340366D01*
X1144347Y338866D01*
G37*
G36*
G01X1155734Y631277D02*
X1152552Y630216D01*
X1154673Y628095D01*
X1155734Y631277D01*
G37*
G36*
G01X1171923Y816118D02*
X1175923D01*
X1173923Y812118D01*
X1171923Y816118D01*
G37*
G36*
G01X1166330Y1738990D02*
X1160330Y1741990D01*
Y1735990D01*
X1166330Y1738990D01*
G37*
G36*
G01X1166124Y1786014D02*
X1160124Y1789014D01*
Y1783014D01*
X1166124Y1786014D01*
G37*
G36*
G01X1184493Y203452D02*
X1172997D01*
Y206601D01*
X1184493D01*
Y203452D01*
G37*
G36*
G01X1184262Y262744D02*
X1172766D01*
Y265893D01*
X1184262D01*
Y262744D01*
G37*
G36*
G01X1174978Y432059D02*
Y428059D01*
X1178978Y430059D01*
X1174978Y432059D01*
G37*
G36*
G01X1199601Y153214D02*
X1198540Y156396D01*
X1196419Y154275D01*
X1199601Y153214D01*
G37*
G36*
G01X1200107Y220252D02*
X1203107D01*
Y221552D01*
X1200107D01*
Y220252D01*
G37*
G36*
G01X1218309Y59585D02*
X1219529Y62025D01*
X1220749Y59585D01*
X1218309D01*
G37*
G36*
G01X1216597Y173804D02*
X1219426Y176633D01*
X1215183Y178047D01*
X1216597Y173804D01*
G37*
G36*
G01X1214330Y234813D02*
Y250325D01*
X1216930D01*
Y234813D01*
X1214330D01*
G37*
G36*
G01X1211974Y267235D02*
X1227486D01*
Y264635D01*
X1211974D01*
Y267235D01*
G37*
G36*
G01X1206534Y268911D02*
X1209362Y271739D01*
X1205119Y273153D01*
X1206534Y268911D01*
G37*
G36*
G01X1210096Y322716D02*
X1211831Y321849D01*
X1210096Y320982D01*
Y322716D01*
G37*
G36*
G01X1211406Y348437D02*
Y346437D01*
X1214406Y347437D01*
X1211406Y348437D01*
G37*
G36*
G01X1224392Y122644D02*
X1221563Y119815D01*
X1225806Y118401D01*
X1224392Y122644D01*
G37*
G36*
G01X1225386Y142689D02*
X1223004Y141498D01*
Y143880D01*
X1225386Y142689D01*
G37*
G36*
G01X1242287Y211197D02*
Y214197D01*
X1240987D01*
Y211197D01*
X1242287D01*
G37*
G36*
G01X1239348Y255368D02*
X1240848Y258368D01*
X1237848D01*
X1239348Y255368D01*
G37*
G36*
G01X1240304Y329752D02*
Y327292D01*
X1238124Y328584D01*
X1240304Y329752D01*
G37*
G36*
G01X1252880Y1149853D02*
X1250880Y1145853D01*
X1254880D01*
X1252880Y1149853D01*
G37*
G36*
G01X1259071Y70858D02*
X1257408Y65867D01*
X1254081Y69194D01*
X1259071Y70858D01*
G37*
G36*
G01X1260087Y195583D02*
Y184087D01*
X1256938D01*
Y195583D01*
X1260087D01*
G37*
G36*
G01X1264685Y386776D02*
X1267513Y383947D01*
X1268927Y388190D01*
X1264685Y386776D01*
G37*
G36*
G01X1268168Y447522D02*
X1270996Y444694D01*
X1272410Y448936D01*
X1268168Y447522D01*
G37*
G36*
G01X1266017Y909426D02*
X1263017Y910926D01*
Y907926D01*
X1266017Y909426D01*
G37*
G36*
G01X1286855Y203452D02*
X1275359D01*
Y206601D01*
X1286855D01*
Y203452D01*
G37*
G36*
G01X1286624Y262744D02*
X1275128D01*
Y265893D01*
X1286624D01*
Y262744D01*
G37*
G36*
G01X1281305Y483629D02*
X1284305D01*
Y484929D01*
X1281305D01*
Y483629D01*
G37*
G36*
G01X1281707Y901055D02*
X1283122Y899641D01*
X1284536Y902470D01*
X1281707Y901055D01*
G37*
G36*
G01X1276375Y1169105D02*
X1275155Y1166665D01*
X1273935Y1169105D01*
X1276375D01*
G37*
G36*
G01X1301857Y35242D02*
X1304297Y34022D01*
X1301857Y32802D01*
Y35242D01*
G37*
G36*
G01X1290557Y326581D02*
X1288117Y327801D01*
X1290557Y329021D01*
Y326581D01*
G37*
G36*
G01X1293494Y782053D02*
X1290665Y779225D01*
X1294908Y777811D01*
X1293494Y782053D01*
G37*
G36*
G01X1304544Y798041D02*
X1301716Y795212D01*
X1300302Y799455D01*
X1304544Y798041D01*
G37*
G36*
G01X1289550Y928750D02*
X1288050Y925750D01*
X1291050D01*
X1289550Y928750D01*
G37*
G36*
G01X1295579Y1624402D02*
Y1620402D01*
X1299579Y1622402D01*
X1295579Y1624402D01*
G37*
G36*
G01X1318790Y174023D02*
X1321618Y176852D01*
X1317376Y178266D01*
X1318790Y174023D01*
G37*
G36*
G01X1302469Y220252D02*
X1305469D01*
Y221552D01*
X1302469D01*
Y220252D01*
G37*
G36*
G01X1316692Y234813D02*
Y250325D01*
X1319292D01*
Y234813D01*
X1316692D01*
G37*
G36*
G01X1314336Y267235D02*
X1329848D01*
Y264635D01*
X1314336D01*
Y267235D01*
G37*
G36*
G01X1309213Y268293D02*
X1312041Y271122D01*
X1307798Y272536D01*
X1309213Y268293D01*
G37*
G36*
G01X1312682Y349721D02*
Y352750D01*
X1315711Y351235D01*
X1312682Y349721D01*
G37*
G36*
G01X1304657Y397590D02*
Y394590D01*
X1305957D01*
Y397590D01*
X1304657D01*
G37*
G36*
G01X1310999Y901918D02*
X1318480D01*
Y904918D01*
X1307999D01*
Y894437D01*
X1310999D01*
Y901918D01*
G37*
G36*
G01X1315441Y944300D02*
X1316941Y941300D01*
X1313941D01*
X1315441Y944300D01*
G37*
G36*
G01X1306466Y959861D02*
X1304966Y962861D01*
X1307966D01*
X1306466Y959861D01*
G37*
G36*
G01X1310371Y1011634D02*
Y1007634D01*
X1306371Y1009634D01*
X1310371Y1011634D01*
G37*
G36*
G01X1322674Y476777D02*
X1321613Y479959D01*
X1319492Y477838D01*
X1322674Y476777D01*
G37*
G36*
G01X1332059Y959700D02*
X1330559Y962700D01*
X1333559D01*
X1332059Y959700D01*
G37*
G36*
G01X1349506Y153121D02*
X1348445Y156303D01*
X1346324Y154182D01*
X1349506Y153121D01*
G37*
G36*
G01X1347236Y433234D02*
X1350792Y432048D01*
X1348422Y429678D01*
X1347236Y433234D01*
G37*
G36*
G01X1343800Y591968D02*
Y587968D01*
X1347800Y589968D01*
X1343800Y591968D01*
G37*
G36*
G01Y638468D02*
Y634468D01*
X1347800Y636468D01*
X1343800Y638468D01*
G37*
G36*
G01Y682968D02*
Y678968D01*
X1347800Y680968D01*
X1343800Y682968D01*
G37*
G36*
G01Y729968D02*
Y725968D01*
X1347800Y727968D01*
X1343800Y729968D01*
G37*
G36*
G01X1346789Y1103950D02*
X1349618Y1106779D01*
X1345375Y1108193D01*
X1346789Y1103950D01*
G37*
G36*
G01X1374718Y122597D02*
X1371890Y119768D01*
X1376132Y118354D01*
X1374718Y122597D01*
G37*
G36*
G01X1375387Y142689D02*
X1373005Y141498D01*
Y143880D01*
X1375387Y142689D01*
G37*
G36*
G01X1382582Y1005803D02*
X1383730Y1003507D01*
X1381434D01*
X1382582Y1005803D01*
G37*
G36*
G01X1378867Y1104496D02*
X1381696Y1107325D01*
X1377453Y1108739D01*
X1378867Y1104496D01*
G37*
G36*
G01X1392288Y211197D02*
Y214197D01*
X1390988D01*
Y211197D01*
X1392288D01*
G37*
G36*
G01X1387669Y253411D02*
X1386608Y256593D01*
X1384487Y254472D01*
X1387669Y253411D01*
G37*
G36*
G01X1396486Y356587D02*
Y352587D01*
X1400486Y354587D01*
X1396486Y356587D01*
G37*
G36*
G01X1408669Y71059D02*
X1407006Y66068D01*
X1403679Y69395D01*
X1408669Y71059D01*
G37*
G36*
G01X1410088Y195583D02*
Y184087D01*
X1406939D01*
Y195583D01*
X1410088D01*
G37*
G36*
G01X1409218Y518777D02*
Y503265D01*
X1406618D01*
Y518777D01*
X1409218D01*
G37*
G36*
G01X1415582Y976473D02*
Y972473D01*
X1411582Y974473D01*
X1415582Y976473D01*
G37*
G36*
G01X1412812Y1103861D02*
X1415640Y1106690D01*
X1411398Y1108104D01*
X1412812Y1103861D01*
G37*
G36*
G01X1436856Y203452D02*
X1425360D01*
Y206601D01*
X1436856D01*
Y203452D01*
G37*
G36*
G01X1436625Y262744D02*
X1425129D01*
Y265893D01*
X1436625D01*
Y262744D01*
G37*
G36*
G01X1425270Y458230D02*
X1422441Y455402D01*
X1426684Y453988D01*
X1425270Y458230D01*
G37*
G36*
G01X1420121Y459545D02*
X1423303Y460606D01*
X1421182Y462727D01*
X1420121Y459545D01*
G37*
G36*
G01X1433272Y486594D02*
X1430272D01*
Y485294D01*
X1433272D01*
Y486594D01*
G37*
G36*
G01X1423441Y533338D02*
X1420441D01*
Y532038D01*
X1423441D01*
Y533338D01*
G37*
G36*
G01X1427393Y591861D02*
Y580365D01*
X1424244D01*
Y591861D01*
X1427393D01*
G37*
G36*
G01X1428758Y628414D02*
X1427082Y631767D01*
X1430434D01*
X1428758Y628414D01*
G37*
G36*
G01X1434453Y948544D02*
X1433039Y952787D01*
X1430211Y949958D01*
X1434453Y948544D01*
G37*
G36*
G01X1432496Y1517620D02*
X1433996Y1520620D01*
X1430996D01*
X1432496Y1517620D01*
G37*
G36*
G01X1430661Y1537435D02*
X1433661Y1535935D01*
Y1538935D01*
X1430661Y1537435D01*
G37*
G36*
G01X1430288Y1558075D02*
X1433288Y1556575D01*
Y1559575D01*
X1430288Y1558075D01*
G37*
G36*
G01X1439055Y550138D02*
X1450551D01*
Y546989D01*
X1439055D01*
Y550138D01*
G37*
G36*
G01X1439196Y612215D02*
X1454708D01*
Y609615D01*
X1439196D01*
Y612215D01*
G37*
G36*
G01X1434800Y714468D02*
Y710468D01*
X1438800Y712468D01*
X1434800Y714468D01*
G37*
G36*
G01Y758468D02*
Y754468D01*
X1438800Y756468D01*
X1434800Y758468D01*
G37*
G36*
G01X1437310Y1008350D02*
X1439310D01*
X1438310Y1011350D01*
X1437310Y1008350D01*
G37*
G36*
G01X1446798Y1107037D02*
X1449627Y1109865D01*
X1445384Y1111279D01*
X1446798Y1107037D01*
G37*
G36*
G01X1457394Y37313D02*
X1454565Y34484D01*
X1458808Y33070D01*
X1457394Y37313D01*
G37*
G36*
G01X1451968Y153554D02*
X1450907Y156736D01*
X1448786Y154615D01*
X1451968Y153554D01*
G37*
G36*
G01X1452470Y220252D02*
X1455470D01*
Y221552D01*
X1452470D01*
Y220252D01*
G37*
G36*
G01X1464337Y267235D02*
X1479849D01*
Y264635D01*
X1464337D01*
Y267235D01*
G37*
G36*
G01X1459143Y264476D02*
X1461972Y267305D01*
X1457729Y268719D01*
X1459143Y264476D01*
G37*
G36*
G01X1448886Y504394D02*
X1460382D01*
Y501245D01*
X1448886D01*
Y504394D01*
G37*
G36*
G01X1453037Y595463D02*
X1450209Y598291D01*
X1448795Y594049D01*
X1453037Y595463D01*
G37*
G36*
G01X1451800Y799968D02*
Y795968D01*
X1455800Y797968D01*
X1451800Y799968D01*
G37*
G36*
G01Y843968D02*
Y839968D01*
X1455800Y841968D01*
X1451800Y843968D01*
G37*
G36*
G01X1453222Y988075D02*
Y984075D01*
X1449222Y986075D01*
X1453222Y988075D01*
G37*
G36*
G01X1453732Y1015163D02*
X1450732Y1016663D01*
Y1013663D01*
X1453732Y1015163D01*
G37*
G36*
G01X1470672Y59585D02*
X1471892Y62025D01*
X1473112Y59585D01*
X1470672D01*
G37*
G36*
G01X1476547Y122497D02*
X1473719Y119669D01*
X1477962Y118255D01*
X1476547Y122497D01*
G37*
G36*
G01X1477749Y142689D02*
X1475367Y141498D01*
Y143880D01*
X1477749Y142689D01*
G37*
G36*
G01X1468912Y174270D02*
X1471740Y177098D01*
X1467498Y178513D01*
X1468912Y174270D01*
G37*
G36*
G01X1466693Y234813D02*
Y250325D01*
X1469293D01*
Y234813D01*
X1466693D01*
G37*
G36*
G01X1477145Y870295D02*
X1481145Y868295D01*
Y872295D01*
X1477145Y870295D01*
G37*
G36*
G01X1472359D02*
X1477330Y872780D01*
Y867810D01*
X1472359Y870295D01*
G37*
G36*
G01X1468807Y1624402D02*
Y1620402D01*
X1472807Y1622402D01*
X1468807Y1624402D01*
G37*
G36*
G01X1494650Y211197D02*
Y214197D01*
X1493350D01*
Y211197D01*
X1494650D01*
G37*
G36*
G01X1489909Y254461D02*
X1488849Y257643D01*
X1486727Y255521D01*
X1489909Y254461D01*
G37*
G36*
G01X1493477Y917423D02*
Y913423D01*
X1497477Y915423D01*
X1493477Y917423D01*
G37*
G36*
G01X1511780Y71416D02*
X1510117Y66425D01*
X1506790Y69752D01*
X1511780Y71416D01*
G37*
G36*
G01X1512450Y195583D02*
Y184087D01*
X1509301D01*
Y195583D01*
X1512450D01*
G37*
G36*
G01X1498581Y353916D02*
Y349916D01*
X1502581Y351916D01*
X1498581Y353916D01*
G37*
G36*
G01X1502834Y884729D02*
X1500534Y880429D01*
X1504734D01*
X1502834Y884729D01*
G37*
G36*
G01X1520078Y1258464D02*
Y1261464D01*
X1509598D01*
Y1250984D01*
X1512598D01*
Y1258464D01*
X1520078D01*
G37*
G36*
G01X1539218Y203452D02*
X1527722D01*
Y206601D01*
X1539218D01*
Y203452D01*
G37*
G36*
G01X1538987Y262744D02*
X1527491D01*
Y265893D01*
X1538987D01*
Y262744D01*
G37*
G36*
G01X1554072Y154098D02*
X1553011Y157280D01*
X1550890Y155159D01*
X1554072Y154098D01*
G37*
G36*
G01X1554832Y220252D02*
X1557832D01*
Y221552D01*
X1554832D01*
Y220252D01*
G37*
G36*
G01X1562746Y263033D02*
X1565575Y265861D01*
X1561332Y267275D01*
X1562746Y263033D01*
G37*
G36*
G01X1552055Y659279D02*
Y657279D01*
X1555055Y658279D01*
X1552055Y659279D01*
G37*
G36*
G01X1573034Y59585D02*
X1574254Y62025D01*
X1575474Y59585D01*
X1573034D01*
G37*
G36*
G01X1579200Y122570D02*
X1576372Y119742D01*
X1580614Y118328D01*
X1579200Y122570D01*
G37*
G36*
G01X1580111Y142689D02*
X1577729Y141498D01*
Y143880D01*
X1580111Y142689D01*
G37*
G36*
G01X1571228Y174362D02*
X1574056Y177190D01*
X1569814Y178604D01*
X1571228Y174362D01*
G37*
G36*
G01X1569055Y234813D02*
Y250325D01*
X1571655D01*
Y234813D01*
X1569055D01*
G37*
G36*
G01X1566699Y267235D02*
X1582211D01*
Y264635D01*
X1566699D01*
Y267235D01*
G37*
G36*
G01X1580140Y573453D02*
Y577453D01*
X1576140Y575453D01*
X1580140Y573453D01*
G37*
G36*
G01X1571704Y687863D02*
X1574164D01*
X1572872Y685683D01*
X1571704Y687863D01*
G37*
G36*
G01X1579697Y701232D02*
X1577962Y702099D01*
X1579697Y702966D01*
Y701232D01*
G37*
G36*
G01X1575314Y992400D02*
Y988400D01*
X1571314Y990400D01*
X1575314Y992400D01*
G37*
G36*
G01X1592168Y253752D02*
X1591108Y256934D01*
X1588986Y254813D01*
X1592168Y253752D01*
G37*
G36*
G01X1596328Y928608D02*
Y924608D01*
X1592328Y926608D01*
X1596328Y928608D01*
G37*
G36*
G01X1589668Y1476002D02*
X1592256Y1476864D01*
X1591393Y1474276D01*
X1589668Y1476002D01*
G37*
G36*
G01X1612775Y71263D02*
X1611111Y66273D01*
X1607785Y69600D01*
X1612775Y71263D01*
G37*
G36*
G01X1597012Y211197D02*
Y214197D01*
X1595712D01*
Y211197D01*
X1597012D01*
G37*
G36*
G01X1604700Y334235D02*
X1602260Y335455D01*
X1604700Y336675D01*
Y334235D01*
G37*
G36*
G01X1612788Y631298D02*
X1609606Y630237D01*
X1611727Y628116D01*
X1612788Y631298D01*
G37*
G36*
G01X1606081Y1463688D02*
X1609081Y1462188D01*
Y1465188D01*
X1606081Y1463688D01*
G37*
G36*
G01X1614812Y195583D02*
Y184087D01*
X1611663D01*
Y195583D01*
X1614812D01*
G37*
G36*
G01X1624948Y705833D02*
X1621948Y707333D01*
Y704333D01*
X1624948Y705833D01*
G37*
G36*
G01Y723733D02*
X1621948Y725233D01*
Y722233D01*
X1624948Y723733D01*
G37*
G36*
G01X1625248Y738333D02*
X1622248Y739833D01*
Y736833D01*
X1625248Y738333D01*
G37*
G36*
G01Y756533D02*
X1622248Y758033D01*
Y755033D01*
X1625248Y756533D01*
G37*
G36*
G01X1614448Y780733D02*
X1611448Y782233D01*
Y779233D01*
X1614448Y780733D01*
G37*
G36*
G01X1614248Y793433D02*
X1611248Y794933D01*
Y791933D01*
X1614248Y793433D01*
G37*
G36*
G01X1613948Y807533D02*
X1610948Y809033D01*
Y806033D01*
X1613948Y807533D01*
G37*
G36*
G01X1614048Y821633D02*
X1611048Y823133D01*
Y820133D01*
X1614048Y821633D01*
G37*
G36*
G01X1641580Y203452D02*
X1630084D01*
Y206601D01*
X1641580D01*
Y203452D01*
G37*
G36*
G01X1641349Y262744D02*
X1629853D01*
Y265893D01*
X1641349D01*
Y262744D01*
G37*
G36*
G01X1632065Y432059D02*
Y428059D01*
X1636065Y430059D01*
X1632065Y432059D01*
G37*
G36*
G01X1646701Y893353D02*
Y889353D01*
X1642701Y891353D01*
X1646701Y893353D01*
G37*
G36*
G01X1646132Y964120D02*
Y960120D01*
X1642132Y962120D01*
X1646132Y964120D01*
G37*
G36*
G01X1642035Y1624402D02*
Y1620402D01*
X1646035Y1622402D01*
X1642035Y1624402D01*
G37*
G36*
G01X1655581Y153843D02*
X1654520Y157025D01*
X1652399Y154904D01*
X1655581Y153843D01*
G37*
G36*
G01X1657194Y220252D02*
X1660194D01*
Y221552D01*
X1657194D01*
Y220252D01*
G37*
G36*
G01X1675396Y59585D02*
X1676616Y62025D01*
X1677836Y59585D01*
X1675396D01*
G37*
G36*
G01X1672721Y172566D02*
X1675549Y175395D01*
X1671307Y176809D01*
X1672721Y172566D01*
G37*
G36*
G01X1671417Y234813D02*
Y250325D01*
X1674017D01*
Y234813D01*
X1671417D01*
G37*
G36*
G01X1669061Y267235D02*
X1684573D01*
Y264635D01*
X1669061D01*
Y267235D01*
G37*
G36*
G01X1663737Y268274D02*
X1666565Y271102D01*
X1662322Y272516D01*
X1663737Y268274D01*
G37*
G36*
G01X1667183Y322716D02*
X1668918Y321849D01*
X1667183Y320982D01*
Y322716D01*
G37*
G36*
G01X1668493Y348437D02*
Y346437D01*
X1671493Y347437D01*
X1668493Y348437D01*
G37*
G36*
G01X1681146Y122720D02*
X1678318Y119892D01*
X1682560Y118477D01*
X1681146Y122720D01*
G37*
G36*
G01X1682473Y142689D02*
X1680091Y141498D01*
Y143880D01*
X1682473Y142689D01*
G37*
G36*
G01X1694203Y254607D02*
X1693142Y257789D01*
X1691021Y255668D01*
X1694203Y254607D01*
G37*
G36*
G01X1699374Y211197D02*
Y214197D01*
X1698074D01*
Y211197D01*
X1699374D01*
G37*
G36*
G01X1697391Y329752D02*
Y327292D01*
X1695211Y328584D01*
X1697391Y329752D01*
G37*
G36*
G01X1709967Y1149853D02*
X1707967Y1145853D01*
X1711967D01*
X1709967Y1149853D01*
G37*
G36*
G01X1716222Y71519D02*
X1714559Y66528D01*
X1711232Y69855D01*
X1716222Y71519D01*
G37*
G36*
G01X1717174Y195583D02*
Y184087D01*
X1714025D01*
Y195583D01*
X1717174D01*
G37*
G36*
G01X1722199Y386822D02*
X1725028Y383993D01*
X1726442Y388236D01*
X1722199Y386822D01*
G37*
G36*
G01X1743942Y203452D02*
X1732446D01*
Y206601D01*
X1743942D01*
Y203452D01*
G37*
G36*
G01X1743711Y262744D02*
X1732215D01*
Y265893D01*
X1743711D01*
Y262744D01*
G37*
G36*
G01X1724705Y448921D02*
X1727533Y446092D01*
X1728947Y450335D01*
X1724705Y448921D01*
G37*
G36*
G01X1738392Y483629D02*
X1741392D01*
Y484929D01*
X1738392D01*
Y483629D01*
G37*
G36*
G01X1733462Y1169105D02*
X1732242Y1166665D01*
X1731022Y1169105D01*
X1733462D01*
G37*
G36*
G01X1755634Y910100D02*
X1757118Y906386D01*
X1760090Y909728D01*
X1755634Y910100D01*
G37*
G36*
G01X1752762Y1598832D02*
X1755590Y1596004D01*
X1757005Y1600247D01*
X1752762Y1598832D01*
G37*
G36*
G01X1759556Y220252D02*
X1762556D01*
Y221552D01*
X1759556D01*
Y220252D01*
G37*
G36*
G01X1771423Y267235D02*
X1786935D01*
Y264635D01*
X1771423D01*
Y267235D01*
G37*
G36*
G01X1766200Y268863D02*
X1769028Y271692D01*
X1764786Y273106D01*
X1766200Y268863D01*
G37*
G36*
G01X1761744Y397590D02*
Y394590D01*
X1763044D01*
Y397590D01*
X1761744D01*
G37*
G36*
G01X1777758Y59585D02*
X1778978Y62025D01*
X1780198Y59585D01*
X1777758D01*
G37*
G36*
G01X1775784Y173630D02*
X1778613Y176458D01*
X1774370Y177872D01*
X1775784Y173630D01*
G37*
G36*
G01X1773779Y234813D02*
Y250325D01*
X1776379D01*
Y234813D01*
X1773779D01*
G37*
G36*
G01X1779147Y476631D02*
X1778087Y479813D01*
X1775965Y477691D01*
X1779147Y476631D01*
G37*
G36*
G01X1776778Y816683D02*
X1775528Y814183D01*
X1778028D01*
X1776778Y816683D01*
G37*
G36*
G01X1789728Y818275D02*
X1785670Y816246D01*
Y820304D01*
X1789728Y818275D01*
G37*
G36*
G01X1780971Y1446665D02*
X1777971Y1448165D01*
Y1445165D01*
X1780971Y1446665D01*
G37*
G36*
G01X1780848Y1478855D02*
X1777848Y1480355D01*
Y1477355D01*
X1780848Y1478855D01*
G37*
G36*
G01X1804252Y432227D02*
X1807605Y433903D01*
Y430551D01*
X1804252Y432227D01*
G37*
G36*
G01X1804764Y971700D02*
X1803583Y968156D01*
X1805945D01*
X1804764Y971700D01*
G37*
G36*
G01X1798258Y1205092D02*
X1799478Y1207532D01*
X1800698Y1205092D01*
X1798258D01*
G37*
G36*
G01X1803490Y1206630D02*
Y1210630D01*
X1799490Y1208630D01*
X1803490Y1206630D01*
G37*
G36*
G01X1812506Y1085501D02*
X1816506D01*
X1814506Y1089501D01*
X1812506Y1085501D01*
G37*
%LPC*%
G75*
G36*
G01X692120Y821516D02*
X689754Y823975D01*
X689673Y825244D01*
X694573D01*
X694494Y823984D01*
X692120Y821516D01*
G37*
G36*
G01X691282Y820645D02*
X690049Y819363D01*
X689874Y822098D01*
X691282Y820645D01*
G37*
G36*
G01X694205Y819349D02*
X692958Y820645D01*
X694377Y822110D01*
X694205Y819349D01*
G37*
G36*
G01X693873Y817944D02*
G03X692573Y816594I849J-2119D01*
G01X690223Y816644D01*
X690152Y817747D01*
X692120Y819779D01*
X693890Y817951D01*
X693873Y817944D01*
G37*
%LPD*%
G75*
G36*
G01X690773Y824194D02*
X693473D01*
Y823444D01*
X690773D01*
Y824194D01*
G37*
G36*
G01X342581Y467810D02*
Y470959D01*
X354077D01*
Y467810D01*
X342581D01*
G37*
G36*
G01X373684Y413204D02*
Y424700D01*
X376833D01*
Y413204D01*
X373684D01*
G37*
G36*
G01X384773Y429160D02*
Y432309D01*
X396269D01*
Y429160D01*
X384773D01*
G37*
G36*
G01X405045Y373767D02*
Y376367D01*
X420557D01*
Y373767D01*
X405045D01*
G37*
G36*
G01X435471Y406628D02*
Y422140D01*
X438071D01*
Y406628D01*
X435471D01*
G37*
G36*
G01X1256754Y467810D02*
Y470959D01*
X1268250D01*
Y467810D01*
X1256754D01*
G37*
G36*
G01X1287857Y413204D02*
Y424700D01*
X1291006D01*
Y413204D01*
X1287857D01*
G37*
G36*
G01X1299000Y429160D02*
Y432309D01*
X1310496D01*
Y429160D01*
X1299000D01*
G37*
G36*
G01X1319218Y373767D02*
Y376367D01*
X1334730D01*
Y373767D01*
X1319218D01*
G37*
G36*
G01X1349644Y406628D02*
Y422140D01*
X1352244D01*
Y406628D01*
X1349644D01*
G37*
G36*
G01X1713841Y467810D02*
Y470959D01*
X1725337D01*
Y467810D01*
X1713841D01*
G37*
G36*
G01X1744944Y413204D02*
Y424700D01*
X1748093D01*
Y413204D01*
X1744944D01*
G37*
G36*
G01X1756087Y429160D02*
Y432309D01*
X1767583D01*
Y429160D01*
X1756087D01*
G37*
G36*
G01X1776305Y373767D02*
Y376367D01*
X1791817D01*
Y373767D01*
X1776305D01*
G37*
G36*
G01X1806731Y406628D02*
Y422140D01*
X1809331D01*
Y406628D01*
X1806731D01*
G37*
G54D10*
G01X650241Y806065D02*
X650841Y806465D01*
G01X650041Y805965D02*
X650241Y806065D01*
G01X649741Y805865D02*
X650041Y805965D01*
G01X649041Y805765D02*
X649741Y805865D01*
G01X648941Y805765D02*
X649041D01*
G01X648341Y805865D02*
X648941Y805765D01*
G01X648041Y805965D02*
X648341Y805865D01*
G01X647641Y806165D02*
X648041Y805965D01*
G01X647141Y806565D02*
X647641Y806165D01*
G01X650841Y806465D02*
X651241Y806965D01*
G01X646841D02*
X647141Y806565D01*
G01X646641Y807365D02*
X646841Y806965D01*
G01X646541Y807665D02*
X646641Y807365D01*
G01X646441Y808165D02*
X646541Y807665D01*
G01X646441Y808465D02*
Y808165D01*
G01X646541Y809065D02*
X646441Y808465D01*
G01X646641Y809365D02*
X646541Y809065D01*
G01X646841Y809765D02*
X646641Y809365D01*
G01X647141Y810165D02*
X646841Y809765D01*
G01X647241Y810265D02*
X647141Y810165D01*
G01X647641Y810565D02*
X647241Y810265D01*
G01X648041Y810765D02*
X647641Y810565D01*
G01X648341Y810865D02*
X648041Y810765D01*
G01X648841Y810965D02*
X648341Y810865D01*
G01X649241Y810965D02*
X648841D01*
G01X649741Y810865D02*
X649241Y810965D01*
G01X650041Y810765D02*
X649741Y810865D01*
G01X650441Y810565D02*
X650041Y810765D01*
G01X650941Y810165D02*
X650441Y810565D01*
G01X651241Y809765D02*
X650941Y810165D01*
G01X651441Y809365D02*
X651241Y809765D01*
G01X651541Y809065D02*
X651441Y809365D01*
G01X651641Y808365D02*
X651541Y809065D01*
G01X646441Y808365D02*
X651641D01*
G01X652941Y810065D02*
X654041Y810665D01*
G01X651841Y832165D02*
Y822065D01*
G01X645741Y832165D02*
Y822065D01*
G01X656651Y824465D02*
G02I-2410J0D01*
G01X648241Y827165D02*
X645741D01*
G01X648241Y832165D02*
G02Y827165I0J-2500D01*
G01X645741Y832165D02*
X648241D01*
G01X654041Y810665D02*
Y805665D01*
G01X817945Y1416409D02*
Y1438583D01*
X999047D01*
Y1348031D01*
X825787D01*
Y1336220D01*
X817945D01*
Y1416409D01*
G54D11*
G01X-20602Y-468335D02*
Y-543335D01*
X479398D01*
Y-468335D01*
X-20602D01*
G01X-8602Y-533335D02*
Y-538335D01*
G01X-10059Y-533335D02*
X-7145D01*
G01X-2235Y-538335D02*
X-4769D01*
Y-533335D01*
X-2235D01*
G01X-3249Y-535752D02*
X-4769D01*
G01X331Y-533335D02*
Y-538335D01*
X2865D01*
G01X6698Y-538502D02*
X6571Y-538418D01*
Y-538252D01*
X6698Y-538168D01*
X6825Y-538252D01*
Y-538418D01*
X6698Y-538502D01*
G01Y-536252D02*
X6571Y-536168D01*
Y-536002D01*
X6698Y-535918D01*
X6825Y-536002D01*
Y-536168D01*
X6698Y-536252D01*
G01X11481Y-540002D02*
X10848Y-539168D01*
X10531Y-538335D01*
Y-535002D01*
X10848Y-534168D01*
X11481Y-533335D01*
G01X16898D02*
X16391Y-533502D01*
X16011Y-533918D01*
X15758Y-534418D01*
X15568Y-535085D01*
X15505Y-535835D01*
X15568Y-536585D01*
X15758Y-537252D01*
X16011Y-537752D01*
X16391Y-538168D01*
X16898Y-538335D01*
X17405Y-538168D01*
X17785Y-537752D01*
X18038Y-537252D01*
X18228Y-536585D01*
X18291Y-535835D01*
X18228Y-535085D01*
X18038Y-534418D01*
X17785Y-533918D01*
X17405Y-533502D01*
X16898Y-533335D01*
G01X20605Y-537335D02*
X20985Y-537918D01*
X21491Y-538252D01*
X22061Y-538335D01*
X22568Y-538252D01*
X23075Y-537835D01*
X23391Y-537335D01*
X23455Y-536835D01*
X23328Y-536252D01*
X22885Y-535835D01*
X22441Y-535668D01*
X21871D01*
G01X22441D02*
X22821Y-535418D01*
X23138Y-535002D01*
X23265Y-534502D01*
X23138Y-534002D01*
X22821Y-533585D01*
X22251Y-533335D01*
X21681Y-533418D01*
X21111Y-533752D01*
G01X27415Y-540002D02*
X28048Y-539168D01*
X28365Y-538335D01*
Y-535002D01*
X28048Y-534168D01*
X27415Y-533335D01*
G01X30805Y-537335D02*
X31185Y-537918D01*
X31691Y-538252D01*
X32261Y-538335D01*
X32768Y-538252D01*
X33275Y-537835D01*
X33591Y-537335D01*
X33655Y-536835D01*
X33528Y-536252D01*
X33085Y-535835D01*
X32641Y-535668D01*
X32071D01*
G01X32641D02*
X33021Y-535418D01*
X33338Y-535002D01*
X33465Y-534502D01*
X33338Y-534002D01*
X33021Y-533585D01*
X32451Y-533335D01*
X31881Y-533418D01*
X31311Y-533752D01*
G01X36095Y-534168D02*
X36475Y-533668D01*
X36918Y-533418D01*
X37425Y-533335D01*
X38058Y-533502D01*
X38501Y-533918D01*
X38628Y-534418D01*
X38565Y-534918D01*
X38311Y-535335D01*
X37045Y-536168D01*
X36475Y-536752D01*
X36095Y-537585D01*
X35968Y-538335D01*
X38628D01*
G01X42271D02*
X42398Y-537252D01*
X42588Y-536335D01*
X42841Y-535502D01*
X43158Y-534585D01*
X43665Y-533335D01*
X41131D01*
G01X46675Y-536668D02*
X48321D01*
G01X51395Y-534168D02*
X51775Y-533668D01*
X52218Y-533418D01*
X52725Y-533335D01*
X53358Y-533502D01*
X53801Y-533918D01*
X53928Y-534418D01*
X53865Y-534918D01*
X53611Y-535335D01*
X52345Y-536168D01*
X51775Y-536752D01*
X51395Y-537585D01*
X51268Y-538335D01*
X53928D01*
G01X56305Y-537335D02*
X56685Y-537918D01*
X57191Y-538252D01*
X57761Y-538335D01*
X58268Y-538252D01*
X58775Y-537835D01*
X59091Y-537335D01*
X59155Y-536835D01*
X59028Y-536252D01*
X58585Y-535835D01*
X58141Y-535668D01*
X57571D01*
G01X58141D02*
X58521Y-535418D01*
X58838Y-535002D01*
X58965Y-534502D01*
X58838Y-534002D01*
X58521Y-533585D01*
X57951Y-533335D01*
X57381Y-533418D01*
X56811Y-533752D01*
G01X63558Y-538335D02*
Y-533335D01*
X61215Y-536918D01*
X64381D01*
G01X66505Y-537585D02*
X66885Y-538002D01*
X67328Y-538252D01*
X67898Y-538335D01*
X68468Y-538168D01*
X68911Y-537835D01*
X69228Y-537252D01*
X69291Y-536585D01*
X69165Y-535918D01*
X68848Y-535502D01*
X68405Y-535168D01*
X67961Y-535085D01*
X67518Y-535168D01*
X66948Y-535502D01*
X67138Y-533335D01*
X68848D01*
G01X76895Y-538335D02*
Y-533335D01*
X79301D01*
G01X78415Y-535752D02*
X76895D01*
G01X81615Y-538335D02*
X83198Y-533335D01*
X84781Y-538335D01*
G01X84211Y-536585D02*
X82185D01*
G01X86968Y-538335D02*
X89628Y-533335D01*
G01X86968D02*
X89628Y-538335D01*
G01X93398Y-538502D02*
X93271Y-538418D01*
Y-538252D01*
X93398Y-538168D01*
X93525Y-538252D01*
Y-538418D01*
X93398Y-538502D01*
G01Y-536252D02*
X93271Y-536168D01*
Y-536002D01*
X93398Y-535918D01*
X93525Y-536002D01*
Y-536168D01*
X93398Y-536252D01*
G01X98181Y-540002D02*
X97548Y-539168D01*
X97231Y-538335D01*
Y-535002D01*
X97548Y-534168D01*
X98181Y-533335D01*
G01X103598D02*
X103091Y-533502D01*
X102711Y-533918D01*
X102458Y-534418D01*
X102268Y-535085D01*
X102205Y-535835D01*
X102268Y-536585D01*
X102458Y-537252D01*
X102711Y-537752D01*
X103091Y-538168D01*
X103598Y-538335D01*
X104105Y-538168D01*
X104485Y-537752D01*
X104738Y-537252D01*
X104928Y-536585D01*
X104991Y-535835D01*
X104928Y-535085D01*
X104738Y-534418D01*
X104485Y-533918D01*
X104105Y-533502D01*
X103598Y-533335D01*
G01X107305Y-537335D02*
X107685Y-537918D01*
X108191Y-538252D01*
X108761Y-538335D01*
X109268Y-538252D01*
X109775Y-537835D01*
X110091Y-537335D01*
X110155Y-536835D01*
X110028Y-536252D01*
X109585Y-535835D01*
X109141Y-535668D01*
X108571D01*
G01X109141D02*
X109521Y-535418D01*
X109838Y-535002D01*
X109965Y-534502D01*
X109838Y-534002D01*
X109521Y-533585D01*
X108951Y-533335D01*
X108381Y-533418D01*
X107811Y-533752D01*
G01X114115Y-540002D02*
X114748Y-539168D01*
X115065Y-538335D01*
Y-535002D01*
X114748Y-534168D01*
X114115Y-533335D01*
G01X117505Y-537335D02*
X117885Y-537918D01*
X118391Y-538252D01*
X118961Y-538335D01*
X119468Y-538252D01*
X119975Y-537835D01*
X120291Y-537335D01*
X120355Y-536835D01*
X120228Y-536252D01*
X119785Y-535835D01*
X119341Y-535668D01*
X118771D01*
G01X119341D02*
X119721Y-535418D01*
X120038Y-535002D01*
X120165Y-534502D01*
X120038Y-534002D01*
X119721Y-533585D01*
X119151Y-533335D01*
X118581Y-533418D01*
X118011Y-533752D01*
G01X122921Y-537752D02*
X123365Y-538168D01*
X123871Y-538335D01*
X124378Y-538168D01*
X124821Y-537668D01*
X125138Y-536918D01*
X125265Y-536168D01*
Y-535252D01*
X125138Y-534502D01*
X124821Y-533835D01*
X124441Y-533502D01*
X123998Y-533335D01*
X123491Y-533502D01*
X123111Y-533835D01*
X122858Y-534335D01*
X122731Y-535002D01*
X122858Y-535585D01*
X123175Y-536168D01*
X123555Y-536502D01*
X123998Y-536585D01*
X124505Y-536418D01*
X124885Y-536002D01*
X125265Y-535252D01*
G01X128971Y-538335D02*
X129098Y-537252D01*
X129288Y-536335D01*
X129541Y-535502D01*
X129858Y-534585D01*
X130365Y-533335D01*
X127831D01*
G01X133375Y-536668D02*
X135021D01*
G01X137905Y-537335D02*
X138285Y-537918D01*
X138791Y-538252D01*
X139361Y-538335D01*
X139868Y-538252D01*
X140375Y-537835D01*
X140691Y-537335D01*
X140755Y-536835D01*
X140628Y-536252D01*
X140185Y-535835D01*
X139741Y-535668D01*
X139171D01*
G01X139741D02*
X140121Y-535418D01*
X140438Y-535002D01*
X140565Y-534502D01*
X140438Y-534002D01*
X140121Y-533585D01*
X139551Y-533335D01*
X138981Y-533418D01*
X138411Y-533752D01*
G01X143195Y-536252D02*
X143638Y-535668D01*
X144018Y-535335D01*
X144525Y-535168D01*
X144968Y-535335D01*
X145285Y-535668D01*
X145538Y-536168D01*
X145601Y-536752D01*
X145538Y-537252D01*
X145285Y-537752D01*
X144905Y-538168D01*
X144461Y-538335D01*
X143955Y-538168D01*
X143511Y-537668D01*
X143258Y-536918D01*
X143195Y-536085D01*
X143321Y-535002D01*
X143511Y-534418D01*
X143828Y-533835D01*
X144271Y-533418D01*
X144715Y-533335D01*
X145158Y-533502D01*
X145475Y-533918D01*
G01X149498Y-538335D02*
Y-533335D01*
X148738Y-534335D01*
G01Y-538335D02*
X150258D01*
G01X155358D02*
Y-533335D01*
X153015Y-536918D01*
X156181D01*
G01X795131Y1645405D02*
G03X789296Y1647992I-5835J-5287D01*
G01X7874D01*
G03X0Y1640118I0J-7874D01*
G01Y970427D01*
G03X2306Y964859I7874J0D01*
G01X12654Y954511D01*
G02X14961Y948943I-5568J-5569D01*
G01Y344836D01*
G02X12654Y339269I-7873J1D01*
G01X2306Y328920D01*
G03X0Y323353I5567J-5567D01*
G01Y7874D01*
G03X7874Y0I7874J0D01*
G01X23484D01*
G03X31358Y7874I0J7874D01*
G01Y46654D01*
G02X35295Y50591I3937J0D01*
G01X66791D01*
G02X70728Y46654I0J-3937D01*
G01Y7874D01*
G03X78602Y0I7874J0D01*
G01X125846D01*
G03X133720Y7874I0J7874D01*
G01Y46654D01*
G02X137657Y50591I3937J0D01*
G01X169154D01*
G02X173091Y46654I0J-3937D01*
G01Y7874D01*
G03X180965Y0I7874J0D01*
G01X228209D01*
G03X236083Y7874I0J7874D01*
G01Y46654D01*
G02X240020Y50591I3937J0D01*
G01X271516D01*
G02X275453Y46654I0J-3937D01*
G01Y7874D01*
G03X283327Y0I7874J0D01*
G01X330571D01*
G03X338445Y7874I0J7874D01*
G01Y46654D01*
G02X342382Y50591I3937J0D01*
G01X373878D01*
G02X377815Y46654I0J-3937D01*
G01Y7874D01*
G03X385689Y0I7874J0D01*
G01X480571D01*
G03X488445Y7874I0J7874D01*
G01Y46654D01*
G02X492382Y50591I3937J0D01*
G01X523878D01*
G02X527815Y46654I0J-3937D01*
G01Y7874D01*
G03X535689Y0I7874J0D01*
G01X582933D01*
G03X590807Y7874I0J7874D01*
G01Y46654D01*
G02X594744Y50591I3937J0D01*
G01X626240D01*
G02X630177Y46654I0J-3937D01*
G01Y7874D01*
G03X638051Y0I7874J0D01*
G01X685295D01*
G03X693169Y7874I0J7874D01*
G01Y46654D01*
G02X697106Y50591I3937J0D01*
G01X728602D01*
G02X732539Y46654I0J-3937D01*
G01Y7874D01*
G03X740413Y0I7874J0D01*
G01X787657D01*
G03X795531Y7874I0J7874D01*
G01Y46654D01*
G02X799469Y50591I3937J0D01*
G01X830965D01*
G02X834902Y46654I0J-3937D01*
G01Y7874D01*
G03X842776Y0I7874J0D01*
G01X937657D01*
G03X945531Y7874I0J7874D01*
G01Y46654D01*
G02X949469Y50591I3938J0D01*
G01X980965D01*
G02X984902Y46654I0J-3937D01*
G01Y7874D01*
G03X992776Y0I7874J0D01*
G01X1040020D01*
G03X1047894Y7874I0J7874D01*
G01Y46654D01*
G02X1051831Y50591I3937J0D01*
G01X1083327D01*
G02X1087264Y46654I0J-3937D01*
G01Y7874D01*
G03X1095138Y0I7874J0D01*
G01X1142382D01*
G03X1150256Y7874I0J7874D01*
G01Y46654D01*
G02X1154193Y50591I3937J0D01*
G01X1185689D01*
G02X1189626Y46654I0J-3937D01*
G01Y7874D01*
G03X1197500Y0I7874J0D01*
G01X1244744D01*
G03X1252618Y7874I0J7874D01*
G01Y46654D01*
G02X1256555Y50591I3937J0D01*
G01X1288051D01*
G02X1291988Y46654I0J-3937D01*
G01Y7874D01*
G03X1299862Y0I7874J0D01*
G01X1394744D01*
G03X1402618Y7874I0J7874D01*
G01Y46654D01*
G02X1406555Y50591I3937J0D01*
G01X1438051D01*
G02X1441988Y46654I0J-3937D01*
G01Y7874D01*
G03X1449862Y0I7874J0D01*
G01X1497106D01*
G03X1504980Y7874I0J7874D01*
G01Y46654D01*
G02X1508917Y50591I3937J0D01*
G01X1540413D01*
G02X1544350Y46654I0J-3937D01*
G01Y7874D01*
G03X1552224Y0I7874J0D01*
G01X1599469D01*
G03X1607343Y7874I0J7874D01*
G01Y46654D01*
G02X1611280Y50591I3937J0D01*
G01X1642776D01*
G02X1646713Y46654I0J-3937D01*
G01Y7874D01*
G03X1654587Y0I7874J0D01*
G01X1701831D01*
G03X1709705Y7874I0J7874D01*
G01Y46654D01*
G02X1713642Y50591I3937J0D01*
G01X1745138D01*
G02X1749075Y46654I0J-3937D01*
G01Y7874D01*
G03X1756949Y0I7874J0D01*
G01X1833071D01*
G03X1840945Y7874I0J7874D01*
G01Y323353D01*
G03X1838639Y328920I-7873J0D01*
G01X1828291Y339269D01*
G02X1825984Y344836I5566J5568D01*
G01Y948943D01*
G02X1828291Y954511I7875J-1D01*
G01X1838639Y964859D01*
G03X1840945Y970427I-5568J5568D01*
G01Y1640118D01*
G03X1833071Y1647992I-7874J0D01*
G01X1081727D01*
G03X1075892Y1645405I0J-7874D01*
G02X1070057Y1642819I-5834J5288D01*
G01X800966D01*
G02X795131Y1645405I-1J7874D01*
G01X7480Y1226024D02*
G02X20079I6299J0D01*
G02X7480I-6299J0D01*
G01X20472Y1573425D02*
X26772D01*
G02Y1561220I0J-6103D01*
G01X20472D01*
G02Y1573425I0J6102D01*
G01X12598Y1604724D02*
G02X34646I11024J0D01*
G02X12598I-11024J0D01*
G01X24882Y81575D02*
G02X32756I3937J0D01*
G02X24882I-3937J0D01*
G01X51181Y765197D02*
G02X73228I11023J0D01*
G02X51181I-11024J0D01*
G01X62992Y333465D02*
G02X85039I11024J0D01*
G02X62992I-11023J0D01*
G01X69370Y61614D02*
G02X77244I3937J0D01*
G02X69370I-3937J0D01*
G01X73031Y1186654D02*
G02X85630I6299J0D01*
G02X73031I-6300J0D01*
G01X91201Y70866D02*
G02X113248I11024J0D01*
G02X91201I-11023J0D01*
G01X107874Y1066535D02*
G02X125591I8859J0D01*
G02X107874I-8858J0D01*
G01Y1263386D02*
G02X125591I8859J0D01*
G02X107874I-8858J0D01*
G01X127244Y81575D02*
G02X135118I3937J0D01*
G02X127244I-3937J0D01*
G01X174398Y-468335D02*
Y-543335D01*
G01Y-518335D02*
X277398D01*
Y-493335D01*
G01X174398D02*
X277398D01*
G01X171732Y61614D02*
G02X179606I3937J0D01*
G02X171732I-3937J0D01*
G01X229606Y81575D02*
G02X237480I3937J0D01*
G02X229606I-3937J0D01*
G01X241644Y1580079D02*
G02X229144I-6250J0D01*
G02X241644I6250J0D01*
G01X241683Y1606142D02*
G02X229183I-6250J0D01*
G02X241683I6250J0D01*
G01X241644Y1626339D02*
G02X229144I-6250J0D01*
G02X241644I6250J0D01*
G01X277398Y-468335D02*
Y-543335D01*
G01X274094Y61614D02*
G02X281969I3938J0D01*
G02X274094I-3937J0D01*
G01X279398Y-468335D02*
Y-543335D01*
G01X284905Y-528335D02*
Y-523335D01*
X286171D01*
X286678Y-523585D01*
X287058Y-523918D01*
X287375Y-524418D01*
X287628Y-525002D01*
X287691Y-525835D01*
X287628Y-526668D01*
X287375Y-527252D01*
X287058Y-527752D01*
X286678Y-528085D01*
X286171Y-528335D01*
X284905D01*
G01X289815D02*
X291398Y-523335D01*
X292981Y-528335D01*
G01X292411Y-526585D02*
X290385D01*
G01X296498Y-523335D02*
Y-528335D01*
G01X295041Y-523335D02*
X297955D01*
G01X302865Y-528335D02*
X300331D01*
Y-523335D01*
X302865D01*
G01X301851Y-525752D02*
X300331D01*
G01X306698Y-528502D02*
X306571Y-528418D01*
Y-528252D01*
X306698Y-528168D01*
X306825Y-528252D01*
Y-528418D01*
X306698Y-528502D01*
G01Y-526252D02*
X306571Y-526168D01*
Y-526002D01*
X306698Y-525918D01*
X306825Y-526002D01*
Y-526168D01*
X306698Y-526252D01*
G01X279398Y-518335D02*
X479398D01*
G01X285031Y-503335D02*
Y-498335D01*
X286551D01*
X287058Y-498585D01*
X287438Y-499168D01*
X287565Y-499835D01*
X287438Y-500502D01*
X287121Y-501002D01*
X286551Y-501252D01*
X285031D01*
G01X290258Y-503502D02*
X292538Y-498335D01*
G01X295041Y-503335D02*
Y-498335D01*
X297955Y-503335D01*
Y-498335D01*
G01X301598Y-503502D02*
X301471Y-503418D01*
Y-503252D01*
X301598Y-503168D01*
X301725Y-503252D01*
Y-503418D01*
X301598Y-503502D01*
G01Y-501252D02*
X301471Y-501168D01*
Y-501002D01*
X301598Y-500918D01*
X301725Y-501002D01*
Y-501168D01*
X301598Y-501252D01*
G01X279398Y-493335D02*
X479398D01*
G01X285031Y-478335D02*
Y-473335D01*
X286551D01*
X287058Y-473585D01*
X287438Y-474168D01*
X287565Y-474835D01*
X287438Y-475502D01*
X287121Y-476002D01*
X286551Y-476252D01*
X285031D01*
G01X290131Y-478335D02*
Y-473335D01*
X291715D01*
X292221Y-473585D01*
X292538Y-473918D01*
X292665Y-474585D01*
X292538Y-475252D01*
X292158Y-475668D01*
X291715Y-475918D01*
X290131D01*
G01X291715D02*
X292665Y-478335D01*
G01X296498D02*
X295991Y-478252D01*
X295548Y-477918D01*
X295168Y-477418D01*
X294915Y-476835D01*
X294788Y-476168D01*
Y-475502D01*
X294915Y-474835D01*
X295168Y-474252D01*
X295548Y-473752D01*
X295991Y-473418D01*
X296498Y-473335D01*
X297005Y-473418D01*
X297448Y-473752D01*
X297828Y-474252D01*
X298081Y-474835D01*
X298208Y-475502D01*
Y-476168D01*
X298081Y-476835D01*
X297828Y-477418D01*
X297448Y-477918D01*
X297005Y-478252D01*
X296498Y-478335D01*
G01X300331Y-477335D02*
X300648Y-477835D01*
X301028Y-478168D01*
X301471Y-478335D01*
X301978Y-478168D01*
X302358Y-477835D01*
X302738Y-477335D01*
X302865Y-476668D01*
Y-473335D01*
G01X307965Y-478335D02*
X305431D01*
Y-473335D01*
X307965D01*
G01X306951Y-475752D02*
X305431D01*
G01X313191Y-473752D02*
X312811Y-473502D01*
X312368Y-473335D01*
X311861D01*
X311291Y-473585D01*
X310848Y-474002D01*
X310531Y-474502D01*
X310278Y-475335D01*
X310215Y-476085D01*
X310341Y-476835D01*
X310531Y-477335D01*
X310911Y-477835D01*
X311355Y-478168D01*
X311798Y-478335D01*
X312241D01*
X312685Y-478168D01*
X313065Y-477918D01*
X313381Y-477585D01*
G01X316898Y-473335D02*
Y-478335D01*
G01X315441Y-473335D02*
X318355D01*
G01X321998Y-478502D02*
X321871Y-478418D01*
Y-478252D01*
X321998Y-478168D01*
X322125Y-478252D01*
Y-478418D01*
X321998Y-478502D01*
G01Y-476252D02*
X321871Y-476168D01*
Y-476002D01*
X321998Y-475918D01*
X322125Y-476002D01*
Y-476168D01*
X321998Y-476252D01*
G01X331969Y81575D02*
G02X339843I3937J0D01*
G02X331969I-3937J0D01*
G01X344094Y1066535D02*
G02X361811I8858J0D01*
G02X344094I-8859J0D01*
G01Y1263386D02*
G02X361811I8858J0D01*
G02X344094I-8859J0D01*
G01X376457Y61614D02*
G02X384331I3937J0D01*
G02X376457I-3937J0D01*
G01X384055Y1141024D02*
G02X396654I6299J0D01*
G02X384055I-6299J0D01*
G01X394258Y-543563D02*
Y-518563D01*
G01X397031Y-520835D02*
Y-525835D01*
X399565D01*
G01X402638Y-520835D02*
X404158D01*
G01X403398D02*
Y-525835D01*
G01X402638D02*
X404158D01*
G01X409005Y-523168D02*
X409258Y-522918D01*
X409448Y-522502D01*
X409575Y-521918D01*
X409448Y-521418D01*
X409195Y-521085D01*
X408751Y-520835D01*
X407041D01*
Y-525835D01*
X409131D01*
X409575Y-525502D01*
X409828Y-525002D01*
X409955Y-524418D01*
X409828Y-523835D01*
X409448Y-523335D01*
X409005Y-523168D01*
X407041D01*
G01X413598Y-526002D02*
X413471Y-525918D01*
Y-525752D01*
X413598Y-525668D01*
X413725Y-525752D01*
Y-525918D01*
X413598Y-526002D01*
G01Y-523752D02*
X413471Y-523668D01*
Y-523502D01*
X413598Y-523418D01*
X413725Y-523502D01*
Y-523668D01*
X413598Y-523752D01*
G01X398465Y1604724D02*
G02X420512I11024J0D01*
G02X398465I-11023J0D01*
G01X422106Y70866D02*
G02X444154I11024J0D01*
G02X422106I-11024J0D01*
G01X437258Y-518563D02*
Y-543563D01*
G01X437398Y-518335D02*
Y-543335D01*
G01X441298Y-520835D02*
Y-525835D01*
G01X439841Y-520835D02*
X442755D01*
G01X446398Y-525835D02*
X446018Y-525752D01*
X445638Y-525418D01*
X445385Y-524835D01*
X445258Y-524168D01*
X445385Y-523502D01*
X445638Y-522918D01*
X446018Y-522585D01*
X446398Y-522502D01*
X446778Y-522585D01*
X447158Y-522918D01*
X447411Y-523502D01*
X447475Y-524168D01*
X447411Y-524835D01*
X447158Y-525418D01*
X446778Y-525752D01*
X446398Y-525835D01*
G01X451498D02*
X451118Y-525752D01*
X450738Y-525418D01*
X450485Y-524835D01*
X450358Y-524168D01*
X450485Y-523502D01*
X450738Y-522918D01*
X451118Y-522585D01*
X451498Y-522502D01*
X451878Y-522585D01*
X452258Y-522918D01*
X452511Y-523502D01*
X452575Y-524168D01*
X452511Y-524835D01*
X452258Y-525418D01*
X451878Y-525752D01*
X451498Y-525835D01*
G01X456598D02*
Y-520835D01*
G01X461698Y-526002D02*
X461571Y-525918D01*
Y-525752D01*
X461698Y-525668D01*
X461825Y-525752D01*
Y-525918D01*
X461698Y-526002D01*
G01Y-523752D02*
X461571Y-523668D01*
Y-523502D01*
X461698Y-523418D01*
X461825Y-523502D01*
Y-523668D01*
X461698Y-523752D01*
G01X437398Y-493335D02*
Y-518335D01*
G01X440031Y-500835D02*
Y-495835D01*
X441615D01*
X442121Y-496085D01*
X442438Y-496418D01*
X442565Y-497085D01*
X442438Y-497752D01*
X442058Y-498168D01*
X441615Y-498418D01*
X440031D01*
G01X441615D02*
X442565Y-500835D01*
G01X447665D02*
X445131D01*
Y-495835D01*
X447665D01*
G01X446651Y-498252D02*
X445131D01*
G01X449915Y-495835D02*
X451498Y-500835D01*
X453081Y-495835D01*
G01X456598Y-501002D02*
X456471Y-500918D01*
Y-500752D01*
X456598Y-500668D01*
X456725Y-500752D01*
Y-500918D01*
X456598Y-501002D01*
G01Y-498752D02*
X456471Y-498668D01*
Y-498502D01*
X456598Y-498418D01*
X456725Y-498502D01*
Y-498668D01*
X456598Y-498752D01*
G01X445411Y-546502D02*
X445518Y-546377D01*
X445598Y-546168D01*
X445651Y-545877D01*
X445598Y-545627D01*
X445491Y-545460D01*
X445305Y-545335D01*
X444585D01*
Y-547835D01*
X445465D01*
X445651Y-547668D01*
X445758Y-547418D01*
X445811Y-547127D01*
X445758Y-546835D01*
X445598Y-546585D01*
X445411Y-546502D01*
X444585D01*
G01X447878Y-547835D02*
Y-546168D01*
G01Y-546460D02*
X447771Y-546293D01*
X447611Y-546210D01*
X447425Y-546168D01*
X447238Y-546252D01*
X447078Y-546418D01*
X446971Y-546668D01*
X446918Y-547002D01*
X446971Y-547335D01*
X447078Y-547585D01*
X447238Y-547752D01*
X447425Y-547835D01*
X447611Y-547793D01*
X447771Y-547668D01*
X447878Y-547502D01*
G01X449198Y-547543D02*
X449331Y-547710D01*
X449518Y-547835D01*
X449678D01*
X449838Y-547752D01*
X449945Y-547627D01*
X449998Y-547460D01*
X449971Y-547210D01*
X449865Y-547085D01*
X449385Y-546835D01*
X449278Y-546543D01*
X449331Y-546335D01*
X449438Y-546210D01*
X449598Y-546168D01*
X449758Y-546210D01*
X449918Y-546335D01*
G01X451398Y-546710D02*
X452251D01*
X452171Y-546418D01*
X452038Y-546252D01*
X451851Y-546168D01*
X451665Y-546210D01*
X451505Y-546335D01*
X451398Y-546627D01*
X451345Y-546877D01*
Y-547127D01*
X451398Y-547377D01*
X451531Y-547627D01*
X451691Y-547793D01*
X451878Y-547835D01*
X452065Y-547752D01*
X452251Y-547502D01*
G01X453518Y-547835D02*
Y-545335D01*
G01Y-546585D02*
X453651Y-546335D01*
X453811Y-546210D01*
X453971Y-546168D01*
X454211Y-546252D01*
X454371Y-546418D01*
X454478Y-546710D01*
Y-547043D01*
X454425Y-547377D01*
X454318Y-547627D01*
X454131Y-547793D01*
X453971Y-547835D01*
X453811Y-547793D01*
X453651Y-547668D01*
X453518Y-547460D01*
G01X456198Y-547835D02*
X456038Y-547793D01*
X455878Y-547627D01*
X455771Y-547335D01*
X455718Y-547002D01*
X455771Y-546668D01*
X455878Y-546377D01*
X456038Y-546210D01*
X456198Y-546168D01*
X456358Y-546210D01*
X456518Y-546377D01*
X456625Y-546668D01*
X456651Y-547002D01*
X456625Y-547335D01*
X456518Y-547627D01*
X456358Y-547793D01*
X456198Y-547835D01*
G01X458878D02*
Y-546168D01*
G01Y-546460D02*
X458771Y-546293D01*
X458611Y-546210D01*
X458425Y-546168D01*
X458238Y-546252D01*
X458078Y-546418D01*
X457971Y-546668D01*
X457918Y-547002D01*
X457971Y-547335D01*
X458078Y-547585D01*
X458238Y-547752D01*
X458425Y-547835D01*
X458611Y-547793D01*
X458771Y-547668D01*
X458878Y-547502D01*
G01X460225Y-547835D02*
Y-546168D01*
G01Y-546502D02*
X460358Y-546335D01*
X460491Y-546210D01*
X460678Y-546168D01*
X460811Y-546210D01*
X460971Y-546335D01*
G01X463278Y-545335D02*
Y-547835D01*
G01Y-547460D02*
X463171Y-547668D01*
X463011Y-547793D01*
X462825Y-547835D01*
X462611Y-547752D01*
X462451Y-547543D01*
X462345Y-547293D01*
X462318Y-547002D01*
X462345Y-546710D01*
X462451Y-546460D01*
X462611Y-546252D01*
X462825Y-546168D01*
X463011Y-546210D01*
X463145Y-546293D01*
X463278Y-546460D01*
G01X466665Y-547835D02*
Y-545335D01*
X467331D01*
X467545Y-545460D01*
X467678Y-545627D01*
X467731Y-545960D01*
X467678Y-546293D01*
X467518Y-546502D01*
X467331Y-546627D01*
X466665D01*
G01X467331D02*
X467731Y-547835D01*
G01X468998Y-546710D02*
X469851D01*
X469771Y-546418D01*
X469638Y-546252D01*
X469451Y-546168D01*
X469265Y-546210D01*
X469105Y-546335D01*
X468998Y-546627D01*
X468945Y-546877D01*
Y-547127D01*
X468998Y-547377D01*
X469131Y-547627D01*
X469291Y-547793D01*
X469478Y-547835D01*
X469665Y-547752D01*
X469851Y-547502D01*
G01X471118Y-546168D02*
X471598Y-547835D01*
X472078Y-546168D01*
G01X473798Y-547918D02*
X473745Y-547877D01*
Y-547793D01*
X473798Y-547752D01*
X473851Y-547793D01*
Y-547877D01*
X473798Y-547918D01*
G01X475545Y-547543D02*
X475731Y-547752D01*
X475945Y-547835D01*
X476158Y-547752D01*
X476345Y-547502D01*
X476478Y-547127D01*
X476531Y-546752D01*
Y-546293D01*
X476478Y-545918D01*
X476345Y-545585D01*
X476185Y-545418D01*
X475998Y-545335D01*
X475785Y-545418D01*
X475625Y-545585D01*
X475518Y-545835D01*
X475465Y-546168D01*
X475518Y-546460D01*
X475651Y-546752D01*
X475811Y-546918D01*
X475998Y-546960D01*
X476211Y-546877D01*
X476371Y-546668D01*
X476531Y-546293D01*
G01X478411Y-546502D02*
X478518Y-546377D01*
X478598Y-546168D01*
X478651Y-545877D01*
X478598Y-545627D01*
X478491Y-545460D01*
X478305Y-545335D01*
X477585D01*
Y-547835D01*
X478465D01*
X478651Y-547668D01*
X478758Y-547418D01*
X478811Y-547127D01*
X478758Y-546835D01*
X478598Y-546585D01*
X478411Y-546502D01*
X477585D01*
G01X452362Y286220D02*
G02X474409I11023J0D01*
G02X452362I-11024J0D01*
G01Y765197D02*
G02X474409I11023J0D01*
G02X452362I-11024J0D01*
G01X481969Y81575D02*
G02X489843I3937J0D01*
G02X481969I-3937J0D01*
G01X526457Y61614D02*
G02X534331I3937J0D01*
G02X526457I-3937J0D01*
G01X530118Y1086654D02*
G02X542717I6299J0D01*
G02X530118I-6299J0D01*
G01X564961Y1066535D02*
G02X582677I8858J0D01*
G02X564961I-8858J0D01*
G01Y1263386D02*
G02X582677I8858J0D01*
G02X564961I-8858J0D01*
G01X584331Y81575D02*
G02X592205I3937J0D01*
G02X584331I-3937J0D01*
G01X588140Y1580079D02*
G02X575640I-6250J0D01*
G02X588140I6250J0D01*
G01Y1606142D02*
G02X575640I-6250J0D01*
G02X588140I6250J0D01*
G01Y1626339D02*
G02X575640I-6250J0D01*
G02X588140I6250J0D01*
G01X616029Y861392D02*
X619670Y864885D01*
G01X615845Y861442D02*
X619403Y864855D01*
G01X615662Y861494D02*
X619135Y864826D01*
G01X615477Y861544D02*
X618867Y864796D01*
G01X615293Y861594D02*
X618629Y864795D01*
G01X615109Y861646D02*
X618420Y864821D01*
G01X614925Y861696D02*
X618210Y864847D01*
G01X614750Y861756D02*
X618000Y864873D01*
G01X614583Y861822D02*
X617790Y864899D01*
G01X614415Y861888D02*
X617596Y864940D01*
G01X614248Y861955D02*
X617428Y865005D01*
G01X614080Y862021D02*
X617259Y865071D01*
G01X613913Y862088D02*
X617091Y865136D01*
G01X613745Y862154D02*
X616922Y865202D01*
G01X613594Y862236D02*
X616753Y865267D01*
G01X613443Y862319D02*
X616600Y865348D01*
G01X613292Y862401D02*
X616461Y865442D01*
G01X613141Y862484D02*
X616323Y865536D01*
G01X612990Y862567D02*
X616184Y865630D01*
G01X612839Y862649D02*
X616045Y865724D01*
G01X612694Y862737D02*
X615906Y865818D01*
G01X612559Y862835D02*
X615772Y865916D01*
G01X612425Y862933D02*
X615657Y866033D01*
G01X612290Y863030D02*
X615542Y866151D01*
G01X612155Y863129D02*
X615428Y866268D01*
G01X612021Y863226D02*
X615314Y866385D01*
G01X611886Y863325D02*
X615199Y866503D01*
G01X611760Y863431D02*
X615085Y866620D01*
G01X611641Y863545D02*
X614982Y866749D01*
G01X611522Y863657D02*
X614889Y866887D01*
G01X616029Y861392D02*
X619670Y864885D01*
G01X615845Y861442D02*
X619403Y864855D01*
G01X615662Y861494D02*
X619135Y864826D01*
G01X615477Y861544D02*
X618867Y864796D01*
G01X615293Y861594D02*
X618629Y864795D01*
G01X615109Y861646D02*
X618420Y864821D01*
G01X614925Y861696D02*
X618210Y864847D01*
G01X614750Y861756D02*
X618000Y864873D01*
G01X614583Y861822D02*
X617790Y864899D01*
G01X614415Y861888D02*
X617596Y864940D01*
G01X614248Y861955D02*
X617428Y865005D01*
G01X614080Y862021D02*
X617259Y865071D01*
G01X613913Y862088D02*
X617091Y865136D01*
G01X613745Y862154D02*
X616922Y865202D01*
G01X613594Y862236D02*
X616753Y865267D01*
G01X613443Y862319D02*
X616600Y865348D01*
G01X613292Y862401D02*
X616461Y865442D01*
G01X613141Y862484D02*
X616323Y865536D01*
G01X612990Y862567D02*
X616184Y865630D01*
G01X612839Y862649D02*
X616045Y865724D01*
G01X612694Y862737D02*
X615906Y865818D01*
G01X612559Y862835D02*
X615772Y865916D01*
G01X612425Y862933D02*
X615657Y866033D01*
G01X612290Y863030D02*
X615542Y866151D01*
G01X612155Y863129D02*
X615428Y866268D01*
G01X612021Y863226D02*
X615314Y866385D01*
G01X611886Y863325D02*
X615199Y866503D01*
G01X611760Y863431D02*
X615085Y866620D01*
G01X611641Y863545D02*
X614982Y866749D01*
G01X611522Y863657D02*
X614889Y866887D01*
G01X619874Y860989D02*
X628754Y869508D01*
G01X619644Y860997D02*
X628790Y869770D01*
G01X619414Y861003D02*
X628799Y870007D01*
G01X619183Y861010D02*
X628809Y870243D01*
G01X618953Y861016D02*
X628819Y870479D01*
G01X618728Y861027D02*
X628829Y870717D01*
G01X618513Y861048D02*
X628839Y870954D01*
G01X618297Y861068D02*
X628849Y871190D01*
G01X618081Y861088D02*
X628845Y871413D01*
G01X617866Y861109D02*
X628836Y871633D01*
G01X617650Y861129D02*
X628821Y871845D01*
G01X617434Y861149D02*
X628800Y872053D01*
G01X617230Y861179D02*
X628780Y872260D01*
G01X628754Y872462D02*
X617029Y861214D01*
G01X616829Y861250D02*
X621283Y865523D01*
G01X616629Y861285D02*
X620716Y865206D01*
G01X616429Y861320D02*
X620346Y865079D01*
G01X616228Y861355D02*
X619975Y864950D01*
G01X619874Y860989D02*
X628754Y869508D01*
G01X619644Y860997D02*
X628790Y869770D01*
G01X619414Y861003D02*
X628799Y870007D01*
G01X619183Y861010D02*
X628809Y870243D01*
G01X618953Y861016D02*
X628819Y870479D01*
G01X618728Y861027D02*
X628829Y870717D01*
G01X618513Y861048D02*
X628839Y870954D01*
G01X618297Y861068D02*
X628849Y871190D01*
G01X618081Y861088D02*
X628845Y871413D01*
G01X617866Y861109D02*
X628836Y871633D01*
G01X617650Y861129D02*
X628821Y871845D01*
G01X617434Y861149D02*
X628800Y872053D01*
G01X617230Y861179D02*
X628780Y872260D01*
G01X628754Y872462D02*
X617029Y861214D01*
G01X616829Y861250D02*
X621283Y865523D01*
G01X616629Y861285D02*
X620716Y865206D01*
G01X616429Y861320D02*
X620346Y865079D01*
G01X616228Y861355D02*
X619975Y864950D01*
G01X611403Y863770D02*
X614797Y867026D01*
G01X611284Y863883D02*
X614704Y867164D01*
G01X611165Y863996D02*
X614611Y867302D01*
G01X611045Y864109D02*
X614519Y867441D01*
G01X610938Y864234D02*
X614426Y867579D01*
G01X610837Y864363D02*
X614352Y867736D01*
G01X610735Y864493D02*
X614282Y867895D01*
G01X610634Y864623D02*
X614211Y868054D01*
G01X610533Y864753D02*
X614140Y868214D01*
G01X610431Y864883D02*
X614069Y868373D01*
G01X610330Y865013D02*
X613998Y868532D01*
G01X610238Y865152D02*
X613937Y868700D01*
G01X610156Y865300D02*
X613890Y868882D01*
G01X610073Y865448D02*
X613843Y869066D01*
G01X609990Y865596D02*
X613797Y869248D01*
G01X609908Y865744D02*
X613751Y869430D01*
G01X609825Y865892D02*
X613704Y869613D01*
G01X609743Y866040D02*
X613666Y869804D01*
G01X609673Y866201D02*
X613650Y870016D01*
G01X609608Y866365D02*
X613633Y870227D01*
G01X609542Y866529D02*
X613617Y870438D01*
G01X609476Y866693D02*
X613601Y870650D01*
G01X609410Y866857D02*
X613584Y870861D01*
G01X609345Y867022D02*
X613603Y871106D01*
G01X609288Y867194D02*
X613629Y871358D01*
G01X609237Y867373D02*
X613656Y871611D01*
G01X609186Y867551D02*
X613682Y871864D01*
G01X609136Y867730D02*
X613709Y872117D01*
G01X609085Y867909D02*
X613796Y872428D01*
G01X609035Y868088D02*
X613892Y872747D01*
G01X608997Y868279D02*
X613989Y873067D01*
G01X608960Y868471D02*
X614134Y873434D01*
G01X608923Y868662D02*
X614370Y873887D01*
G01X608886Y868854D02*
X614683Y874414D01*
G01X620698Y880413D02*
X608850Y869047D01*
G01X620489Y880438D02*
X608825Y869250D01*
G01X620279Y880464D02*
X608801Y869453D01*
G01X611403Y863770D02*
X614797Y867026D01*
G01X611284Y863883D02*
X614704Y867164D01*
G01X611165Y863996D02*
X614611Y867302D01*
G01X611045Y864109D02*
X614519Y867441D01*
G01X610938Y864234D02*
X614426Y867579D01*
G01X610837Y864363D02*
X614352Y867736D01*
G01X610735Y864493D02*
X614282Y867895D01*
G01X610634Y864623D02*
X614211Y868054D01*
G01X610533Y864753D02*
X614140Y868214D01*
G01X610431Y864883D02*
X614069Y868373D01*
G01X610330Y865013D02*
X613998Y868532D01*
G01X610238Y865152D02*
X613937Y868700D01*
G01X610156Y865300D02*
X613890Y868882D01*
G01X610073Y865448D02*
X613843Y869066D01*
G01X609990Y865596D02*
X613797Y869248D01*
G01X609908Y865744D02*
X613751Y869430D01*
G01X609825Y865892D02*
X613704Y869613D01*
G01X609743Y866040D02*
X613666Y869804D01*
G01X609673Y866201D02*
X613650Y870016D01*
G01X609608Y866365D02*
X613633Y870227D01*
G01X609542Y866529D02*
X613617Y870438D01*
G01X609476Y866693D02*
X613601Y870650D01*
G01X609410Y866857D02*
X613584Y870861D01*
G01X609345Y867022D02*
X613603Y871106D01*
G01X609288Y867194D02*
X613629Y871358D01*
G01X609237Y867373D02*
X613656Y871611D01*
G01X609186Y867551D02*
X613682Y871864D01*
G01X609136Y867730D02*
X613709Y872117D01*
G01X609085Y867909D02*
X613796Y872428D01*
G01X609035Y868088D02*
X613892Y872747D01*
G01X608997Y868279D02*
X613989Y873067D01*
G01X608960Y868471D02*
X614134Y873434D01*
G01X608923Y868662D02*
X614370Y873887D01*
G01X608886Y868854D02*
X614683Y874414D01*
G01X620698Y880413D02*
X608850Y869047D01*
G01X620489Y880438D02*
X608825Y869250D01*
G01X620279Y880464D02*
X608801Y869453D01*
G01X620069Y880491D02*
X608776Y869657D01*
G01X619849Y880507D02*
X608750Y869860D01*
G01X619621Y880516D02*
X608737Y870074D01*
G01X619394Y880525D02*
X608723Y870288D01*
G01X619166Y880533D02*
X608709Y870501D01*
G01X618939Y880542D02*
X608702Y870723D01*
G01X618693Y880533D02*
X608698Y870945D01*
G01X618445Y880523D02*
X608703Y871177D01*
G01X618196Y880511D02*
X608714Y871415D01*
G01X617947Y880500D02*
X608725Y871653D01*
G01X617699Y880489D02*
X608736Y871891D01*
G01X617422Y880450D02*
X608770Y872150D01*
G01X617144Y880411D02*
X608807Y872413D01*
G01X616866Y880372D02*
X608844Y872676D01*
G01X616589Y880333D02*
X608898Y872955D01*
G01X616277Y880261D02*
X608968Y873249D01*
G01X615961Y880184D02*
X609038Y873543D01*
G01X615643Y880107D02*
X609134Y873863D01*
G01X615297Y880003D02*
X609248Y874199D01*
G01X614924Y879871D02*
X609366Y874540D01*
G01X614549Y879739D02*
X609545Y874938D01*
G01X620069Y880491D02*
X608776Y869657D01*
G01X619849Y880507D02*
X608750Y869860D01*
G01X619621Y880516D02*
X608737Y870074D01*
G01X619394Y880525D02*
X608723Y870288D01*
G01X619166Y880533D02*
X608709Y870501D01*
G01X618939Y880542D02*
X608702Y870723D01*
G01X618693Y880533D02*
X608698Y870945D01*
G01X618445Y880523D02*
X608703Y871177D01*
G01X618196Y880511D02*
X608714Y871415D01*
G01X617947Y880500D02*
X608725Y871653D01*
G01X617699Y880489D02*
X608736Y871891D01*
G01X617422Y880450D02*
X608770Y872150D01*
G01X617144Y880411D02*
X608807Y872413D01*
G01X616866Y880372D02*
X608844Y872676D01*
G01X616589Y880333D02*
X608898Y872955D01*
G01X616277Y880261D02*
X608968Y873249D01*
G01X615961Y880184D02*
X609038Y873543D01*
G01X615643Y880107D02*
X609134Y873863D01*
G01X615297Y880003D02*
X609248Y874199D01*
G01X614924Y879871D02*
X609366Y874540D01*
G01X614549Y879739D02*
X609545Y874938D01*
G01X614094Y879530D02*
X609726Y875339D01*
G01X613626Y879309D02*
X610009Y875838D01*
G01X612998Y878933D02*
X610389Y876430D01*
G01X614094Y879530D02*
X609726Y875339D01*
G01X613626Y879309D02*
X610009Y875838D01*
G01X612998Y878933D02*
X610389Y876430D01*
G01X623280Y879707D02*
X619969Y876531D01*
G01X623116Y879778D02*
X619796Y876593D01*
G01X622953Y879848D02*
X619591Y876624D01*
G01X622779Y879909D02*
X619379Y876647D01*
G01X622601Y879966D02*
X619167Y876671D01*
G01X622423Y880022D02*
X618956Y876696D01*
G01X622245Y880078D02*
X618743Y876719D01*
G01X622067Y880135D02*
X618481Y876695D01*
G01X621882Y880185D02*
X618212Y876664D01*
G01X621689Y880227D02*
X617942Y876633D01*
G01X621495Y880268D02*
X617632Y876562D01*
G01X621302Y880310D02*
X617263Y876436D01*
G01X621109Y880352D02*
X616895Y876309D01*
G01X620909Y880387D02*
X616301Y875967D01*
G01X623280Y879707D02*
X619969Y876531D01*
G01X623116Y879778D02*
X619796Y876593D01*
G01X622953Y879848D02*
X619591Y876624D01*
G01X622779Y879909D02*
X619379Y876647D01*
G01X622601Y879966D02*
X619167Y876671D01*
G01X622423Y880022D02*
X618956Y876696D01*
G01X622245Y880078D02*
X618743Y876719D01*
G01X622067Y880135D02*
X618481Y876695D01*
G01X621882Y880185D02*
X618212Y876664D01*
G01X621689Y880227D02*
X617942Y876633D01*
G01X621495Y880268D02*
X617632Y876562D01*
G01X621302Y880310D02*
X617263Y876436D01*
G01X621109Y880352D02*
X616895Y876309D01*
G01X620909Y880387D02*
X616301Y875967D01*
G01X628819Y61614D02*
G02X636693I3937J0D01*
G02X628819I-3937J0D01*
G01X626767Y858742D02*
X628267Y860179D01*
G01X626493Y858705D02*
X628130Y860276D01*
G01X626326Y858773D02*
X627994Y860373D01*
G01X626767Y858742D02*
X627091Y858824D01*
G01X626767Y858742D02*
X628267Y860179D01*
G01X626493Y858705D02*
X628130Y860276D01*
G01X626326Y858773D02*
X627994Y860373D01*
G01X626767Y858742D02*
X627091Y858824D01*
G01X636282Y861593D02*
X645222Y870169D01*
G01X636020Y861568D02*
X645270Y870442D01*
G01X635758Y861545D02*
X645318Y870715D01*
G01X635496Y861521D02*
X645366Y870988D01*
G01X635246Y861507D02*
X645414Y871262D01*
G01X635030Y861528D02*
X645462Y871535D01*
G01X634814Y861548D02*
X645510Y871808D01*
G01X634598Y861567D02*
X645558Y872081D01*
G01X645606Y872355D02*
X634382Y861589D01*
G01X634166Y861608D02*
X638848Y866100D01*
G01X633950Y861627D02*
X638387Y865884D01*
G01X633751Y861663D02*
X638063Y865801D01*
G01X633574Y861722D02*
X637751Y865728D01*
G01X633398Y861780D02*
X637496Y865711D01*
G01X633222Y861838D02*
X637242Y865694D01*
G01X633045Y861895D02*
X637003Y865692D01*
G01X632868Y861954D02*
X636781Y865707D01*
G01X632692Y862012D02*
X636560Y865723D01*
G01X632535Y862089D02*
X636359Y865756D01*
G01X632396Y862183D02*
X636173Y865805D01*
G01X632257Y862276D02*
X635987Y865854D01*
G01X632119Y862371D02*
X635824Y865925D01*
G01X631980Y862465D02*
X635676Y866010D01*
G01X631841Y862558D02*
X635527Y866095D01*
G01X629350Y859402D02*
X629358Y859409D01*
G01X631703Y862653D02*
X635403Y866203D01*
G01X629027Y859318D02*
X629222Y859505D01*
G01X628704Y859237D02*
X629085Y859602D01*
G01X631585Y862767D02*
X635294Y866326D01*
G01X631482Y862896D02*
X635186Y866448D01*
G01X628382Y859154D02*
X628948Y859698D01*
G01X631379Y863024D02*
X635095Y866588D01*
G01X628059Y859071D02*
X628812Y859794D01*
G01X627736Y858990D02*
X628675Y859891D01*
G01X631276Y863153D02*
X635025Y866749D01*
G01X631173Y863281D02*
X634955Y866909D01*
G01X627413Y858906D02*
X628539Y859987D01*
G01X627091Y858824D02*
X628403Y860083D01*
G01X631071Y863410D02*
X634892Y867075D01*
G01X630967Y863538D02*
X634859Y867272D01*
G01X630888Y863690D02*
X634826Y867468D01*
G01X626158Y858838D02*
X627858Y860468D01*
G01X625990Y858906D02*
X627722Y860566D01*
G01X625823Y858971D02*
X627585Y860662D01*
G01X625655Y859037D02*
X627449Y860759D01*
G01X625487Y859104D02*
X627313Y860855D01*
G01X625319Y859169D02*
X627176Y860951D01*
G01X625151Y859237D02*
X627040Y861049D01*
G01X624983Y859302D02*
X626904Y861144D01*
G01X624815Y859367D02*
X626768Y861241D01*
G01X624646Y859433D02*
X626632Y861338D01*
G01X624478Y859499D02*
X626495Y861434D01*
G01X624309Y859565D02*
X626359Y861532D01*
G01X624141Y859630D02*
X626223Y861627D01*
G01X623972Y859695D02*
X626087Y861724D01*
G01X623803Y859760D02*
X625951Y861821D01*
G01X623634Y859825D02*
X625815Y861917D01*
G01X623465Y859891D02*
X625679Y862014D01*
G01X623296Y859956D02*
X625543Y862111D01*
G01X623126Y860021D02*
X625406Y862207D01*
G01X622957Y860085D02*
X625270Y862304D01*
G01X622786Y860148D02*
X625134Y862400D01*
G01X624998Y862497D02*
X622616Y860213D01*
G01X622446Y860277D02*
X624862Y862594D01*
G01X622276Y860341D02*
X627349Y865207D01*
G01X622105Y860403D02*
X627639Y865713D01*
G01X621934Y860467D02*
X627888Y866179D01*
G01X621762Y860529D02*
X628035Y866547D01*
G01X621590Y860592D02*
X628181Y866914D01*
G01X621418Y860653D02*
X628309Y867264D01*
G01X621244Y860714D02*
X628386Y867565D01*
G01X621070Y860775D02*
X628463Y867867D01*
G01X620894Y860832D02*
X628540Y868167D01*
G01X620717Y860889D02*
X628609Y868461D01*
G01X620534Y860943D02*
X628645Y868723D01*
G01X620334Y860977D02*
X628682Y868985D01*
G01X620104Y860984D02*
X628718Y869247D01*
G01X627736Y858990D02*
X628059Y859071D01*
G01X629350Y859402D02*
X629027Y859318D01*
G01X627413Y858906D02*
X627736Y858990D01*
G01X627091Y858824D02*
X627413Y858906D01*
G01X628704Y859237D02*
X629027Y859318D01*
G01X628059Y859071D02*
X628382Y859154D01*
G01D02*
X628704Y859237D01*
G01X636282Y861593D02*
X645222Y870169D01*
G01X636020Y861568D02*
X645270Y870442D01*
G01X635758Y861545D02*
X645318Y870715D01*
G01X635496Y861521D02*
X645366Y870988D01*
G01X635246Y861507D02*
X645414Y871262D01*
G01X635030Y861528D02*
X645462Y871535D01*
G01X634814Y861548D02*
X645510Y871808D01*
G01X634598Y861567D02*
X645558Y872081D01*
G01X645606Y872355D02*
X634382Y861589D01*
G01X634166Y861608D02*
X638848Y866100D01*
G01X633950Y861627D02*
X638387Y865884D01*
G01X633751Y861663D02*
X638063Y865801D01*
G01X633574Y861722D02*
X637751Y865728D01*
G01X633398Y861780D02*
X637496Y865711D01*
G01X633222Y861838D02*
X637242Y865694D01*
G01X633045Y861895D02*
X637003Y865692D01*
G01X632868Y861954D02*
X636781Y865707D01*
G01X632692Y862012D02*
X636560Y865723D01*
G01X632535Y862089D02*
X636359Y865756D01*
G01X632396Y862183D02*
X636173Y865805D01*
G01X632257Y862276D02*
X635987Y865854D01*
G01X632119Y862371D02*
X635824Y865925D01*
G01X631980Y862465D02*
X635676Y866010D01*
G01X631841Y862558D02*
X635527Y866095D01*
G01X629350Y859402D02*
X629358Y859409D01*
G01X631703Y862653D02*
X635403Y866203D01*
G01X629027Y859318D02*
X629222Y859505D01*
G01X628704Y859237D02*
X629085Y859602D01*
G01X631585Y862767D02*
X635294Y866326D01*
G01X631482Y862896D02*
X635186Y866448D01*
G01X628382Y859154D02*
X628948Y859698D01*
G01X631379Y863024D02*
X635095Y866588D01*
G01X628059Y859071D02*
X628812Y859794D01*
G01X627736Y858990D02*
X628675Y859891D01*
G01X631276Y863153D02*
X635025Y866749D01*
G01X631173Y863281D02*
X634955Y866909D01*
G01X627413Y858906D02*
X628539Y859987D01*
G01X627091Y858824D02*
X628403Y860083D01*
G01X631071Y863410D02*
X634892Y867075D01*
G01X630967Y863538D02*
X634859Y867272D01*
G01X630888Y863690D02*
X634826Y867468D01*
G01X626158Y858838D02*
X627858Y860468D01*
G01X625990Y858906D02*
X627722Y860566D01*
G01X625823Y858971D02*
X627585Y860662D01*
G01X625655Y859037D02*
X627449Y860759D01*
G01X625487Y859104D02*
X627313Y860855D01*
G01X625319Y859169D02*
X627176Y860951D01*
G01X625151Y859237D02*
X627040Y861049D01*
G01X624983Y859302D02*
X626904Y861144D01*
G01X624815Y859367D02*
X626768Y861241D01*
G01X624646Y859433D02*
X626632Y861338D01*
G01X624478Y859499D02*
X626495Y861434D01*
G01X624309Y859565D02*
X626359Y861532D01*
G01X624141Y859630D02*
X626223Y861627D01*
G01X623972Y859695D02*
X626087Y861724D01*
G01X623803Y859760D02*
X625951Y861821D01*
G01X623634Y859825D02*
X625815Y861917D01*
G01X623465Y859891D02*
X625679Y862014D01*
G01X623296Y859956D02*
X625543Y862111D01*
G01X623126Y860021D02*
X625406Y862207D01*
G01X622957Y860085D02*
X625270Y862304D01*
G01X622786Y860148D02*
X625134Y862400D01*
G01X624998Y862497D02*
X622616Y860213D01*
G01X622446Y860277D02*
X624862Y862594D01*
G01X622276Y860341D02*
X627349Y865207D01*
G01X622105Y860403D02*
X627639Y865713D01*
G01X621934Y860467D02*
X627888Y866179D01*
G01X621762Y860529D02*
X628035Y866547D01*
G01X621590Y860592D02*
X628181Y866914D01*
G01X621418Y860653D02*
X628309Y867264D01*
G01X621244Y860714D02*
X628386Y867565D01*
G01X621070Y860775D02*
X628463Y867867D01*
G01X620894Y860832D02*
X628540Y868167D01*
G01X620717Y860889D02*
X628609Y868461D01*
G01X620534Y860943D02*
X628645Y868723D01*
G01X620334Y860977D02*
X628682Y868985D01*
G01X620104Y860984D02*
X628718Y869247D01*
G01X627736Y858990D02*
X628059Y859071D01*
G01X629350Y859402D02*
X629027Y859318D01*
G01X627413Y858906D02*
X627736Y858990D01*
G01X627091Y858824D02*
X627413Y858906D01*
G01X628704Y859237D02*
X629027Y859318D01*
G01X628059Y859071D02*
X628382Y859154D01*
G01D02*
X628704Y859237D01*
G01X630820Y863851D02*
X634794Y867663D01*
G01X630751Y864012D02*
X634786Y867883D01*
G01X630683Y864174D02*
X634788Y868112D01*
G01X630614Y864335D02*
X634790Y868341D01*
G01X630546Y864497D02*
X634792Y868570D01*
G01X630477Y864658D02*
X634826Y868830D01*
G01X630436Y864846D02*
X634859Y869089D01*
G01X630401Y865040D02*
X634893Y869349D01*
G01X630367Y865234D02*
X634927Y869609D01*
G01X630331Y865427D02*
X634975Y869881D01*
G01X630297Y865621D02*
X635023Y870155D01*
G01X630262Y865815D02*
X635070Y870428D01*
G01X630228Y866009D02*
X635119Y870701D01*
G01X630226Y866235D02*
X635167Y870975D01*
G01X630224Y866461D02*
X635215Y871248D01*
G01X630222Y866686D02*
X635262Y871521D01*
G01X630221Y866912D02*
X635310Y871794D01*
G01X630219Y867137D02*
X635359Y872067D01*
G01X630217Y867363D02*
X635406Y872340D01*
G01X635454Y872614D02*
X630225Y867598D01*
G01X635502Y872887D02*
X630257Y867855D01*
G01X635551Y873160D02*
X630288Y868112D01*
G01X635598Y873434D02*
X630319Y868369D01*
G01X635646Y873707D02*
X630350Y868627D01*
G01X635694Y873980D02*
X630382Y868884D01*
G01X635742Y874253D02*
X630413Y869141D01*
G01X635790Y874526D02*
X630456Y869409D01*
G01X628721Y872658D02*
X622782Y866960D01*
G01X628689Y872854D02*
X623143Y867535D01*
G01X628655Y873050D02*
X623323Y867934D01*
G01X628618Y873241D02*
X623503Y868334D01*
G01X628572Y873424D02*
X623591Y868646D01*
G01X628527Y873607D02*
X623667Y868945D01*
G01X628480Y873790D02*
X623743Y869245D01*
G01X630504Y869683D02*
X630456Y869409D01*
G01X630820Y863851D02*
X634794Y867663D01*
G01X630751Y864012D02*
X634786Y867883D01*
G01X630683Y864174D02*
X634788Y868112D01*
G01X630614Y864335D02*
X634790Y868341D01*
G01X630546Y864497D02*
X634792Y868570D01*
G01X630477Y864658D02*
X634826Y868830D01*
G01X630436Y864846D02*
X634859Y869089D01*
G01X630401Y865040D02*
X634893Y869349D01*
G01X630367Y865234D02*
X634927Y869609D01*
G01X630331Y865427D02*
X634975Y869881D01*
G01X630297Y865621D02*
X635023Y870155D01*
G01X630262Y865815D02*
X635070Y870428D01*
G01X630228Y866009D02*
X635119Y870701D01*
G01X630226Y866235D02*
X635167Y870975D01*
G01X630224Y866461D02*
X635215Y871248D01*
G01X630222Y866686D02*
X635262Y871521D01*
G01X630221Y866912D02*
X635310Y871794D01*
G01X630219Y867137D02*
X635359Y872067D01*
G01X630217Y867363D02*
X635406Y872340D01*
G01X635454Y872614D02*
X630225Y867598D01*
G01X635502Y872887D02*
X630257Y867855D01*
G01X635551Y873160D02*
X630288Y868112D01*
G01X635598Y873434D02*
X630319Y868369D01*
G01X635646Y873707D02*
X630350Y868627D01*
G01X635694Y873980D02*
X630382Y868884D01*
G01X635742Y874253D02*
X630413Y869141D01*
G01X635790Y874526D02*
X630456Y869409D01*
G01X628721Y872658D02*
X622782Y866960D01*
G01X628689Y872854D02*
X623143Y867535D01*
G01X628655Y873050D02*
X623323Y867934D01*
G01X628618Y873241D02*
X623503Y868334D01*
G01X628572Y873424D02*
X623591Y868646D01*
G01X628527Y873607D02*
X623667Y868945D01*
G01X628480Y873790D02*
X623743Y869245D01*
G01X630504Y869683D02*
X630456Y869409D01*
G01X635838Y874799D02*
X630504Y869683D01*
G01X635886Y875073D02*
X630552Y869956D01*
G01X635934Y875346D02*
X630600Y870229D01*
G01X635982Y875619D02*
X630648Y870503D01*
G01X636030Y875893D02*
X630696Y870776D01*
G01X636078Y876165D02*
X630744Y871049D01*
G01X636126Y876439D02*
X630792Y871322D01*
G01X636174Y876712D02*
X630840Y871595D01*
G01X636222Y876986D02*
X630887Y871868D01*
G01X636269Y877258D02*
X630936Y872142D01*
G01X636318Y877531D02*
X630984Y872415D01*
G01X636366Y877805D02*
X631031Y872688D01*
G01X636413Y878078D02*
X631079Y872962D01*
G01X636461Y878352D02*
X631128Y873234D01*
G01X636509Y878624D02*
X631176Y873508D01*
G01X636394Y878741D02*
X631223Y873781D01*
G01X636157Y878741D02*
X631271Y874055D01*
G01X635920Y878741D02*
X631319Y874327D01*
G01X635683Y878741D02*
X631367Y874600D01*
G01X635446Y878741D02*
X631415Y874874D01*
G01X628434Y873973D02*
X623806Y869533D01*
G01X628382Y874150D02*
X623826Y869780D01*
G01X628322Y874320D02*
X623846Y870026D01*
G01X628263Y874490D02*
X623866Y870273D01*
G01X628202Y874660D02*
X623886Y870519D01*
G01X628143Y874830D02*
X623890Y870750D01*
G01X628083Y874999D02*
X623872Y870960D01*
G01X628010Y875157D02*
X623855Y871171D01*
G01X627935Y875312D02*
X623837Y871381D01*
G01X627860Y875467D02*
X623819Y871592D01*
G01X627785Y875623D02*
X623802Y871802D01*
G01X627711Y875778D02*
X623771Y871999D01*
G01X627635Y875933D02*
X623723Y872181D01*
G01X627549Y876078D02*
X623676Y872363D01*
G01X627458Y876218D02*
X623629Y872545D01*
G01X627367Y876357D02*
X623581Y872726D01*
G01X627275Y876497D02*
X623534Y872907D01*
G01X627184Y876637D02*
X623484Y873087D01*
G01X627092Y876776D02*
X623411Y873244D01*
G01X627001Y876915D02*
X623339Y873402D01*
G01X626893Y877039D02*
X623266Y873560D01*
G01X626783Y877161D02*
X623193Y873717D01*
G01X626674Y877283D02*
X623120Y873874D01*
G01X626564Y877405D02*
X623048Y874032D01*
G01X626454Y877527D02*
X622962Y874177D01*
G01X626344Y877648D02*
X622866Y874312D01*
G01X626234Y877770D02*
X622770Y874447D01*
G01X626114Y877882D02*
X622674Y874582D01*
G01X625989Y877990D02*
X622578Y874717D01*
G01X625863Y878097D02*
X622482Y874852D01*
G01X625739Y878204D02*
X622386Y874988D01*
G01X635119Y870701D02*
X635167Y870975D01*
G01X634975Y869881D02*
X635023Y870155D01*
G01X635167Y870975D02*
X635215Y871248D01*
G01X634927Y869609D02*
X634975Y869881D01*
G01X635070Y870428D02*
X635119Y870701D01*
G01X635310Y871794D02*
X635359Y872067D01*
G01X635262Y871521D02*
X635310Y871794D01*
G01X635215Y871248D02*
X635262Y871521D01*
G01X635406Y872340D02*
X635454Y872614D01*
G01D02*
X635502Y872887D01*
G01X635790Y874526D02*
X635838Y874799D01*
G01X635502Y872887D02*
X635551Y873160D01*
G01X635742Y874253D02*
X635790Y874526D01*
G01X635838Y874799D02*
X635886Y875073D01*
G01X635694Y873980D02*
X635742Y874253D01*
G01X635551Y873160D02*
X635598Y873434D01*
G01X635646Y873707D02*
X635694Y873980D01*
G01X635598Y873434D02*
X635646Y873707D01*
G01X635023Y870155D02*
X635070Y870428D01*
G01X630744Y871049D02*
X630696Y870776D01*
G01X630887Y871868D02*
X630840Y871595D01*
G01D02*
X630792Y871322D01*
G01X631031Y872688D02*
X630984Y872415D01*
G01D02*
X630936Y872142D01*
G01D02*
X630887Y871868D01*
G01X630792Y871322D02*
X630744Y871049D01*
G01X630696Y870776D02*
X630648Y870503D01*
G01D02*
X630600Y870229D01*
G01X631415Y874874D02*
X631367Y874600D01*
G01X631079Y872962D02*
X631031Y872688D01*
G01X631367Y874600D02*
X631319Y874327D01*
G01X631463Y875147D02*
X631415Y874874D01*
G01X631319Y874327D02*
X631271Y874055D01*
G01X631128Y873234D02*
X631079Y872962D01*
G01X631176Y873508D02*
X631128Y873234D01*
G01X631271Y874055D02*
X631223Y873781D01*
G01D02*
X631176Y873508D01*
G01X630600Y870229D02*
X630552Y869956D01*
G01X635406Y872340D02*
X635359Y872067D01*
G01X630552Y869956D02*
X630504Y869683D01*
G01X635838Y874799D02*
X630504Y869683D01*
G01X635886Y875073D02*
X630552Y869956D01*
G01X635934Y875346D02*
X630600Y870229D01*
G01X635982Y875619D02*
X630648Y870503D01*
G01X636030Y875893D02*
X630696Y870776D01*
G01X636078Y876165D02*
X630744Y871049D01*
G01X636126Y876439D02*
X630792Y871322D01*
G01X636174Y876712D02*
X630840Y871595D01*
G01X636222Y876986D02*
X630887Y871868D01*
G01X636269Y877258D02*
X630936Y872142D01*
G01X636318Y877531D02*
X630984Y872415D01*
G01X636366Y877805D02*
X631031Y872688D01*
G01X636413Y878078D02*
X631079Y872962D01*
G01X636461Y878352D02*
X631128Y873234D01*
G01X636509Y878624D02*
X631176Y873508D01*
G01X636394Y878741D02*
X631223Y873781D01*
G01X636157Y878741D02*
X631271Y874055D01*
G01X635920Y878741D02*
X631319Y874327D01*
G01X635683Y878741D02*
X631367Y874600D01*
G01X635446Y878741D02*
X631415Y874874D01*
G01X628434Y873973D02*
X623806Y869533D01*
G01X628382Y874150D02*
X623826Y869780D01*
G01X628322Y874320D02*
X623846Y870026D01*
G01X628263Y874490D02*
X623866Y870273D01*
G01X628202Y874660D02*
X623886Y870519D01*
G01X628143Y874830D02*
X623890Y870750D01*
G01X628083Y874999D02*
X623872Y870960D01*
G01X628010Y875157D02*
X623855Y871171D01*
G01X627935Y875312D02*
X623837Y871381D01*
G01X627860Y875467D02*
X623819Y871592D01*
G01X627785Y875623D02*
X623802Y871802D01*
G01X627711Y875778D02*
X623771Y871999D01*
G01X627635Y875933D02*
X623723Y872181D01*
G01X627549Y876078D02*
X623676Y872363D01*
G01X627458Y876218D02*
X623629Y872545D01*
G01X627367Y876357D02*
X623581Y872726D01*
G01X627275Y876497D02*
X623534Y872907D01*
G01X627184Y876637D02*
X623484Y873087D01*
G01X627092Y876776D02*
X623411Y873244D01*
G01X627001Y876915D02*
X623339Y873402D01*
G01X626893Y877039D02*
X623266Y873560D01*
G01X626783Y877161D02*
X623193Y873717D01*
G01X626674Y877283D02*
X623120Y873874D01*
G01X626564Y877405D02*
X623048Y874032D01*
G01X626454Y877527D02*
X622962Y874177D01*
G01X626344Y877648D02*
X622866Y874312D01*
G01X626234Y877770D02*
X622770Y874447D01*
G01X626114Y877882D02*
X622674Y874582D01*
G01X625989Y877990D02*
X622578Y874717D01*
G01X625863Y878097D02*
X622482Y874852D01*
G01X625739Y878204D02*
X622386Y874988D01*
G01X635119Y870701D02*
X635167Y870975D01*
G01X634975Y869881D02*
X635023Y870155D01*
G01X635167Y870975D02*
X635215Y871248D01*
G01X634927Y869609D02*
X634975Y869881D01*
G01X635070Y870428D02*
X635119Y870701D01*
G01X635310Y871794D02*
X635359Y872067D01*
G01X635262Y871521D02*
X635310Y871794D01*
G01X635215Y871248D02*
X635262Y871521D01*
G01X635406Y872340D02*
X635454Y872614D01*
G01D02*
X635502Y872887D01*
G01X635790Y874526D02*
X635838Y874799D01*
G01X635502Y872887D02*
X635551Y873160D01*
G01X635742Y874253D02*
X635790Y874526D01*
G01X635838Y874799D02*
X635886Y875073D01*
G01X635694Y873980D02*
X635742Y874253D01*
G01X635551Y873160D02*
X635598Y873434D01*
G01X635646Y873707D02*
X635694Y873980D01*
G01X635598Y873434D02*
X635646Y873707D01*
G01X635023Y870155D02*
X635070Y870428D01*
G01X630744Y871049D02*
X630696Y870776D01*
G01X630887Y871868D02*
X630840Y871595D01*
G01D02*
X630792Y871322D01*
G01X631031Y872688D02*
X630984Y872415D01*
G01D02*
X630936Y872142D01*
G01D02*
X630887Y871868D01*
G01X630792Y871322D02*
X630744Y871049D01*
G01X630696Y870776D02*
X630648Y870503D01*
G01D02*
X630600Y870229D01*
G01X631415Y874874D02*
X631367Y874600D01*
G01X631079Y872962D02*
X631031Y872688D01*
G01X631367Y874600D02*
X631319Y874327D01*
G01X631463Y875147D02*
X631415Y874874D01*
G01X631319Y874327D02*
X631271Y874055D01*
G01X631128Y873234D02*
X631079Y872962D01*
G01X631176Y873508D02*
X631128Y873234D01*
G01X631271Y874055D02*
X631223Y873781D01*
G01D02*
X631176Y873508D01*
G01X630600Y870229D02*
X630552Y869956D01*
G01X635406Y872340D02*
X635359Y872067D01*
G01X630552Y869956D02*
X630504Y869683D01*
G01X635209Y878741D02*
X631463Y875147D01*
G01X634973Y878741D02*
X631511Y875421D01*
G01X634736Y878741D02*
X631559Y875693D01*
G01X634499Y878741D02*
X631607Y875967D01*
G01X634262Y878741D02*
X631655Y876240D01*
G01X634025Y878741D02*
X631703Y876513D01*
G01X633789Y878741D02*
X631751Y876786D01*
G01X633551Y878741D02*
X631799Y877060D01*
G01X633315Y878741D02*
X631847Y877333D01*
G01X633078Y878741D02*
X631895Y877606D01*
G01X632841Y878741D02*
X631943Y877879D01*
G01X632604Y878741D02*
X631991Y878152D01*
G01X632367Y878741D02*
X632039Y878426D01*
G01X632131Y878741D02*
X632086Y878699D01*
G01X625613Y878310D02*
X622268Y875102D01*
G01X625488Y878417D02*
X622149Y875214D01*
G01X625355Y878518D02*
X622030Y875328D01*
G01X625218Y878613D02*
X621910Y875440D01*
G01X625081Y878708D02*
X621792Y875554D01*
G01X624944Y878804D02*
X621672Y875666D01*
G01X624806Y878900D02*
X621540Y875766D01*
G01X624669Y878995D02*
X621396Y875856D01*
G01X624522Y879081D02*
X621252Y875944D01*
G01X624372Y879165D02*
X621108Y876034D01*
G01X624222Y879248D02*
X620964Y876123D01*
G01X624072Y879332D02*
X620819Y876211D01*
G01X623922Y879415D02*
X620663Y876289D01*
G01X623771Y879496D02*
X620490Y876350D01*
G01X623606Y879567D02*
X620316Y876410D01*
G01X623443Y879637D02*
X620142Y876471D01*
G01X635446Y878741D02*
X635209D01*
G01D02*
X634973D01*
G01X634499D02*
X634262D01*
G01X634973D02*
X634736D01*
G01D02*
X634499D01*
G01X636394D02*
X636157D01*
G01D02*
X635920D01*
G01X635683D02*
X635446D01*
G01X635920D02*
X635683D01*
G01X632604D02*
X632367D01*
G01X634262D02*
X634025D01*
G01X632367D02*
X632131D01*
G01X632841D02*
X632604D01*
G01X634025D02*
X633789D01*
G01D02*
X633551D01*
G01D02*
X633315D01*
G01X633078D02*
X632841D01*
G01X633315D02*
X633078D01*
G01X635886Y875073D02*
X635934Y875346D01*
G01D02*
X635982Y875619D01*
G01X636318Y877531D02*
X636366Y877805D01*
G01X636269Y877258D02*
X636318Y877531D01*
G01X636078Y876165D02*
X636126Y876439D01*
G01X635982Y875619D02*
X636030Y875893D01*
G01D02*
X636078Y876165D01*
G01X636174Y876712D02*
X636222Y876986D01*
G01D02*
X636269Y877258D01*
G01X636126Y876439D02*
X636174Y876712D01*
G01X631847Y877333D02*
X631895Y877606D01*
G01X631943Y877879D02*
X631991Y878152D01*
G01X631895Y877606D02*
X631943Y877879D01*
G01X631799Y877060D02*
X631847Y877333D01*
G01X631991Y878152D02*
X632039Y878426D01*
G01X631655Y876240D02*
X631607Y875967D01*
G01X631751Y876786D02*
X631799Y877060D01*
G01X631703Y876513D02*
X631751Y876786D01*
G01X631655Y876240D02*
X631703Y876513D01*
G01X632094Y878741D02*
X632086Y878699D01*
G01X632131Y878741D02*
X632094D01*
G01X631607Y875967D02*
X631559Y875693D01*
G01X632039Y878426D02*
X632086Y878699D01*
G01X631559Y875693D02*
X631511Y875421D01*
G01D02*
X631463Y875147D01*
G01X635209Y878741D02*
X631463Y875147D01*
G01X634973Y878741D02*
X631511Y875421D01*
G01X634736Y878741D02*
X631559Y875693D01*
G01X634499Y878741D02*
X631607Y875967D01*
G01X634262Y878741D02*
X631655Y876240D01*
G01X634025Y878741D02*
X631703Y876513D01*
G01X633789Y878741D02*
X631751Y876786D01*
G01X633551Y878741D02*
X631799Y877060D01*
G01X633315Y878741D02*
X631847Y877333D01*
G01X633078Y878741D02*
X631895Y877606D01*
G01X632841Y878741D02*
X631943Y877879D01*
G01X632604Y878741D02*
X631991Y878152D01*
G01X632367Y878741D02*
X632039Y878426D01*
G01X632131Y878741D02*
X632086Y878699D01*
G01X625613Y878310D02*
X622268Y875102D01*
G01X625488Y878417D02*
X622149Y875214D01*
G01X625355Y878518D02*
X622030Y875328D01*
G01X625218Y878613D02*
X621910Y875440D01*
G01X625081Y878708D02*
X621792Y875554D01*
G01X624944Y878804D02*
X621672Y875666D01*
G01X624806Y878900D02*
X621540Y875766D01*
G01X624669Y878995D02*
X621396Y875856D01*
G01X624522Y879081D02*
X621252Y875944D01*
G01X624372Y879165D02*
X621108Y876034D01*
G01X624222Y879248D02*
X620964Y876123D01*
G01X624072Y879332D02*
X620819Y876211D01*
G01X623922Y879415D02*
X620663Y876289D01*
G01X623771Y879496D02*
X620490Y876350D01*
G01X623606Y879567D02*
X620316Y876410D01*
G01X623443Y879637D02*
X620142Y876471D01*
G01X635446Y878741D02*
X635209D01*
G01D02*
X634973D01*
G01X634499D02*
X634262D01*
G01X634973D02*
X634736D01*
G01D02*
X634499D01*
G01X636394D02*
X636157D01*
G01D02*
X635920D01*
G01X635683D02*
X635446D01*
G01X635920D02*
X635683D01*
G01X632604D02*
X632367D01*
G01X634262D02*
X634025D01*
G01X632367D02*
X632131D01*
G01X632841D02*
X632604D01*
G01X634025D02*
X633789D01*
G01D02*
X633551D01*
G01D02*
X633315D01*
G01X633078D02*
X632841D01*
G01X633315D02*
X633078D01*
G01X635886Y875073D02*
X635934Y875346D01*
G01D02*
X635982Y875619D01*
G01X636318Y877531D02*
X636366Y877805D01*
G01X636269Y877258D02*
X636318Y877531D01*
G01X636078Y876165D02*
X636126Y876439D01*
G01X635982Y875619D02*
X636030Y875893D01*
G01D02*
X636078Y876165D01*
G01X636174Y876712D02*
X636222Y876986D01*
G01D02*
X636269Y877258D01*
G01X636126Y876439D02*
X636174Y876712D01*
G01X631847Y877333D02*
X631895Y877606D01*
G01X631943Y877879D02*
X631991Y878152D01*
G01X631895Y877606D02*
X631943Y877879D01*
G01X631799Y877060D02*
X631847Y877333D01*
G01X631991Y878152D02*
X632039Y878426D01*
G01X631655Y876240D02*
X631607Y875967D01*
G01X631751Y876786D02*
X631799Y877060D01*
G01X631703Y876513D02*
X631751Y876786D01*
G01X631655Y876240D02*
X631703Y876513D01*
G01X632094Y878741D02*
X632086Y878699D01*
G01X632131Y878741D02*
X632094D01*
G01X631607Y875967D02*
X631559Y875693D01*
G01X632039Y878426D02*
X632086Y878699D01*
G01X631559Y875693D02*
X631511Y875421D01*
G01D02*
X631463Y875147D01*
G01X650650Y23622D02*
G02X672697I11023J0D01*
G02X650650I-11024J0D01*
G01X652558Y861529D02*
X662144Y870724D01*
G01X652294Y861502D02*
X662192Y870998D01*
G01X652067Y861511D02*
X662239Y871270D01*
G01X651839Y861521D02*
X662288Y871543D01*
G01X662336Y871817D02*
X651618Y861536D01*
G01X651407Y861562D02*
X655965Y865933D01*
G01X651197Y861586D02*
X655444Y865660D01*
G01X650997Y861621D02*
X655062Y865521D01*
G01X650802Y861662D02*
X654688Y865390D01*
G01X650607Y861701D02*
X654417Y865357D01*
G01X650424Y861754D02*
X654146Y865323D01*
G01X650244Y861808D02*
X653875Y865290D01*
G01X650063Y861863D02*
X653614Y865268D01*
G01X649895Y861928D02*
X653394Y865284D01*
G01X649729Y861996D02*
X653174Y865300D01*
G01X649563Y862063D02*
X652964Y865325D01*
G01X649408Y862142D02*
X652777Y865374D01*
G01X649256Y862223D02*
X652591Y865423D01*
G01X649104Y862305D02*
X652420Y865486D01*
G01X648961Y862395D02*
X652267Y865566D01*
G01X648823Y862489D02*
X652114Y865647D01*
G01X648685Y862584D02*
X651987Y865753D01*
G01X648554Y862686D02*
X651867Y865865D01*
G01X648430Y862794D02*
X651757Y865986D01*
G01X648306Y862902D02*
X651671Y866130D01*
G01X648186Y863015D02*
X651584Y866275D01*
G01X648076Y863137D02*
X651531Y866450D01*
G01X647967Y863259D02*
X651479Y866628D01*
G01X647859Y863382D02*
X651457Y866834D01*
G01X647765Y863520D02*
X651442Y867047D01*
G01X647671Y863657D02*
X651462Y867293D01*
G01X643662Y861856D02*
X643781Y861970D01*
G01X643425Y861856D02*
X643830Y862244D01*
G01X643188Y861856D02*
X643877Y862517D01*
G01X642951Y861856D02*
X643925Y862790D01*
G01X642715Y861856D02*
X643973Y863063D01*
G01X642477Y861856D02*
X644022Y863337D01*
G01X642241Y861856D02*
X644070Y863610D01*
G01X642004Y861856D02*
X644117Y863883D01*
G01X641767Y861856D02*
X644165Y864156D01*
G01X641531Y861856D02*
X644213Y864430D01*
G01X641293Y861856D02*
X644262Y864704D01*
G01X641057Y861856D02*
X644310Y864976D01*
G01X640820Y861856D02*
X644357Y865249D01*
G01X640583Y861856D02*
X644405Y865523D01*
G01X640346Y861856D02*
X644454Y865796D01*
G01X640109Y861856D02*
X644502Y866069D01*
G01X639873Y861856D02*
X644550Y866343D01*
G01X639636Y861856D02*
X644597Y866616D01*
G01X639398Y861856D02*
X644645Y866889D01*
G01X639356Y862042D02*
X644694Y867163D01*
G01X639404Y862316D02*
X644742Y867436D01*
G01X639451Y862588D02*
X644790Y867709D01*
G01X639500Y862862D02*
X644837Y867982D01*
G01X638996Y862605D02*
X644886Y868256D01*
G01X638391Y862252D02*
X644934Y868528D01*
G01X637921Y862029D02*
X644982Y868802D01*
G01X637534Y861884D02*
X645030Y869076D01*
G01X637201Y861792D02*
X645077Y869349D01*
G01X636867Y861700D02*
X645126Y869622D01*
G01X636544Y861617D02*
X645174Y869896D01*
G01X643425Y861856D02*
X643662D01*
G01X642477D02*
X642715D01*
G01D02*
X642951D01*
G01X642004D02*
X642241D01*
G01D02*
X642477D01*
G01X643188D02*
X643425D01*
G01X642951D02*
X643188D01*
G01X641767D02*
X642004D01*
G01X639636D02*
X639873D01*
G01X641531D02*
X641767D01*
G01X640109D02*
X640346D01*
G01D02*
X640583D01*
G01X639873D02*
X640109D01*
G01X641293D02*
X641531D01*
G01X639398D02*
X639636D01*
G01X641057D02*
X641293D01*
G01X640820D02*
X641057D01*
G01X640583D02*
X640820D01*
G01X639500Y862862D02*
X639451Y862588D01*
G01X639404Y862316D02*
X639356Y862042D01*
G01X639451Y862588D02*
X639404Y862316D01*
G01X639324Y861856D02*
X639398D01*
G01X639356Y862042D02*
X639324Y861856D01*
G01X643925Y862790D02*
X643877Y862517D01*
G01D02*
X643830Y862244D01*
G01X643973Y863063D02*
X643925Y862790D01*
G01X643830Y862244D02*
X643781Y861970D01*
G01X643761Y861856D02*
X643781Y861970D01*
G01X643662Y861856D02*
X643761D01*
G01X644117Y863883D02*
X644070Y863610D01*
G01D02*
X644022Y863337D01*
G01D02*
X643973Y863063D01*
G01X652558Y861529D02*
X662144Y870724D01*
G01X652294Y861502D02*
X662192Y870998D01*
G01X652067Y861511D02*
X662239Y871270D01*
G01X651839Y861521D02*
X662288Y871543D01*
G01X662336Y871817D02*
X651618Y861536D01*
G01X651407Y861562D02*
X655965Y865933D01*
G01X651197Y861586D02*
X655444Y865660D01*
G01X650997Y861621D02*
X655062Y865521D01*
G01X650802Y861662D02*
X654688Y865390D01*
G01X650607Y861701D02*
X654417Y865357D01*
G01X650424Y861754D02*
X654146Y865323D01*
G01X650244Y861808D02*
X653875Y865290D01*
G01X650063Y861863D02*
X653614Y865268D01*
G01X649895Y861928D02*
X653394Y865284D01*
G01X649729Y861996D02*
X653174Y865300D01*
G01X649563Y862063D02*
X652964Y865325D01*
G01X649408Y862142D02*
X652777Y865374D01*
G01X649256Y862223D02*
X652591Y865423D01*
G01X649104Y862305D02*
X652420Y865486D01*
G01X648961Y862395D02*
X652267Y865566D01*
G01X648823Y862489D02*
X652114Y865647D01*
G01X648685Y862584D02*
X651987Y865753D01*
G01X648554Y862686D02*
X651867Y865865D01*
G01X648430Y862794D02*
X651757Y865986D01*
G01X648306Y862902D02*
X651671Y866130D01*
G01X648186Y863015D02*
X651584Y866275D01*
G01X648076Y863137D02*
X651531Y866450D01*
G01X647967Y863259D02*
X651479Y866628D01*
G01X647859Y863382D02*
X651457Y866834D01*
G01X647765Y863520D02*
X651442Y867047D01*
G01X647671Y863657D02*
X651462Y867293D01*
G01X643662Y861856D02*
X643781Y861970D01*
G01X643425Y861856D02*
X643830Y862244D01*
G01X643188Y861856D02*
X643877Y862517D01*
G01X642951Y861856D02*
X643925Y862790D01*
G01X642715Y861856D02*
X643973Y863063D01*
G01X642477Y861856D02*
X644022Y863337D01*
G01X642241Y861856D02*
X644070Y863610D01*
G01X642004Y861856D02*
X644117Y863883D01*
G01X641767Y861856D02*
X644165Y864156D01*
G01X641531Y861856D02*
X644213Y864430D01*
G01X641293Y861856D02*
X644262Y864704D01*
G01X641057Y861856D02*
X644310Y864976D01*
G01X640820Y861856D02*
X644357Y865249D01*
G01X640583Y861856D02*
X644405Y865523D01*
G01X640346Y861856D02*
X644454Y865796D01*
G01X640109Y861856D02*
X644502Y866069D01*
G01X639873Y861856D02*
X644550Y866343D01*
G01X639636Y861856D02*
X644597Y866616D01*
G01X639398Y861856D02*
X644645Y866889D01*
G01X639356Y862042D02*
X644694Y867163D01*
G01X639404Y862316D02*
X644742Y867436D01*
G01X639451Y862588D02*
X644790Y867709D01*
G01X639500Y862862D02*
X644837Y867982D01*
G01X638996Y862605D02*
X644886Y868256D01*
G01X638391Y862252D02*
X644934Y868528D01*
G01X637921Y862029D02*
X644982Y868802D01*
G01X637534Y861884D02*
X645030Y869076D01*
G01X637201Y861792D02*
X645077Y869349D01*
G01X636867Y861700D02*
X645126Y869622D01*
G01X636544Y861617D02*
X645174Y869896D01*
G01X643425Y861856D02*
X643662D01*
G01X642477D02*
X642715D01*
G01D02*
X642951D01*
G01X642004D02*
X642241D01*
G01D02*
X642477D01*
G01X643188D02*
X643425D01*
G01X642951D02*
X643188D01*
G01X641767D02*
X642004D01*
G01X639636D02*
X639873D01*
G01X641531D02*
X641767D01*
G01X640109D02*
X640346D01*
G01D02*
X640583D01*
G01X639873D02*
X640109D01*
G01X641293D02*
X641531D01*
G01X639398D02*
X639636D01*
G01X641057D02*
X641293D01*
G01X640820D02*
X641057D01*
G01X640583D02*
X640820D01*
G01X639500Y862862D02*
X639451Y862588D01*
G01X639404Y862316D02*
X639356Y862042D01*
G01X639451Y862588D02*
X639404Y862316D01*
G01X639324Y861856D02*
X639398D01*
G01X639356Y862042D02*
X639324Y861856D01*
G01X643925Y862790D02*
X643877Y862517D01*
G01D02*
X643830Y862244D01*
G01X643973Y863063D02*
X643925Y862790D01*
G01X643830Y862244D02*
X643781Y861970D01*
G01X643761Y861856D02*
X643781Y861970D01*
G01X643662Y861856D02*
X643761D01*
G01X644117Y863883D02*
X644070Y863610D01*
G01D02*
X644022Y863337D01*
G01D02*
X643973Y863063D01*
G01X647577Y863794D02*
X651498Y867555D01*
G01X647497Y863944D02*
X651623Y867902D01*
G01X647419Y864097D02*
X651749Y868250D01*
G01X647342Y864250D02*
X656431Y872968D01*
G01X647275Y864413D02*
X656231Y873004D01*
G01X647216Y864583D02*
X656030Y873038D01*
G01X647156Y864753D02*
X655818Y873063D01*
G01X647105Y864931D02*
X655593Y873074D01*
G01X647064Y865119D02*
X655369Y873086D01*
G01X647024Y865308D02*
X655144Y873098D01*
G01X646989Y865502D02*
X654920Y873110D01*
G01X646971Y865711D02*
X654672Y873099D01*
G01X646952Y865921D02*
X654419Y873084D01*
G01X646938Y866135D02*
X654166Y873068D01*
G01X646944Y866367D02*
X653912Y873052D01*
G01X646949Y866600D02*
X653659Y873037D01*
G01X646961Y866838D02*
X653395Y873010D01*
G01X646993Y867097D02*
X653097Y872952D01*
G01X647027Y867356D02*
X652799Y872894D01*
G01X647079Y867633D02*
X652502Y872835D01*
G01X647166Y867944D02*
X652204Y872777D01*
G01X647253Y868254D02*
X651849Y872663D01*
G01X647341Y868566D02*
X651474Y872531D01*
G01X647450Y868898D02*
X651100Y872399D01*
G01X647688Y869353D02*
X650649Y872193D01*
G01X639780Y866993D02*
X645654Y872628D01*
G01X640041Y867470D02*
X645702Y872901D01*
G01X640219Y867869D02*
X645750Y873175D01*
G01X640340Y868212D02*
X645798Y873449D01*
G01X645846Y873721D02*
X640452Y868547D01*
G01X645894Y873994D02*
X640517Y868836D01*
G01X645942Y874268D02*
X640583Y869127D01*
G01X645990Y874541D02*
X640648Y869417D01*
G01X644837Y867982D02*
X644886Y868256D01*
G01X644165Y864156D02*
X644117Y863883D01*
G01X644213Y864430D02*
X644165Y864156D01*
G01X644934Y868528D02*
X644982Y868802D01*
G01X644742Y867436D02*
X644790Y867709D01*
G01D02*
X644837Y867982D01*
G01X644886Y868256D02*
X644934Y868528D01*
G01X644982Y868802D02*
X645030Y869076D01*
G01D02*
X645077Y869349D01*
G01D02*
X645126Y869622D01*
G01X644357Y865249D02*
X644310Y864976D01*
G01X644454Y865796D02*
X644405Y865523D01*
G01D02*
X644357Y865249D01*
G01X644262Y864704D02*
X644213Y864430D01*
G01X644310Y864976D02*
X644262Y864704D01*
G01X644502Y866069D02*
X644454Y865796D01*
G01X644645Y866889D02*
X644597Y866616D01*
G01X644645Y866889D02*
X644694Y867163D01*
G01X644550Y866343D02*
X644502Y866069D01*
G01X644597Y866616D02*
X644550Y866343D01*
G01X644694Y867163D02*
X644742Y867436D01*
G01X647577Y863794D02*
X651498Y867555D01*
G01X647497Y863944D02*
X651623Y867902D01*
G01X647419Y864097D02*
X651749Y868250D01*
G01X647342Y864250D02*
X656431Y872968D01*
G01X647275Y864413D02*
X656231Y873004D01*
G01X647216Y864583D02*
X656030Y873038D01*
G01X647156Y864753D02*
X655818Y873063D01*
G01X647105Y864931D02*
X655593Y873074D01*
G01X647064Y865119D02*
X655369Y873086D01*
G01X647024Y865308D02*
X655144Y873098D01*
G01X646989Y865502D02*
X654920Y873110D01*
G01X646971Y865711D02*
X654672Y873099D01*
G01X646952Y865921D02*
X654419Y873084D01*
G01X646938Y866135D02*
X654166Y873068D01*
G01X646944Y866367D02*
X653912Y873052D01*
G01X646949Y866600D02*
X653659Y873037D01*
G01X646961Y866838D02*
X653395Y873010D01*
G01X646993Y867097D02*
X653097Y872952D01*
G01X647027Y867356D02*
X652799Y872894D01*
G01X647079Y867633D02*
X652502Y872835D01*
G01X647166Y867944D02*
X652204Y872777D01*
G01X647253Y868254D02*
X651849Y872663D01*
G01X647341Y868566D02*
X651474Y872531D01*
G01X647450Y868898D02*
X651100Y872399D01*
G01X647688Y869353D02*
X650649Y872193D01*
G01X639780Y866993D02*
X645654Y872628D01*
G01X640041Y867470D02*
X645702Y872901D01*
G01X640219Y867869D02*
X645750Y873175D01*
G01X640340Y868212D02*
X645798Y873449D01*
G01X645846Y873721D02*
X640452Y868547D01*
G01X645894Y873994D02*
X640517Y868836D01*
G01X645942Y874268D02*
X640583Y869127D01*
G01X645990Y874541D02*
X640648Y869417D01*
G01X644837Y867982D02*
X644886Y868256D01*
G01X644165Y864156D02*
X644117Y863883D01*
G01X644213Y864430D02*
X644165Y864156D01*
G01X644934Y868528D02*
X644982Y868802D01*
G01X644742Y867436D02*
X644790Y867709D01*
G01D02*
X644837Y867982D01*
G01X644886Y868256D02*
X644934Y868528D01*
G01X644982Y868802D02*
X645030Y869076D01*
G01D02*
X645077Y869349D01*
G01D02*
X645126Y869622D01*
G01X644357Y865249D02*
X644310Y864976D01*
G01X644454Y865796D02*
X644405Y865523D01*
G01D02*
X644357Y865249D01*
G01X644262Y864704D02*
X644213Y864430D01*
G01X644310Y864976D02*
X644262Y864704D01*
G01X644502Y866069D02*
X644454Y865796D01*
G01X644645Y866889D02*
X644597Y866616D01*
G01X644645Y866889D02*
X644694Y867163D01*
G01X644550Y866343D02*
X644502Y866069D01*
G01X644597Y866616D02*
X644550Y866343D01*
G01X644694Y867163D02*
X644742Y867436D01*
G01X647926Y869809D02*
X650097Y871891D01*
G01X656886Y879085D02*
X652432Y874812D01*
G01X656654Y879091D02*
X652010Y874635D01*
G01X656410Y879084D02*
X651554Y874425D01*
G01X656166Y879077D02*
X651264Y874374D01*
G01X655923Y879071D02*
X651201Y874541D01*
G01X655671Y879057D02*
X651138Y874708D01*
G01X655410Y879033D02*
X651075Y874875D01*
G01X655149Y879010D02*
X651013Y875042D01*
G01X646038Y874814D02*
X640701Y869695D01*
G01X646086Y875087D02*
X640749Y869968D01*
G01X646134Y875361D02*
X640797Y870241D01*
G01X646182Y875634D02*
X640845Y870515D01*
G01X646230Y875908D02*
X640893Y870787D01*
G01X646278Y876180D02*
X640941Y871060D01*
G01X646326Y876454D02*
X640989Y871334D01*
G01X646374Y876727D02*
X641037Y871607D01*
G01X646422Y877001D02*
X641084Y871880D01*
G01X646470Y877273D02*
X641132Y872153D01*
G01X646519Y877547D02*
X641180Y872426D01*
G01X646567Y877821D02*
X641228Y872700D01*
G01X646614Y878094D02*
X641276Y872972D01*
G01X646662Y878367D02*
X641324Y873245D01*
G01X646710Y878640D02*
X641372Y873519D01*
G01X646578Y878741D02*
X641419Y873792D01*
G01X646342Y878741D02*
X641468Y874065D01*
G01X646105Y878741D02*
X641515Y874338D01*
G01X645868Y878741D02*
X641563Y874611D01*
G01X645631Y878741D02*
X641611Y874885D01*
G01X651201Y874541D02*
X651264Y874374D01*
G01X650950Y875209D02*
X651013Y875042D01*
G01X651138Y874708D02*
X651201Y874541D01*
G01X651013Y875042D02*
X651075Y874875D01*
G01D02*
X651138Y874708D01*
G01X641468Y874065D02*
X641419Y873792D01*
G01X645702Y872901D02*
X645750Y873175D01*
G01X645654Y872628D02*
X645702Y872901D01*
G01X645222Y870169D02*
X645270Y870442D01*
G01X645318Y870715D02*
X645366Y870988D01*
G01X645270Y870442D02*
X645318Y870715D01*
G01X645606Y872355D02*
X645558Y872081D01*
G01X645414Y871262D02*
X645462Y871535D01*
G01X645558Y872081D02*
X645510Y871808D01*
G01X645462Y871535D02*
X645510Y871808D01*
G01X645366Y870988D02*
X645414Y871262D01*
G01X645606Y872355D02*
X645654Y872628D01*
G01X646038Y874814D02*
X646086Y875087D01*
G01X645990Y874541D02*
X646038Y874814D01*
G01X645798Y873449D02*
X645846Y873721D01*
G01X645894Y873994D02*
X645942Y874268D01*
G01D02*
X645990Y874541D01*
G01X645846Y873721D02*
X645894Y873994D01*
G01X645174Y869896D02*
X645222Y870169D01*
G01X640797Y870241D02*
X640749Y869968D01*
G01X645798Y873449D02*
X645750Y873175D01*
G01X640749Y869968D02*
X640701Y869695D01*
G01X640845Y870515D02*
X640797Y870241D01*
G01X645126Y869622D02*
X645174Y869896D01*
G01X641276Y872972D02*
X641228Y872700D01*
G01X640893Y870787D02*
X640845Y870515D01*
G01X641228Y872700D02*
X641180Y872426D01*
G01X641372Y873519D02*
X641324Y873245D01*
G01X641180Y872426D02*
X641132Y872153D01*
G01X641324Y873245D02*
X641276Y872972D01*
G01X640989Y871334D02*
X640941Y871060D01*
G01D02*
X640893Y870787D01*
G01X641132Y872153D02*
X641084Y871880D01*
G01X641037Y871607D02*
X640989Y871334D01*
G01X641084Y871880D02*
X641037Y871607D01*
G01X641611Y874885D02*
X641563Y874611D01*
G01X641419Y873792D02*
X641372Y873519D01*
G01X641515Y874338D02*
X641468Y874065D01*
G01X641563Y874611D02*
X641515Y874338D01*
G01X641659Y875158D02*
X641611Y874885D01*
G01X647926Y869809D02*
X650097Y871891D01*
G01X656886Y879085D02*
X652432Y874812D01*
G01X656654Y879091D02*
X652010Y874635D01*
G01X656410Y879084D02*
X651554Y874425D01*
G01X656166Y879077D02*
X651264Y874374D01*
G01X655923Y879071D02*
X651201Y874541D01*
G01X655671Y879057D02*
X651138Y874708D01*
G01X655410Y879033D02*
X651075Y874875D01*
G01X655149Y879010D02*
X651013Y875042D01*
G01X646038Y874814D02*
X640701Y869695D01*
G01X646086Y875087D02*
X640749Y869968D01*
G01X646134Y875361D02*
X640797Y870241D01*
G01X646182Y875634D02*
X640845Y870515D01*
G01X646230Y875908D02*
X640893Y870787D01*
G01X646278Y876180D02*
X640941Y871060D01*
G01X646326Y876454D02*
X640989Y871334D01*
G01X646374Y876727D02*
X641037Y871607D01*
G01X646422Y877001D02*
X641084Y871880D01*
G01X646470Y877273D02*
X641132Y872153D01*
G01X646519Y877547D02*
X641180Y872426D01*
G01X646567Y877821D02*
X641228Y872700D01*
G01X646614Y878094D02*
X641276Y872972D01*
G01X646662Y878367D02*
X641324Y873245D01*
G01X646710Y878640D02*
X641372Y873519D01*
G01X646578Y878741D02*
X641419Y873792D01*
G01X646342Y878741D02*
X641468Y874065D01*
G01X646105Y878741D02*
X641515Y874338D01*
G01X645868Y878741D02*
X641563Y874611D01*
G01X645631Y878741D02*
X641611Y874885D01*
G01X651201Y874541D02*
X651264Y874374D01*
G01X650950Y875209D02*
X651013Y875042D01*
G01X651138Y874708D02*
X651201Y874541D01*
G01X651013Y875042D02*
X651075Y874875D01*
G01D02*
X651138Y874708D01*
G01X641468Y874065D02*
X641419Y873792D01*
G01X645702Y872901D02*
X645750Y873175D01*
G01X645654Y872628D02*
X645702Y872901D01*
G01X645222Y870169D02*
X645270Y870442D01*
G01X645318Y870715D02*
X645366Y870988D01*
G01X645270Y870442D02*
X645318Y870715D01*
G01X645606Y872355D02*
X645558Y872081D01*
G01X645414Y871262D02*
X645462Y871535D01*
G01X645558Y872081D02*
X645510Y871808D01*
G01X645462Y871535D02*
X645510Y871808D01*
G01X645366Y870988D02*
X645414Y871262D01*
G01X645606Y872355D02*
X645654Y872628D01*
G01X646038Y874814D02*
X646086Y875087D01*
G01X645990Y874541D02*
X646038Y874814D01*
G01X645798Y873449D02*
X645846Y873721D01*
G01X645894Y873994D02*
X645942Y874268D01*
G01D02*
X645990Y874541D01*
G01X645846Y873721D02*
X645894Y873994D01*
G01X645174Y869896D02*
X645222Y870169D01*
G01X640797Y870241D02*
X640749Y869968D01*
G01X645798Y873449D02*
X645750Y873175D01*
G01X640749Y869968D02*
X640701Y869695D01*
G01X640845Y870515D02*
X640797Y870241D01*
G01X645126Y869622D02*
X645174Y869896D01*
G01X641276Y872972D02*
X641228Y872700D01*
G01X640893Y870787D02*
X640845Y870515D01*
G01X641228Y872700D02*
X641180Y872426D01*
G01X641372Y873519D02*
X641324Y873245D01*
G01X641180Y872426D02*
X641132Y872153D01*
G01X641324Y873245D02*
X641276Y872972D01*
G01X640989Y871334D02*
X640941Y871060D01*
G01D02*
X640893Y870787D01*
G01X641132Y872153D02*
X641084Y871880D01*
G01X641037Y871607D02*
X640989Y871334D01*
G01X641084Y871880D02*
X641037Y871607D01*
G01X641611Y874885D02*
X641563Y874611D01*
G01X641419Y873792D02*
X641372Y873519D01*
G01X641515Y874338D02*
X641468Y874065D01*
G01X641563Y874611D02*
X641515Y874338D01*
G01X641659Y875158D02*
X641611Y874885D01*
G01X654889Y878987D02*
X650950Y875209D01*
G01X654605Y878943D02*
X650887Y875376D01*
G01X654321Y878898D02*
X650824Y875543D01*
G01X654037Y878852D02*
X650761Y875710D01*
G01X653725Y878780D02*
X650698Y875876D01*
G01X653411Y878707D02*
X650636Y876043D01*
G01X653083Y878619D02*
X650573Y876211D01*
G01X652733Y878510D02*
X650510Y876378D01*
G01X652374Y878392D02*
X650447Y876544D01*
G01X651979Y878241D02*
X650384Y876711D01*
G01X651570Y878076D02*
X650321Y876879D01*
G01X651126Y877878D02*
X650259Y877045D01*
G01X650655Y877652D02*
X650196Y877212D01*
G01X650158Y877403D02*
X650133Y877379D01*
G01X645394Y878741D02*
X641659Y875158D01*
G01X645157Y878741D02*
X641707Y875430D01*
G01X644921Y878741D02*
X641754Y875704D01*
G01X644683Y878741D02*
X641803Y875977D01*
G01X644447Y878741D02*
X641850Y876250D01*
G01X644210Y878741D02*
X641898Y876523D01*
G01X643973Y878741D02*
X641946Y876796D01*
G01X643736Y878741D02*
X641994Y877070D01*
G01X643499Y878741D02*
X642042Y877343D01*
G01X643263Y878741D02*
X642089Y877615D01*
G01X643026Y878741D02*
X642138Y877889D01*
G01X642789Y878741D02*
X642186Y878162D01*
G01X642552Y878741D02*
X642233Y878435D01*
G01X642315Y878741D02*
X642281Y878708D01*
G01X650321Y876879D02*
X650259Y877045D01*
G01X650321Y876879D02*
X650384Y876711D01*
G01X650259Y877045D02*
X650196Y877212D01*
G01D02*
X650133Y877379D01*
G01X650384Y876711D02*
X650447Y876544D01*
G01X650573Y876211D02*
X650636Y876043D01*
G01X650510Y876378D02*
X650573Y876211D01*
G01X650447Y876544D02*
X650510Y876378D01*
G01X650636Y876043D02*
X650698Y875876D01*
G01X650887Y875376D02*
X650950Y875209D01*
G01X650824Y875543D02*
X650887Y875376D01*
G01X650761Y875710D02*
X650824Y875543D01*
G01X650698Y875876D02*
X650761Y875710D01*
G01X645157Y878741D02*
X644921D01*
G01X645394D02*
X645157D01*
G01X644683D02*
X644447D01*
G01D02*
X644210D01*
G01X646342D02*
X646105D01*
G01X645631D02*
X645394D01*
G01X646105D02*
X645868D01*
G01D02*
X645631D01*
G01X643263D02*
X643026D01*
G01D02*
X642789D01*
G01D02*
X642552D01*
G01D02*
X642315D01*
G01X643973D02*
X643736D01*
G01X643499D02*
X643263D01*
G01X646578D02*
X646342D01*
G01X643736D02*
X643499D01*
G01X644210D02*
X643973D01*
G01X646182Y875634D02*
X646230Y875908D01*
G01X646728Y878741D02*
X646578D01*
G01X646710Y878640D02*
X646728Y878741D01*
G01X646134Y875361D02*
X646182Y875634D01*
G01X646086Y875087D02*
X646134Y875361D01*
G01X646519Y877547D02*
X646567Y877821D01*
G01D02*
X646614Y878094D01*
G01X646230Y875908D02*
X646278Y876180D01*
G01X646614Y878094D02*
X646662Y878367D01*
G01D02*
X646710Y878640D01*
G01X646326Y876454D02*
X646374Y876727D01*
G01X646278Y876180D02*
X646326Y876454D01*
G01X646470Y877273D02*
X646519Y877547D01*
G01X646422Y877001D02*
X646470Y877273D01*
G01X646374Y876727D02*
X646422Y877001D01*
G01X644921Y878741D02*
X644683D01*
G01X636530D02*
X636394D01*
G01X636509Y878624D02*
X636530Y878741D01*
G01X636461Y878352D02*
X636509Y878624D01*
G01X636413Y878078D02*
X636461Y878352D01*
G01X636366Y877805D02*
X636413Y878078D01*
G01X642233Y878435D02*
X642281Y878708D01*
G01X642138Y877889D02*
X642186Y878162D01*
G01X642287Y878741D02*
X642281Y878708D01*
G01X642315Y878741D02*
X642287D01*
G01X641946Y876796D02*
X641994Y877070D01*
G01X642042Y877343D02*
X642089Y877615D01*
G01D02*
X642138Y877889D01*
G01X641994Y877070D02*
X642042Y877343D01*
G01X641898Y876523D02*
X641946Y876796D01*
G01X642186Y878162D02*
X642233Y878435D01*
G01X641850Y876250D02*
X641898Y876523D01*
G01X641707Y875430D02*
X641659Y875158D01*
G01X641754Y875704D02*
X641707Y875430D01*
G01X641803Y875977D02*
X641850Y876250D01*
G01X641803Y875977D02*
X641754Y875704D01*
G01X654889Y878987D02*
X650950Y875209D01*
G01X654605Y878943D02*
X650887Y875376D01*
G01X654321Y878898D02*
X650824Y875543D01*
G01X654037Y878852D02*
X650761Y875710D01*
G01X653725Y878780D02*
X650698Y875876D01*
G01X653411Y878707D02*
X650636Y876043D01*
G01X653083Y878619D02*
X650573Y876211D01*
G01X652733Y878510D02*
X650510Y876378D01*
G01X652374Y878392D02*
X650447Y876544D01*
G01X651979Y878241D02*
X650384Y876711D01*
G01X651570Y878076D02*
X650321Y876879D01*
G01X651126Y877878D02*
X650259Y877045D01*
G01X650655Y877652D02*
X650196Y877212D01*
G01X650158Y877403D02*
X650133Y877379D01*
G01X645394Y878741D02*
X641659Y875158D01*
G01X645157Y878741D02*
X641707Y875430D01*
G01X644921Y878741D02*
X641754Y875704D01*
G01X644683Y878741D02*
X641803Y875977D01*
G01X644447Y878741D02*
X641850Y876250D01*
G01X644210Y878741D02*
X641898Y876523D01*
G01X643973Y878741D02*
X641946Y876796D01*
G01X643736Y878741D02*
X641994Y877070D01*
G01X643499Y878741D02*
X642042Y877343D01*
G01X643263Y878741D02*
X642089Y877615D01*
G01X643026Y878741D02*
X642138Y877889D01*
G01X642789Y878741D02*
X642186Y878162D01*
G01X642552Y878741D02*
X642233Y878435D01*
G01X642315Y878741D02*
X642281Y878708D01*
G01X650321Y876879D02*
X650259Y877045D01*
G01X650321Y876879D02*
X650384Y876711D01*
G01X650259Y877045D02*
X650196Y877212D01*
G01D02*
X650133Y877379D01*
G01X650384Y876711D02*
X650447Y876544D01*
G01X650573Y876211D02*
X650636Y876043D01*
G01X650510Y876378D02*
X650573Y876211D01*
G01X650447Y876544D02*
X650510Y876378D01*
G01X650636Y876043D02*
X650698Y875876D01*
G01X650887Y875376D02*
X650950Y875209D01*
G01X650824Y875543D02*
X650887Y875376D01*
G01X650761Y875710D02*
X650824Y875543D01*
G01X650698Y875876D02*
X650761Y875710D01*
G01X645157Y878741D02*
X644921D01*
G01X645394D02*
X645157D01*
G01X644683D02*
X644447D01*
G01D02*
X644210D01*
G01X646342D02*
X646105D01*
G01X645631D02*
X645394D01*
G01X646105D02*
X645868D01*
G01D02*
X645631D01*
G01X643263D02*
X643026D01*
G01D02*
X642789D01*
G01D02*
X642552D01*
G01D02*
X642315D01*
G01X643973D02*
X643736D01*
G01X643499D02*
X643263D01*
G01X646578D02*
X646342D01*
G01X643736D02*
X643499D01*
G01X644210D02*
X643973D01*
G01X646182Y875634D02*
X646230Y875908D01*
G01X646728Y878741D02*
X646578D01*
G01X646710Y878640D02*
X646728Y878741D01*
G01X646134Y875361D02*
X646182Y875634D01*
G01X646086Y875087D02*
X646134Y875361D01*
G01X646519Y877547D02*
X646567Y877821D01*
G01D02*
X646614Y878094D01*
G01X646230Y875908D02*
X646278Y876180D01*
G01X646614Y878094D02*
X646662Y878367D01*
G01D02*
X646710Y878640D01*
G01X646326Y876454D02*
X646374Y876727D01*
G01X646278Y876180D02*
X646326Y876454D01*
G01X646470Y877273D02*
X646519Y877547D01*
G01X646422Y877001D02*
X646470Y877273D01*
G01X646374Y876727D02*
X646422Y877001D01*
G01X644921Y878741D02*
X644683D01*
G01X636530D02*
X636394D01*
G01X636509Y878624D02*
X636530Y878741D01*
G01X636461Y878352D02*
X636509Y878624D01*
G01X636413Y878078D02*
X636461Y878352D01*
G01X636366Y877805D02*
X636413Y878078D01*
G01X642233Y878435D02*
X642281Y878708D01*
G01X642138Y877889D02*
X642186Y878162D01*
G01X642287Y878741D02*
X642281Y878708D01*
G01X642315Y878741D02*
X642287D01*
G01X641946Y876796D02*
X641994Y877070D01*
G01X642042Y877343D02*
X642089Y877615D01*
G01D02*
X642138Y877889D01*
G01X641994Y877070D02*
X642042Y877343D01*
G01X641898Y876523D02*
X641946Y876796D01*
G01X642186Y878162D02*
X642233Y878435D01*
G01X641850Y876250D02*
X641898Y876523D01*
G01X641707Y875430D02*
X641659Y875158D01*
G01X641754Y875704D02*
X641707Y875430D01*
G01X641803Y875977D02*
X641850Y876250D01*
G01X641803Y875977D02*
X641754Y875704D01*
G01X667822Y861856D02*
X667884Y861917D01*
G01X667585Y861856D02*
X667932Y862190D01*
G01X667347Y861856D02*
X667979Y862462D01*
G01X667111Y861856D02*
X668028Y862736D01*
G01X666874Y861856D02*
X668077Y863010D01*
G01X666636Y861856D02*
X668124Y863283D01*
G01X666400Y861856D02*
X668172Y863556D01*
G01X666163Y861856D02*
X668221Y863829D01*
G01X665926Y861856D02*
X668269Y864103D01*
G01X665690Y861856D02*
X668317Y864376D01*
G01X665454Y861856D02*
X668364Y864649D01*
G01X665215Y861856D02*
X668413Y864923D01*
G01X664979Y861856D02*
X668461Y865197D01*
G01X664743Y861856D02*
X668508Y865469D01*
G01X664506Y861856D02*
X668557Y865742D01*
G01X664268Y861856D02*
X668606Y866016D01*
G01X664031Y861856D02*
X668653Y866290D01*
G01X663795Y861856D02*
X668701Y866563D01*
G01X663558Y861856D02*
X668750Y866836D01*
G01X663459Y861987D02*
X668798Y867110D01*
G01X663506Y862261D02*
X668846Y867383D01*
G01X663555Y862534D02*
X668893Y867656D01*
G01X663602Y862807D02*
X668942Y867929D01*
G01X663650Y863081D02*
X668990Y868203D01*
G01X663699Y863355D02*
X669037Y868476D01*
G01X663746Y863627D02*
X669086Y868749D01*
G01X660479Y861856D02*
X660612Y861982D01*
G01X660241Y861856D02*
X660659Y862256D01*
G01X660005Y861856D02*
X660707Y862529D01*
G01X659769Y861856D02*
X660755Y862802D01*
G01X659531Y861856D02*
X660801Y863075D01*
G01X659294Y861856D02*
X660850Y863349D01*
G01X659057Y861856D02*
X660899Y863622D01*
G01X658821Y861856D02*
X660945Y863894D01*
G01X658584Y861856D02*
X660994Y864168D01*
G01X658347Y861856D02*
X661043Y864441D01*
G01X658111Y861856D02*
X661089Y864714D01*
G01X657874Y861856D02*
X661138Y864987D01*
G01X657636Y861856D02*
X661185Y865260D01*
G01X657399Y861856D02*
X661233Y865534D01*
G01X657162Y861856D02*
X661282Y865807D01*
G01X656926Y861856D02*
X661329Y866080D01*
G01X656689Y861856D02*
X661377Y866354D01*
G01X656452Y861856D02*
X661425Y866627D01*
G01X656216Y861856D02*
X661473Y866899D01*
G01X656182Y862051D02*
X661520Y867173D01*
G01X656231Y862325D02*
X661569Y867446D01*
G01X656279Y862599D02*
X661617Y867719D01*
G01X656328Y862872D02*
X661664Y867992D01*
G01X655781Y862575D02*
X661713Y868265D01*
G01X655184Y862230D02*
X661760Y868539D01*
G01X654710Y862002D02*
X661808Y868812D01*
G01X654329Y861864D02*
X661857Y869085D01*
G01X653992Y861768D02*
X661904Y869358D01*
G01X653655Y861673D02*
X661952Y869631D01*
G01X653348Y861605D02*
X662000Y869904D01*
G01X653085Y861581D02*
X662048Y870178D01*
G01X652821Y861553D02*
X662095Y870450D01*
G01X668077Y863010D02*
X668028Y862736D01*
G01X668172Y863556D02*
X668124Y863283D01*
G01X668028Y862736D02*
X667979Y862462D01*
G01X668124Y863283D02*
X668077Y863010D01*
G01X668221Y863829D02*
X668172Y863556D01*
G01X663794Y863900D02*
X663746Y863627D01*
G01X667585Y861856D02*
X667822D01*
G01X667111D02*
X667347D01*
G01D02*
X667585D01*
G01X666874D02*
X667111D01*
G01X666636D02*
X666874D01*
G01X663555Y862534D02*
X663506Y862261D01*
G01X663795Y861856D02*
X664031D01*
G01X666400D02*
X666636D01*
G01X663435D02*
X663558D01*
G01X663459Y861987D02*
X663435Y861856D01*
G01X663506Y862261D02*
X663459Y861987D01*
G01X663746Y863627D02*
X663699Y863355D01*
G01D02*
X663650Y863081D01*
G01D02*
X663602Y862807D01*
G01D02*
X663555Y862534D01*
G01X663558Y861856D02*
X663795D01*
G01X665690D02*
X665926D01*
G01X666163D02*
X666400D01*
G01X665454D02*
X665690D01*
G01X665926D02*
X666163D01*
G01X664743D02*
X664979D01*
G01X664506D02*
X664743D01*
G01X664268D02*
X664506D01*
G01X665215D02*
X665454D01*
G01X664979D02*
X665215D01*
G01X664031D02*
X664268D01*
G01X667932Y862190D02*
X667884Y861917D01*
G01X667979Y862462D02*
X667932Y862190D01*
G01X667873Y861856D02*
X667884Y861917D01*
G01X667822Y861856D02*
X667873D01*
G01X658347D02*
X658584D01*
G01X658821D02*
X659057D01*
G01D02*
X659294D01*
G01X658584D02*
X658821D01*
G01X660005D02*
X660241D01*
G01D02*
X660479D01*
G01X659531D02*
X659769D01*
G01D02*
X660005D01*
G01X658111D02*
X658347D01*
G01X659294D02*
X659531D01*
G01X657874D02*
X658111D01*
G01X656689D02*
X656926D01*
G01X656452D02*
X656689D01*
G01X656148D02*
X656216D01*
G01X656182Y862051D02*
X656148Y861856D01*
G01X656216D02*
X656452D01*
G01X656231Y862325D02*
X656182Y862051D01*
G01X657636Y861856D02*
X657874D01*
G01X657162D02*
X657399D01*
G01X656926D02*
X657162D01*
G01X657399D02*
X657636D01*
G01X656328Y862872D02*
X656279Y862599D01*
G01D02*
X656231Y862325D01*
G01X660899Y863622D02*
X660945Y863894D01*
G01X660850Y863349D02*
X660899Y863622D01*
G01X660589Y861856D02*
X660612Y861982D01*
G01X660479Y861856D02*
X660589D01*
G01X660612Y861982D02*
X660659Y862256D01*
G01X660755Y862802D02*
X660801Y863075D01*
G01D02*
X660850Y863349D01*
G01X660659Y862256D02*
X660707Y862529D01*
G01D02*
X660755Y862802D01*
G01X667822Y861856D02*
X667884Y861917D01*
G01X667585Y861856D02*
X667932Y862190D01*
G01X667347Y861856D02*
X667979Y862462D01*
G01X667111Y861856D02*
X668028Y862736D01*
G01X666874Y861856D02*
X668077Y863010D01*
G01X666636Y861856D02*
X668124Y863283D01*
G01X666400Y861856D02*
X668172Y863556D01*
G01X666163Y861856D02*
X668221Y863829D01*
G01X665926Y861856D02*
X668269Y864103D01*
G01X665690Y861856D02*
X668317Y864376D01*
G01X665454Y861856D02*
X668364Y864649D01*
G01X665215Y861856D02*
X668413Y864923D01*
G01X664979Y861856D02*
X668461Y865197D01*
G01X664743Y861856D02*
X668508Y865469D01*
G01X664506Y861856D02*
X668557Y865742D01*
G01X664268Y861856D02*
X668606Y866016D01*
G01X664031Y861856D02*
X668653Y866290D01*
G01X663795Y861856D02*
X668701Y866563D01*
G01X663558Y861856D02*
X668750Y866836D01*
G01X663459Y861987D02*
X668798Y867110D01*
G01X663506Y862261D02*
X668846Y867383D01*
G01X663555Y862534D02*
X668893Y867656D01*
G01X663602Y862807D02*
X668942Y867929D01*
G01X663650Y863081D02*
X668990Y868203D01*
G01X663699Y863355D02*
X669037Y868476D01*
G01X663746Y863627D02*
X669086Y868749D01*
G01X660479Y861856D02*
X660612Y861982D01*
G01X660241Y861856D02*
X660659Y862256D01*
G01X660005Y861856D02*
X660707Y862529D01*
G01X659769Y861856D02*
X660755Y862802D01*
G01X659531Y861856D02*
X660801Y863075D01*
G01X659294Y861856D02*
X660850Y863349D01*
G01X659057Y861856D02*
X660899Y863622D01*
G01X658821Y861856D02*
X660945Y863894D01*
G01X658584Y861856D02*
X660994Y864168D01*
G01X658347Y861856D02*
X661043Y864441D01*
G01X658111Y861856D02*
X661089Y864714D01*
G01X657874Y861856D02*
X661138Y864987D01*
G01X657636Y861856D02*
X661185Y865260D01*
G01X657399Y861856D02*
X661233Y865534D01*
G01X657162Y861856D02*
X661282Y865807D01*
G01X656926Y861856D02*
X661329Y866080D01*
G01X656689Y861856D02*
X661377Y866354D01*
G01X656452Y861856D02*
X661425Y866627D01*
G01X656216Y861856D02*
X661473Y866899D01*
G01X656182Y862051D02*
X661520Y867173D01*
G01X656231Y862325D02*
X661569Y867446D01*
G01X656279Y862599D02*
X661617Y867719D01*
G01X656328Y862872D02*
X661664Y867992D01*
G01X655781Y862575D02*
X661713Y868265D01*
G01X655184Y862230D02*
X661760Y868539D01*
G01X654710Y862002D02*
X661808Y868812D01*
G01X654329Y861864D02*
X661857Y869085D01*
G01X653992Y861768D02*
X661904Y869358D01*
G01X653655Y861673D02*
X661952Y869631D01*
G01X653348Y861605D02*
X662000Y869904D01*
G01X653085Y861581D02*
X662048Y870178D01*
G01X652821Y861553D02*
X662095Y870450D01*
G01X668077Y863010D02*
X668028Y862736D01*
G01X668172Y863556D02*
X668124Y863283D01*
G01X668028Y862736D02*
X667979Y862462D01*
G01X668124Y863283D02*
X668077Y863010D01*
G01X668221Y863829D02*
X668172Y863556D01*
G01X663794Y863900D02*
X663746Y863627D01*
G01X667585Y861856D02*
X667822D01*
G01X667111D02*
X667347D01*
G01D02*
X667585D01*
G01X666874D02*
X667111D01*
G01X666636D02*
X666874D01*
G01X663555Y862534D02*
X663506Y862261D01*
G01X663795Y861856D02*
X664031D01*
G01X666400D02*
X666636D01*
G01X663435D02*
X663558D01*
G01X663459Y861987D02*
X663435Y861856D01*
G01X663506Y862261D02*
X663459Y861987D01*
G01X663746Y863627D02*
X663699Y863355D01*
G01D02*
X663650Y863081D01*
G01D02*
X663602Y862807D01*
G01D02*
X663555Y862534D01*
G01X663558Y861856D02*
X663795D01*
G01X665690D02*
X665926D01*
G01X666163D02*
X666400D01*
G01X665454D02*
X665690D01*
G01X665926D02*
X666163D01*
G01X664743D02*
X664979D01*
G01X664506D02*
X664743D01*
G01X664268D02*
X664506D01*
G01X665215D02*
X665454D01*
G01X664979D02*
X665215D01*
G01X664031D02*
X664268D01*
G01X667932Y862190D02*
X667884Y861917D01*
G01X667979Y862462D02*
X667932Y862190D01*
G01X667873Y861856D02*
X667884Y861917D01*
G01X667822Y861856D02*
X667873D01*
G01X658347D02*
X658584D01*
G01X658821D02*
X659057D01*
G01D02*
X659294D01*
G01X658584D02*
X658821D01*
G01X660005D02*
X660241D01*
G01D02*
X660479D01*
G01X659531D02*
X659769D01*
G01D02*
X660005D01*
G01X658111D02*
X658347D01*
G01X659294D02*
X659531D01*
G01X657874D02*
X658111D01*
G01X656689D02*
X656926D01*
G01X656452D02*
X656689D01*
G01X656148D02*
X656216D01*
G01X656182Y862051D02*
X656148Y861856D01*
G01X656216D02*
X656452D01*
G01X656231Y862325D02*
X656182Y862051D01*
G01X657636Y861856D02*
X657874D01*
G01X657162D02*
X657399D01*
G01X656926D02*
X657162D01*
G01X657399D02*
X657636D01*
G01X656328Y862872D02*
X656279Y862599D01*
G01D02*
X656231Y862325D01*
G01X660899Y863622D02*
X660945Y863894D01*
G01X660850Y863349D02*
X660899Y863622D01*
G01X660589Y861856D02*
X660612Y861982D01*
G01X660479Y861856D02*
X660589D01*
G01X660612Y861982D02*
X660659Y862256D01*
G01X660755Y862802D02*
X660801Y863075D01*
G01D02*
X660850Y863349D01*
G01X660659Y862256D02*
X660707Y862529D01*
G01D02*
X660755Y862802D01*
G01X663794Y863900D02*
X669135Y869023D01*
G01X663842Y864174D02*
X669182Y869296D01*
G01X663891Y864447D02*
X669230Y869570D01*
G01X663937Y864720D02*
X669279Y869843D01*
G01X669326Y870116D02*
X663986Y864993D01*
G01X669374Y870389D02*
X664035Y865266D01*
G01X669422Y870663D02*
X664082Y865540D01*
G01X669471Y870936D02*
X664130Y865813D01*
G01X669525Y871216D02*
X664179Y866086D01*
G01X669591Y871506D02*
X664226Y866360D01*
G01X669656Y871795D02*
X664274Y866633D01*
G01X669719Y872083D02*
X664323Y866906D01*
G01X669837Y872423D02*
X664370Y867179D01*
G01X669957Y872766D02*
X664417Y867452D01*
G01X670147Y873175D02*
X664466Y867726D01*
G01X670461Y873704D02*
X664514Y867999D01*
G01X675756Y879011D02*
X664561Y868271D01*
G01X675539Y879031D02*
X664610Y868545D01*
G01X675324Y879050D02*
X664658Y868819D01*
G01X675108Y879071D02*
X664705Y869091D01*
G01X674891Y879090D02*
X664754Y869365D01*
G01X662383Y872090D02*
X657050Y866973D01*
G01X662432Y872363D02*
X657097Y867246D01*
G01X662479Y872636D02*
X657145Y867519D01*
G01X662527Y872909D02*
X657193Y867793D01*
G01X662574Y873183D02*
X657241Y868066D01*
G01X662595Y873429D02*
X657289Y868339D01*
G01X662615Y873675D02*
X657337Y868612D01*
G01X662635Y873922D02*
X657385Y868886D01*
G01X662654Y874168D02*
X657275Y869008D01*
G01X662675Y874414D02*
X657135Y869099D01*
G01X662668Y874635D02*
X656983Y869181D01*
G01X662641Y874836D02*
X656827Y869260D01*
G01X662614Y875037D02*
X656663Y869329D01*
G01X662586Y875238D02*
X656491Y869391D01*
G01X662558Y875438D02*
X656312Y869446D01*
G01X652812Y869270D02*
X656631Y872934D01*
G01X668317Y864376D02*
X668364Y864649D01*
G01X668557Y865742D02*
X668606Y866016D01*
G01X668269Y864103D02*
X668221Y863829D01*
G01X668508Y865469D02*
X668557Y865742D01*
G01X668701Y866563D02*
X668750Y866836D01*
G01X668653Y866290D02*
X668701Y866563D01*
G01X668606Y866016D02*
X668653Y866290D01*
G01X668364Y864649D02*
X668413Y864923D01*
G01X668317Y864376D02*
X668269Y864103D01*
G01X668461Y865197D02*
X668508Y865469D01*
G01X668413Y864923D02*
X668461Y865197D01*
G01X668798Y867110D02*
X668846Y867383D01*
G01X668750Y866836D02*
X668798Y867110D01*
G01X663891Y864447D02*
X663842Y864174D01*
G01X663937Y864720D02*
X663891Y864447D01*
G01X663986Y864993D02*
X663937Y864720D01*
G01X663986Y864993D02*
X664035Y865266D01*
G01X663842Y864174D02*
X663794Y863900D01*
G01X664417Y867452D02*
X664370Y867179D01*
G01X664274Y866633D02*
X664226Y866360D01*
G01X664179Y866086D02*
X664130Y865813D01*
G01X664370Y867179D02*
X664323Y866906D01*
G01D02*
X664274Y866633D01*
G01X664226Y866360D02*
X664179Y866086D01*
G01X664130Y865813D02*
X664082Y865540D01*
G01D02*
X664035Y865266D01*
G01X664466Y867726D02*
X664417Y867452D01*
G01X664561Y868271D02*
X664514Y867999D01*
G01D02*
X664466Y867726D01*
G01X664658Y868819D02*
X664610Y868545D01*
G01X664754Y869365D02*
X664705Y869091D01*
G01D02*
X664658Y868819D01*
G01X664610Y868545D02*
X664561Y868271D01*
G01X664801Y869638D02*
X664754Y869365D01*
G01X657097Y867246D02*
X657050Y866973D01*
G01X657337Y868612D02*
X657289Y868339D01*
G01X657385Y868886D02*
X657337Y868612D01*
G01X661664Y867992D02*
X661713Y868265D01*
G01X657241Y868066D02*
X657193Y867793D01*
G01D02*
X657145Y867519D01*
G01X657289Y868339D02*
X657241Y868066D01*
G01X657145Y867519D02*
X657097Y867246D01*
G01X661473Y866899D02*
X661520Y867173D01*
G01X661282Y865807D02*
X661329Y866080D01*
G01X661569Y867446D02*
X661617Y867719D01*
G01D02*
X661664Y867992D01*
G01X661425Y866627D02*
X661473Y866899D01*
G01X661520Y867173D02*
X661569Y867446D01*
G01X661760Y868539D02*
X661808Y868812D01*
G01X661713Y868265D02*
X661760Y868539D01*
G01X661089Y864714D02*
X661138Y864987D01*
G01X661043Y864441D02*
X661089Y864714D01*
G01X660994Y864168D02*
X661043Y864441D01*
G01X660945Y863894D02*
X660994Y864168D01*
G01X661233Y865534D02*
X661282Y865807D01*
G01X661329Y866080D02*
X661377Y866354D01*
G01D02*
X661425Y866627D01*
G01X661185Y865260D02*
X661233Y865534D01*
G01X661138Y864987D02*
X661185Y865260D01*
G01X661857Y869085D02*
X661904Y869358D01*
G01D02*
X661952Y869631D01*
G01X661808Y868812D02*
X661857Y869085D01*
G01X663794Y863900D02*
X669135Y869023D01*
G01X663842Y864174D02*
X669182Y869296D01*
G01X663891Y864447D02*
X669230Y869570D01*
G01X663937Y864720D02*
X669279Y869843D01*
G01X669326Y870116D02*
X663986Y864993D01*
G01X669374Y870389D02*
X664035Y865266D01*
G01X669422Y870663D02*
X664082Y865540D01*
G01X669471Y870936D02*
X664130Y865813D01*
G01X669525Y871216D02*
X664179Y866086D01*
G01X669591Y871506D02*
X664226Y866360D01*
G01X669656Y871795D02*
X664274Y866633D01*
G01X669719Y872083D02*
X664323Y866906D01*
G01X669837Y872423D02*
X664370Y867179D01*
G01X669957Y872766D02*
X664417Y867452D01*
G01X670147Y873175D02*
X664466Y867726D01*
G01X670461Y873704D02*
X664514Y867999D01*
G01X675756Y879011D02*
X664561Y868271D01*
G01X675539Y879031D02*
X664610Y868545D01*
G01X675324Y879050D02*
X664658Y868819D01*
G01X675108Y879071D02*
X664705Y869091D01*
G01X674891Y879090D02*
X664754Y869365D01*
G01X662383Y872090D02*
X657050Y866973D01*
G01X662432Y872363D02*
X657097Y867246D01*
G01X662479Y872636D02*
X657145Y867519D01*
G01X662527Y872909D02*
X657193Y867793D01*
G01X662574Y873183D02*
X657241Y868066D01*
G01X662595Y873429D02*
X657289Y868339D01*
G01X662615Y873675D02*
X657337Y868612D01*
G01X662635Y873922D02*
X657385Y868886D01*
G01X662654Y874168D02*
X657275Y869008D01*
G01X662675Y874414D02*
X657135Y869099D01*
G01X662668Y874635D02*
X656983Y869181D01*
G01X662641Y874836D02*
X656827Y869260D01*
G01X662614Y875037D02*
X656663Y869329D01*
G01X662586Y875238D02*
X656491Y869391D01*
G01X662558Y875438D02*
X656312Y869446D01*
G01X652812Y869270D02*
X656631Y872934D01*
G01X668317Y864376D02*
X668364Y864649D01*
G01X668557Y865742D02*
X668606Y866016D01*
G01X668269Y864103D02*
X668221Y863829D01*
G01X668508Y865469D02*
X668557Y865742D01*
G01X668701Y866563D02*
X668750Y866836D01*
G01X668653Y866290D02*
X668701Y866563D01*
G01X668606Y866016D02*
X668653Y866290D01*
G01X668364Y864649D02*
X668413Y864923D01*
G01X668317Y864376D02*
X668269Y864103D01*
G01X668461Y865197D02*
X668508Y865469D01*
G01X668413Y864923D02*
X668461Y865197D01*
G01X668798Y867110D02*
X668846Y867383D01*
G01X668750Y866836D02*
X668798Y867110D01*
G01X663891Y864447D02*
X663842Y864174D01*
G01X663937Y864720D02*
X663891Y864447D01*
G01X663986Y864993D02*
X663937Y864720D01*
G01X663986Y864993D02*
X664035Y865266D01*
G01X663842Y864174D02*
X663794Y863900D01*
G01X664417Y867452D02*
X664370Y867179D01*
G01X664274Y866633D02*
X664226Y866360D01*
G01X664179Y866086D02*
X664130Y865813D01*
G01X664370Y867179D02*
X664323Y866906D01*
G01D02*
X664274Y866633D01*
G01X664226Y866360D02*
X664179Y866086D01*
G01X664130Y865813D02*
X664082Y865540D01*
G01D02*
X664035Y865266D01*
G01X664466Y867726D02*
X664417Y867452D01*
G01X664561Y868271D02*
X664514Y867999D01*
G01D02*
X664466Y867726D01*
G01X664658Y868819D02*
X664610Y868545D01*
G01X664754Y869365D02*
X664705Y869091D01*
G01D02*
X664658Y868819D01*
G01X664610Y868545D02*
X664561Y868271D01*
G01X664801Y869638D02*
X664754Y869365D01*
G01X657097Y867246D02*
X657050Y866973D01*
G01X657337Y868612D02*
X657289Y868339D01*
G01X657385Y868886D02*
X657337Y868612D01*
G01X661664Y867992D02*
X661713Y868265D01*
G01X657241Y868066D02*
X657193Y867793D01*
G01D02*
X657145Y867519D01*
G01X657289Y868339D02*
X657241Y868066D01*
G01X657145Y867519D02*
X657097Y867246D01*
G01X661473Y866899D02*
X661520Y867173D01*
G01X661282Y865807D02*
X661329Y866080D01*
G01X661569Y867446D02*
X661617Y867719D01*
G01D02*
X661664Y867992D01*
G01X661425Y866627D02*
X661473Y866899D01*
G01X661520Y867173D02*
X661569Y867446D01*
G01X661760Y868539D02*
X661808Y868812D01*
G01X661713Y868265D02*
X661760Y868539D01*
G01X661089Y864714D02*
X661138Y864987D01*
G01X661043Y864441D02*
X661089Y864714D01*
G01X660994Y864168D02*
X661043Y864441D01*
G01X660945Y863894D02*
X660994Y864168D01*
G01X661233Y865534D02*
X661282Y865807D01*
G01X661329Y866080D02*
X661377Y866354D01*
G01D02*
X661425Y866627D01*
G01X661185Y865260D02*
X661233Y865534D01*
G01X661138Y864987D02*
X661185Y865260D01*
G01X661857Y869085D02*
X661904Y869358D01*
G01D02*
X661952Y869631D01*
G01X661808Y868812D02*
X661857Y869085D01*
G01X674637Y879073D02*
X664801Y869638D01*
G01X674376Y879050D02*
X664849Y869911D01*
G01X674113Y879025D02*
X664898Y870184D01*
G01X673852Y879001D02*
X664945Y870457D01*
G01X673589Y878977D02*
X664993Y870731D01*
G01X673258Y878887D02*
X665041Y871004D01*
G01X672926Y878795D02*
X665089Y871277D01*
G01X672593Y878702D02*
X665136Y871550D01*
G01X672192Y878545D02*
X665185Y871824D01*
G01X671721Y878322D02*
X665233Y872097D01*
G01X671072Y877925D02*
X665280Y872370D01*
G01X670665Y877762D02*
X665329Y872643D01*
G01X670714Y878036D02*
X665378Y872917D01*
G01X670761Y878309D02*
X665424Y873190D01*
G01X670809Y878582D02*
X665473Y873463D01*
G01X670738Y878741D02*
X665522Y873736D01*
G01X670501Y878741D02*
X665568Y874009D01*
G01X670263Y878741D02*
X665616Y874283D01*
G01X670027Y878741D02*
X665665Y874556D01*
G01X669791Y878741D02*
X665713Y874829D01*
G01X662531Y875639D02*
X656122Y869492D01*
G01X662475Y875815D02*
X655927Y869533D01*
G01X662410Y875977D02*
X655723Y869563D01*
G01X662342Y876140D02*
X655514Y869590D01*
G01X662274Y876303D02*
X655296Y869608D01*
G01X662208Y876466D02*
X655074Y869623D01*
G01X657849Y872511D02*
X654847Y869632D01*
G01X662142Y876629D02*
X658054Y872708D01*
G01X657690Y872586D02*
X654615Y869637D01*
G01X662059Y876777D02*
X658101Y872981D01*
G01X661957Y876907D02*
X658148Y873254D01*
G01X657531Y872660D02*
X654375Y869633D01*
G01X657360Y872725D02*
X654103Y869599D01*
G01X661857Y877037D02*
X658174Y873505D01*
G01X661755Y877167D02*
X658188Y873746D01*
G01X653830Y869565D02*
X657182Y872781D01*
G01X653558Y869531D02*
X657004Y872837D01*
G01X661653Y877297D02*
X658167Y873952D01*
G01X653277Y869489D02*
X656825Y872893D01*
G01X661553Y877427D02*
X658137Y874151D01*
G01X661450Y877558D02*
X658079Y874323D01*
G01X661318Y877657D02*
X658018Y874491D01*
G01X661187Y877758D02*
X657927Y874631D01*
G01X661054Y877858D02*
X657835Y874770D01*
G01X660921Y877958D02*
X657719Y874886D01*
G01X660788Y878058D02*
X657596Y874995D01*
G01X657107Y879071D02*
X652811Y874949D01*
G01X665329Y872643D02*
X665280Y872370D01*
G01D02*
X665233Y872097D01*
G01X665713Y874829D02*
X665665Y874556D01*
G01D02*
X665616Y874283D01*
G01X665713Y874829D02*
X665760Y875102D01*
G01X665616Y874283D02*
X665568Y874009D01*
G01X664993Y870731D02*
X664945Y870457D01*
G01X665041Y871004D02*
X664993Y870731D01*
G01X664945Y870457D02*
X664898Y870184D01*
G01X665568Y874009D02*
X665522Y873736D01*
G01X664898Y870184D02*
X664849Y869911D01*
G01D02*
X664801Y869638D01*
G01X665378Y872917D02*
X665329Y872643D01*
G01X665424Y873190D02*
X665378Y872917D01*
G01X665473Y873463D02*
X665424Y873190D01*
G01X665522Y873736D02*
X665473Y873463D01*
G01X665233Y872097D02*
X665185Y871824D01*
G01X665136Y871550D02*
X665089Y871277D01*
G01X665185Y871824D02*
X665136Y871550D01*
G01X665089Y871277D02*
X665041Y871004D01*
G01X662336Y871817D02*
X662288Y871543D01*
G01X662479Y872636D02*
X662432Y872363D01*
G01X662527Y872909D02*
X662479Y872636D01*
G01X662383Y872090D02*
X662336Y871817D01*
G01X662432Y872363D02*
X662383Y872090D01*
G01X662144Y870724D02*
X662192Y870998D01*
G01X662095Y870450D02*
X662144Y870724D01*
G01X662192Y870998D02*
X662239Y871270D01*
G01X662288Y871543D02*
X662239Y871270D01*
G01X662000Y869904D02*
X662048Y870178D01*
G01X661952Y869631D02*
X662000Y869904D01*
G01X662048Y870178D02*
X662095Y870450D01*
G01X658101Y872981D02*
X658054Y872708D01*
G01X658148Y873254D02*
X658101Y872981D01*
G01X674637Y879073D02*
X664801Y869638D01*
G01X674376Y879050D02*
X664849Y869911D01*
G01X674113Y879025D02*
X664898Y870184D01*
G01X673852Y879001D02*
X664945Y870457D01*
G01X673589Y878977D02*
X664993Y870731D01*
G01X673258Y878887D02*
X665041Y871004D01*
G01X672926Y878795D02*
X665089Y871277D01*
G01X672593Y878702D02*
X665136Y871550D01*
G01X672192Y878545D02*
X665185Y871824D01*
G01X671721Y878322D02*
X665233Y872097D01*
G01X671072Y877925D02*
X665280Y872370D01*
G01X670665Y877762D02*
X665329Y872643D01*
G01X670714Y878036D02*
X665378Y872917D01*
G01X670761Y878309D02*
X665424Y873190D01*
G01X670809Y878582D02*
X665473Y873463D01*
G01X670738Y878741D02*
X665522Y873736D01*
G01X670501Y878741D02*
X665568Y874009D01*
G01X670263Y878741D02*
X665616Y874283D01*
G01X670027Y878741D02*
X665665Y874556D01*
G01X669791Y878741D02*
X665713Y874829D01*
G01X662531Y875639D02*
X656122Y869492D01*
G01X662475Y875815D02*
X655927Y869533D01*
G01X662410Y875977D02*
X655723Y869563D01*
G01X662342Y876140D02*
X655514Y869590D01*
G01X662274Y876303D02*
X655296Y869608D01*
G01X662208Y876466D02*
X655074Y869623D01*
G01X657849Y872511D02*
X654847Y869632D01*
G01X662142Y876629D02*
X658054Y872708D01*
G01X657690Y872586D02*
X654615Y869637D01*
G01X662059Y876777D02*
X658101Y872981D01*
G01X661957Y876907D02*
X658148Y873254D01*
G01X657531Y872660D02*
X654375Y869633D01*
G01X657360Y872725D02*
X654103Y869599D01*
G01X661857Y877037D02*
X658174Y873505D01*
G01X661755Y877167D02*
X658188Y873746D01*
G01X653830Y869565D02*
X657182Y872781D01*
G01X653558Y869531D02*
X657004Y872837D01*
G01X661653Y877297D02*
X658167Y873952D01*
G01X653277Y869489D02*
X656825Y872893D01*
G01X661553Y877427D02*
X658137Y874151D01*
G01X661450Y877558D02*
X658079Y874323D01*
G01X661318Y877657D02*
X658018Y874491D01*
G01X661187Y877758D02*
X657927Y874631D01*
G01X661054Y877858D02*
X657835Y874770D01*
G01X660921Y877958D02*
X657719Y874886D01*
G01X660788Y878058D02*
X657596Y874995D01*
G01X657107Y879071D02*
X652811Y874949D01*
G01X665329Y872643D02*
X665280Y872370D01*
G01D02*
X665233Y872097D01*
G01X665713Y874829D02*
X665665Y874556D01*
G01D02*
X665616Y874283D01*
G01X665713Y874829D02*
X665760Y875102D01*
G01X665616Y874283D02*
X665568Y874009D01*
G01X664993Y870731D02*
X664945Y870457D01*
G01X665041Y871004D02*
X664993Y870731D01*
G01X664945Y870457D02*
X664898Y870184D01*
G01X665568Y874009D02*
X665522Y873736D01*
G01X664898Y870184D02*
X664849Y869911D01*
G01D02*
X664801Y869638D01*
G01X665378Y872917D02*
X665329Y872643D01*
G01X665424Y873190D02*
X665378Y872917D01*
G01X665473Y873463D02*
X665424Y873190D01*
G01X665522Y873736D02*
X665473Y873463D01*
G01X665233Y872097D02*
X665185Y871824D01*
G01X665136Y871550D02*
X665089Y871277D01*
G01X665185Y871824D02*
X665136Y871550D01*
G01X665089Y871277D02*
X665041Y871004D01*
G01X662336Y871817D02*
X662288Y871543D01*
G01X662479Y872636D02*
X662432Y872363D01*
G01X662527Y872909D02*
X662479Y872636D01*
G01X662383Y872090D02*
X662336Y871817D01*
G01X662432Y872363D02*
X662383Y872090D01*
G01X662144Y870724D02*
X662192Y870998D01*
G01X662095Y870450D02*
X662144Y870724D01*
G01X662192Y870998D02*
X662239Y871270D01*
G01X662288Y871543D02*
X662239Y871270D01*
G01X662000Y869904D02*
X662048Y870178D01*
G01X661952Y869631D02*
X662000Y869904D01*
G01X662048Y870178D02*
X662095Y870450D01*
G01X658101Y872981D02*
X658054Y872708D01*
G01X658148Y873254D02*
X658101Y872981D01*
G01X669554Y878741D02*
X665760Y875102D01*
G01X669317Y878741D02*
X665809Y875376D01*
G01X669081Y878741D02*
X665857Y875649D01*
G01X668843Y878741D02*
X665904Y875922D01*
G01X668606Y878741D02*
X665953Y876195D01*
G01X668370Y878741D02*
X666000Y876468D01*
G01X668132Y878741D02*
X666048Y876742D01*
G01X667895Y878741D02*
X666097Y877014D01*
G01X667659Y878741D02*
X666144Y877288D01*
G01X667422Y878741D02*
X666192Y877562D01*
G01X667184Y878741D02*
X666240Y877834D01*
G01X666948Y878741D02*
X666288Y878108D01*
G01X666711Y878741D02*
X666335Y878381D01*
G01X666474Y878741D02*
X666384Y878654D01*
G01X660656Y878158D02*
X657461Y875093D01*
G01X660514Y878248D02*
X657308Y875173D01*
G01X660351Y878320D02*
X657154Y875253D01*
G01X660188Y878392D02*
X656971Y875305D01*
G01X660027Y878464D02*
X656786Y875354D01*
G01X659865Y878535D02*
X656587Y875391D01*
G01X659703Y878607D02*
X656368Y875408D01*
G01X659541Y878679D02*
X656149Y875425D01*
G01X659360Y878732D02*
X655911Y875423D01*
G01X659168Y878776D02*
X655668Y875419D01*
G01X658977Y878820D02*
X655426Y875414D01*
G01X658786Y878864D02*
X655173Y875398D01*
G01X658595Y878908D02*
X654919Y875381D01*
G01X658403Y878951D02*
X654657Y875358D01*
G01X658212Y878995D02*
X654384Y875322D01*
G01X657991Y879010D02*
X654107Y875284D01*
G01X657771Y879025D02*
X653808Y875224D01*
G01X657549Y879040D02*
X653500Y875156D01*
G01X657328Y879056D02*
X653167Y875064D01*
G01X668132Y878741D02*
X667895D01*
G01X666948D02*
X666711D01*
G01X667422D02*
X667184D01*
G01X667659D02*
X667422D01*
G01X667895D02*
X667659D01*
G01X667184D02*
X666948D01*
G01X668843D02*
X668606D01*
G01X668370D02*
X668132D01*
G01X666711D02*
X666474D01*
G01X668606D02*
X668370D01*
G01X665809Y875376D02*
X665857Y875649D01*
G01D02*
X665904Y875922D01*
G01X665953Y876195D02*
X666000Y876468D01*
G01X665760Y875102D02*
X665809Y875376D01*
G01X666000Y876468D02*
X666048Y876742D01*
G01X665904Y875922D02*
X665953Y876195D01*
G01X666399Y878741D02*
X666384Y878654D01*
G01X666474Y878741D02*
X666399D01*
G01X666335Y878381D02*
X666384Y878654D01*
G01X666097Y877014D02*
X666144Y877288D01*
G01X666048Y876742D02*
X666097Y877014D01*
G01X666288Y878108D02*
X666335Y878381D01*
G01X666144Y877288D02*
X666192Y877562D01*
G01D02*
X666240Y877834D01*
G01D02*
X666288Y878108D01*
G01X669554Y878741D02*
X665760Y875102D01*
G01X669317Y878741D02*
X665809Y875376D01*
G01X669081Y878741D02*
X665857Y875649D01*
G01X668843Y878741D02*
X665904Y875922D01*
G01X668606Y878741D02*
X665953Y876195D01*
G01X668370Y878741D02*
X666000Y876468D01*
G01X668132Y878741D02*
X666048Y876742D01*
G01X667895Y878741D02*
X666097Y877014D01*
G01X667659Y878741D02*
X666144Y877288D01*
G01X667422Y878741D02*
X666192Y877562D01*
G01X667184Y878741D02*
X666240Y877834D01*
G01X666948Y878741D02*
X666288Y878108D01*
G01X666711Y878741D02*
X666335Y878381D01*
G01X666474Y878741D02*
X666384Y878654D01*
G01X660656Y878158D02*
X657461Y875093D01*
G01X660514Y878248D02*
X657308Y875173D01*
G01X660351Y878320D02*
X657154Y875253D01*
G01X660188Y878392D02*
X656971Y875305D01*
G01X660027Y878464D02*
X656786Y875354D01*
G01X659865Y878535D02*
X656587Y875391D01*
G01X659703Y878607D02*
X656368Y875408D01*
G01X659541Y878679D02*
X656149Y875425D01*
G01X659360Y878732D02*
X655911Y875423D01*
G01X659168Y878776D02*
X655668Y875419D01*
G01X658977Y878820D02*
X655426Y875414D01*
G01X658786Y878864D02*
X655173Y875398D01*
G01X658595Y878908D02*
X654919Y875381D01*
G01X658403Y878951D02*
X654657Y875358D01*
G01X658212Y878995D02*
X654384Y875322D01*
G01X657991Y879010D02*
X654107Y875284D01*
G01X657771Y879025D02*
X653808Y875224D01*
G01X657549Y879040D02*
X653500Y875156D01*
G01X657328Y879056D02*
X653167Y875064D01*
G01X668132Y878741D02*
X667895D01*
G01X666948D02*
X666711D01*
G01X667422D02*
X667184D01*
G01X667659D02*
X667422D01*
G01X667895D02*
X667659D01*
G01X667184D02*
X666948D01*
G01X668843D02*
X668606D01*
G01X668370D02*
X668132D01*
G01X666711D02*
X666474D01*
G01X668606D02*
X668370D01*
G01X665809Y875376D02*
X665857Y875649D01*
G01D02*
X665904Y875922D01*
G01X665953Y876195D02*
X666000Y876468D01*
G01X665760Y875102D02*
X665809Y875376D01*
G01X666000Y876468D02*
X666048Y876742D01*
G01X665904Y875922D02*
X665953Y876195D01*
G01X666399Y878741D02*
X666384Y878654D01*
G01X666474Y878741D02*
X666399D01*
G01X666335Y878381D02*
X666384Y878654D01*
G01X666097Y877014D02*
X666144Y877288D01*
G01X666048Y876742D02*
X666097Y877014D01*
G01X666288Y878108D02*
X666335Y878381D01*
G01X666144Y877288D02*
X666192Y877562D01*
G01D02*
X666240Y877834D01*
G01D02*
X666288Y878108D01*
G01X685024Y862226D02*
X688852Y865898D01*
G01X684883Y862318D02*
X688700Y865980D01*
G01X684768Y862436D02*
X688583Y866094D01*
G01X684658Y862558D02*
X688483Y866226D01*
G01X684548Y862679D02*
X688406Y866379D01*
G01X684438Y862801D02*
X688355Y866558D01*
G01X684329Y862923D02*
X688318Y866749D01*
G01X684246Y863071D02*
X688311Y866969D01*
G01X684167Y863222D02*
X688309Y867196D01*
G01X684087Y863372D02*
X688338Y867449D01*
G01X684007Y863523D02*
X688370Y867708D01*
G01X683927Y863674D02*
X688414Y867978D01*
G01X678005Y861856D02*
X678081Y861928D01*
G01X677769Y861856D02*
X678130Y862202D01*
G01X677533Y861856D02*
X678178Y862475D01*
G01X677295Y861856D02*
X678225Y862748D01*
G01X677059Y861856D02*
X678274Y863021D01*
G01X676823Y861856D02*
X678321Y863294D01*
G01X676585Y861856D02*
X678369Y863568D01*
G01X676348Y861856D02*
X678418Y863842D01*
G01X676112Y861856D02*
X678465Y864114D01*
G01X675874Y861856D02*
X678513Y864387D01*
G01X675637Y861856D02*
X678561Y864661D01*
G01X675401Y861856D02*
X678609Y864934D01*
G01X675164Y861856D02*
X678656Y865207D01*
G01X674926Y861856D02*
X678705Y865480D01*
G01X674690Y861856D02*
X678753Y865753D01*
G01X674453Y861856D02*
X678800Y866027D01*
G01X674216Y861856D02*
X678849Y866299D01*
G01X673980Y861856D02*
X678896Y866573D01*
G01X673742Y861856D02*
X678944Y866846D01*
G01X673651Y861996D02*
X678993Y867120D01*
G01X673700Y862269D02*
X679040Y867392D01*
G01X673748Y862542D02*
X679088Y867665D01*
G01X673795Y862816D02*
X679136Y867938D01*
G01X673844Y863089D02*
X679184Y868212D01*
G01X673892Y863362D02*
X679231Y868485D01*
G01X673939Y863635D02*
X679280Y868758D01*
G01X675401Y861856D02*
X675637D01*
G01X676112D02*
X676348D01*
G01X675874D02*
X676112D01*
G01X675637D02*
X675874D01*
G01X676348D02*
X676585D01*
G01D02*
X676823D01*
G01D02*
X677059D01*
G01X673700Y862269D02*
X673651Y861996D01*
G01X673748Y862542D02*
X673700Y862269D01*
G01X673742Y861856D02*
X673980D01*
G01D02*
X674216D01*
G01X673795Y862816D02*
X673748Y862542D01*
G01X673627Y861856D02*
X673742D01*
G01X673651Y861996D02*
X673627Y861856D01*
G01X673892Y863362D02*
X673844Y863089D01*
G01D02*
X673795Y862816D01*
G01X675164Y861856D02*
X675401D01*
G01X674216D02*
X674453D01*
G01X674926D02*
X675164D01*
G01X674453D02*
X674690D01*
G01D02*
X674926D01*
G01X673939Y863635D02*
X673892Y863362D01*
G01X673988Y863909D02*
X673939Y863635D01*
G01X678274Y863021D02*
X678225Y862748D01*
G01X678178Y862475D02*
X678130Y862202D01*
G01X678225Y862748D02*
X678178Y862475D01*
G01X678130Y862202D02*
X678081Y861928D01*
G01X678069Y861856D02*
X678081Y861928D01*
G01X678005Y861856D02*
X678069D01*
G01X678369Y863568D02*
X678321Y863294D01*
G01D02*
X678274Y863021D01*
G01X678418Y863842D02*
X678369Y863568D01*
G01X677295Y861856D02*
X677533D01*
G01X677059D02*
X677295D01*
G01X677533D02*
X677769D01*
G01D02*
X678005D01*
G01X685024Y862226D02*
X688852Y865898D01*
G01X684883Y862318D02*
X688700Y865980D01*
G01X684768Y862436D02*
X688583Y866094D01*
G01X684658Y862558D02*
X688483Y866226D01*
G01X684548Y862679D02*
X688406Y866379D01*
G01X684438Y862801D02*
X688355Y866558D01*
G01X684329Y862923D02*
X688318Y866749D01*
G01X684246Y863071D02*
X688311Y866969D01*
G01X684167Y863222D02*
X688309Y867196D01*
G01X684087Y863372D02*
X688338Y867449D01*
G01X684007Y863523D02*
X688370Y867708D01*
G01X683927Y863674D02*
X688414Y867978D01*
G01X678005Y861856D02*
X678081Y861928D01*
G01X677769Y861856D02*
X678130Y862202D01*
G01X677533Y861856D02*
X678178Y862475D01*
G01X677295Y861856D02*
X678225Y862748D01*
G01X677059Y861856D02*
X678274Y863021D01*
G01X676823Y861856D02*
X678321Y863294D01*
G01X676585Y861856D02*
X678369Y863568D01*
G01X676348Y861856D02*
X678418Y863842D01*
G01X676112Y861856D02*
X678465Y864114D01*
G01X675874Y861856D02*
X678513Y864387D01*
G01X675637Y861856D02*
X678561Y864661D01*
G01X675401Y861856D02*
X678609Y864934D01*
G01X675164Y861856D02*
X678656Y865207D01*
G01X674926Y861856D02*
X678705Y865480D01*
G01X674690Y861856D02*
X678753Y865753D01*
G01X674453Y861856D02*
X678800Y866027D01*
G01X674216Y861856D02*
X678849Y866299D01*
G01X673980Y861856D02*
X678896Y866573D01*
G01X673742Y861856D02*
X678944Y866846D01*
G01X673651Y861996D02*
X678993Y867120D01*
G01X673700Y862269D02*
X679040Y867392D01*
G01X673748Y862542D02*
X679088Y867665D01*
G01X673795Y862816D02*
X679136Y867938D01*
G01X673844Y863089D02*
X679184Y868212D01*
G01X673892Y863362D02*
X679231Y868485D01*
G01X673939Y863635D02*
X679280Y868758D01*
G01X675401Y861856D02*
X675637D01*
G01X676112D02*
X676348D01*
G01X675874D02*
X676112D01*
G01X675637D02*
X675874D01*
G01X676348D02*
X676585D01*
G01D02*
X676823D01*
G01D02*
X677059D01*
G01X673700Y862269D02*
X673651Y861996D01*
G01X673748Y862542D02*
X673700Y862269D01*
G01X673742Y861856D02*
X673980D01*
G01D02*
X674216D01*
G01X673795Y862816D02*
X673748Y862542D01*
G01X673627Y861856D02*
X673742D01*
G01X673651Y861996D02*
X673627Y861856D01*
G01X673892Y863362D02*
X673844Y863089D01*
G01D02*
X673795Y862816D01*
G01X675164Y861856D02*
X675401D01*
G01X674216D02*
X674453D01*
G01X674926D02*
X675164D01*
G01X674453D02*
X674690D01*
G01D02*
X674926D01*
G01X673939Y863635D02*
X673892Y863362D01*
G01X673988Y863909D02*
X673939Y863635D01*
G01X678274Y863021D02*
X678225Y862748D01*
G01X678178Y862475D02*
X678130Y862202D01*
G01X678225Y862748D02*
X678178Y862475D01*
G01X678130Y862202D02*
X678081Y861928D01*
G01X678069Y861856D02*
X678081Y861928D01*
G01X678005Y861856D02*
X678069D01*
G01X678369Y863568D02*
X678321Y863294D01*
G01D02*
X678274Y863021D01*
G01X678418Y863842D02*
X678369Y863568D01*
G01X677295Y861856D02*
X677533D01*
G01X677059D02*
X677295D01*
G01X677533D02*
X677769D01*
G01D02*
X678005D01*
G01X668990Y868203D02*
X669037Y868476D01*
G01D02*
X669086Y868749D01*
G01X669135Y869023D02*
X669182Y869296D01*
G01X669086Y868749D02*
X669135Y869023D01*
G01X668893Y867656D02*
X668942Y867929D01*
G01D02*
X668990Y868203D01*
G01X668846Y867383D02*
X668893Y867656D01*
G01X669182Y869296D02*
X669230Y869570D01*
G01X668990Y868203D02*
X669037Y868476D01*
G01D02*
X669086Y868749D01*
G01X669135Y869023D02*
X669182Y869296D01*
G01X669086Y868749D02*
X669135Y869023D01*
G01X668893Y867656D02*
X668942Y867929D01*
G01D02*
X668990Y868203D01*
G01X668846Y867383D02*
X668893Y867656D01*
G01X669182Y869296D02*
X669230Y869570D01*
G01X676188Y878971D02*
X671732Y874696D01*
G01X675972Y878991D02*
X671270Y874480D01*
G01X669279Y869843D02*
X669230Y869570D01*
G01X669326Y870116D02*
X669279Y869843D01*
G01X669374Y870389D02*
X669326Y870116D01*
G01X669422Y870663D02*
X669374Y870389D01*
G01X669471Y870936D02*
X669422Y870663D01*
G01X676188Y878971D02*
X671732Y874696D01*
G01X675972Y878991D02*
X671270Y874480D01*
G01X669279Y869843D02*
X669230Y869570D01*
G01X669326Y870116D02*
X669279Y869843D01*
G01X669374Y870389D02*
X669326Y870116D01*
G01X669422Y870663D02*
X669374Y870389D01*
G01X669471Y870936D02*
X669422Y870663D01*
G01X683878Y863854D02*
X688463Y868251D01*
G01X683829Y864034D02*
X688510Y868524D01*
G01X683781Y864215D02*
X688559Y868798D01*
G01X683732Y864396D02*
X688606Y869072D01*
G01X683690Y864582D02*
X688654Y869344D01*
G01X683676Y864795D02*
X688703Y869617D01*
G01X683661Y865008D02*
X688750Y869891D01*
G01X683646Y865222D02*
X688799Y870165D01*
G01X683631Y865435D02*
X688846Y870437D01*
G01X683641Y865671D02*
X688894Y870710D01*
G01X683665Y865922D02*
X688943Y870984D01*
G01X683691Y866174D02*
X688990Y871257D01*
G01X683715Y866424D02*
X689039Y871531D01*
G01X683749Y866683D02*
X689087Y871803D01*
G01X683797Y866956D02*
X689134Y872077D01*
G01X683844Y867230D02*
X689183Y872351D01*
G01X689230Y872624D02*
X683893Y867503D01*
G01X683941Y867776D02*
X689279Y872896D01*
G01X683988Y868049D02*
X689327Y873170D01*
G01X684037Y868323D02*
X689375Y873444D01*
G01X684084Y868596D02*
X689423Y873716D01*
G01X684132Y868868D02*
X689470Y873990D01*
G01X684179Y869142D02*
X689519Y874263D01*
G01X684228Y869415D02*
X689567Y874537D01*
G01X673988Y863909D02*
X679328Y869032D01*
G01X674037Y864183D02*
X679375Y869305D01*
G01X674084Y864455D02*
X679424Y869578D01*
G01X674132Y864729D02*
X679471Y869851D01*
G01X674180Y865002D02*
X679519Y870124D01*
G01X674228Y865276D02*
X679568Y870398D01*
G01X674275Y865549D02*
X679615Y870671D01*
G01X674324Y865822D02*
X679663Y870943D01*
G01X674373Y866095D02*
X679712Y871217D01*
G01X674420Y866368D02*
X679752Y871484D01*
G01X674468Y866642D02*
X679783Y871741D01*
G01X674517Y866915D02*
X679815Y871997D01*
G01X674564Y867188D02*
X679846Y872255D01*
G01X674612Y867462D02*
X679877Y872513D01*
G01X674661Y867735D02*
X679910Y872770D01*
G01X674708Y868008D02*
X679939Y873027D01*
G01X674755Y868282D02*
X679945Y873259D01*
G01X679942Y873484D02*
X674804Y868555D01*
G01X674853Y868828D02*
X679941Y873710D01*
G01X674901Y869101D02*
X679939Y873935D01*
G01X674948Y869375D02*
X679937Y874161D01*
G01X683844Y867230D02*
X683797Y866956D01*
G01X684276Y869688D02*
X684228Y869415D01*
G01D02*
X684179Y869142D01*
G01D02*
X684132Y868868D01*
G01X684084Y868596D02*
X684037Y868323D01*
G01D02*
X683988Y868049D01*
G01X684132Y868868D02*
X684084Y868596D01*
G01X683988Y868049D02*
X683941Y867776D01*
G01X683844Y867230D02*
X683893Y867503D01*
G01X683941Y867776D02*
X683893Y867503D01*
G01X683797Y866956D02*
X683749Y866683D01*
G01X674275Y865549D02*
X674228Y865276D01*
G01X674708Y868008D02*
X674661Y867735D01*
G01D02*
X674612Y867462D01*
G01X674517Y866915D02*
X674468Y866642D01*
G01X674564Y867188D02*
X674517Y866915D01*
G01X674612Y867462D02*
X674564Y867188D01*
G01X674180Y865002D02*
X674132Y864729D01*
G01D02*
X674084Y864455D01*
G01X674468Y866642D02*
X674420Y866368D01*
G01X674084Y864455D02*
X674037Y864183D01*
G01D02*
X673988Y863909D01*
G01X674420Y866368D02*
X674373Y866095D01*
G01D02*
X674324Y865822D01*
G01X674228Y865276D02*
X674180Y865002D01*
G01X674324Y865822D02*
X674275Y865549D01*
G01X674755Y868282D02*
X674708Y868008D01*
G01X674997Y869648D02*
X674948Y869375D01*
G01X674853Y868828D02*
X674804Y868555D01*
G01X674948Y869375D02*
X674901Y869101D01*
G01X678800Y866027D02*
X678753Y865753D01*
G01X678849Y866299D02*
X678800Y866027D01*
G01X678944Y866846D02*
X678896Y866573D01*
G01X678993Y867120D02*
X678944Y866846D01*
G01X678896Y866573D02*
X678849Y866299D01*
G01X678513Y864387D02*
X678465Y864114D01*
G01X678609Y864934D02*
X678561Y864661D01*
G01D02*
X678513Y864387D01*
G01X678656Y865207D02*
X678609Y864934D01*
G01X678705Y865480D02*
X678656Y865207D01*
G01X678753Y865753D02*
X678705Y865480D01*
G01X678465Y864114D02*
X678418Y863842D01*
G01X679328Y869032D02*
X679280Y868758D01*
G01X679424Y869578D02*
X679375Y869305D01*
G01X679040Y867392D02*
X678993Y867120D01*
G01X679184Y868212D02*
X679136Y867938D01*
G01X679231Y868485D02*
X679184Y868212D01*
G01X679136Y867938D02*
X679088Y867665D01*
G01D02*
X679040Y867392D01*
G01X679375Y869305D02*
X679328Y869032D01*
G01X679280Y868758D02*
X679231Y868485D01*
G01X674755Y868282D02*
X674804Y868555D01*
G01X674901Y869101D02*
X674853Y868828D01*
G01X683878Y863854D02*
X688463Y868251D01*
G01X683829Y864034D02*
X688510Y868524D01*
G01X683781Y864215D02*
X688559Y868798D01*
G01X683732Y864396D02*
X688606Y869072D01*
G01X683690Y864582D02*
X688654Y869344D01*
G01X683676Y864795D02*
X688703Y869617D01*
G01X683661Y865008D02*
X688750Y869891D01*
G01X683646Y865222D02*
X688799Y870165D01*
G01X683631Y865435D02*
X688846Y870437D01*
G01X683641Y865671D02*
X688894Y870710D01*
G01X683665Y865922D02*
X688943Y870984D01*
G01X683691Y866174D02*
X688990Y871257D01*
G01X683715Y866424D02*
X689039Y871531D01*
G01X683749Y866683D02*
X689087Y871803D01*
G01X683797Y866956D02*
X689134Y872077D01*
G01X683844Y867230D02*
X689183Y872351D01*
G01X689230Y872624D02*
X683893Y867503D01*
G01X683941Y867776D02*
X689279Y872896D01*
G01X683988Y868049D02*
X689327Y873170D01*
G01X684037Y868323D02*
X689375Y873444D01*
G01X684084Y868596D02*
X689423Y873716D01*
G01X684132Y868868D02*
X689470Y873990D01*
G01X684179Y869142D02*
X689519Y874263D01*
G01X684228Y869415D02*
X689567Y874537D01*
G01X673988Y863909D02*
X679328Y869032D01*
G01X674037Y864183D02*
X679375Y869305D01*
G01X674084Y864455D02*
X679424Y869578D01*
G01X674132Y864729D02*
X679471Y869851D01*
G01X674180Y865002D02*
X679519Y870124D01*
G01X674228Y865276D02*
X679568Y870398D01*
G01X674275Y865549D02*
X679615Y870671D01*
G01X674324Y865822D02*
X679663Y870943D01*
G01X674373Y866095D02*
X679712Y871217D01*
G01X674420Y866368D02*
X679752Y871484D01*
G01X674468Y866642D02*
X679783Y871741D01*
G01X674517Y866915D02*
X679815Y871997D01*
G01X674564Y867188D02*
X679846Y872255D01*
G01X674612Y867462D02*
X679877Y872513D01*
G01X674661Y867735D02*
X679910Y872770D01*
G01X674708Y868008D02*
X679939Y873027D01*
G01X674755Y868282D02*
X679945Y873259D01*
G01X679942Y873484D02*
X674804Y868555D01*
G01X674853Y868828D02*
X679941Y873710D01*
G01X674901Y869101D02*
X679939Y873935D01*
G01X674948Y869375D02*
X679937Y874161D01*
G01X683844Y867230D02*
X683797Y866956D01*
G01X684276Y869688D02*
X684228Y869415D01*
G01D02*
X684179Y869142D01*
G01D02*
X684132Y868868D01*
G01X684084Y868596D02*
X684037Y868323D01*
G01D02*
X683988Y868049D01*
G01X684132Y868868D02*
X684084Y868596D01*
G01X683988Y868049D02*
X683941Y867776D01*
G01X683844Y867230D02*
X683893Y867503D01*
G01X683941Y867776D02*
X683893Y867503D01*
G01X683797Y866956D02*
X683749Y866683D01*
G01X674275Y865549D02*
X674228Y865276D01*
G01X674708Y868008D02*
X674661Y867735D01*
G01D02*
X674612Y867462D01*
G01X674517Y866915D02*
X674468Y866642D01*
G01X674564Y867188D02*
X674517Y866915D01*
G01X674612Y867462D02*
X674564Y867188D01*
G01X674180Y865002D02*
X674132Y864729D01*
G01D02*
X674084Y864455D01*
G01X674468Y866642D02*
X674420Y866368D01*
G01X674084Y864455D02*
X674037Y864183D01*
G01D02*
X673988Y863909D01*
G01X674420Y866368D02*
X674373Y866095D01*
G01D02*
X674324Y865822D01*
G01X674228Y865276D02*
X674180Y865002D01*
G01X674324Y865822D02*
X674275Y865549D01*
G01X674755Y868282D02*
X674708Y868008D01*
G01X674997Y869648D02*
X674948Y869375D01*
G01X674853Y868828D02*
X674804Y868555D01*
G01X674948Y869375D02*
X674901Y869101D01*
G01X678800Y866027D02*
X678753Y865753D01*
G01X678849Y866299D02*
X678800Y866027D01*
G01X678944Y866846D02*
X678896Y866573D01*
G01X678993Y867120D02*
X678944Y866846D01*
G01X678896Y866573D02*
X678849Y866299D01*
G01X678513Y864387D02*
X678465Y864114D01*
G01X678609Y864934D02*
X678561Y864661D01*
G01D02*
X678513Y864387D01*
G01X678656Y865207D02*
X678609Y864934D01*
G01X678705Y865480D02*
X678656Y865207D01*
G01X678753Y865753D02*
X678705Y865480D01*
G01X678465Y864114D02*
X678418Y863842D01*
G01X679328Y869032D02*
X679280Y868758D01*
G01X679424Y869578D02*
X679375Y869305D01*
G01X679040Y867392D02*
X678993Y867120D01*
G01X679184Y868212D02*
X679136Y867938D01*
G01X679231Y868485D02*
X679184Y868212D01*
G01X679136Y867938D02*
X679088Y867665D01*
G01D02*
X679040Y867392D01*
G01X679375Y869305D02*
X679328Y869032D01*
G01X679280Y868758D02*
X679231Y868485D01*
G01X674755Y868282D02*
X674804Y868555D01*
G01X674901Y869101D02*
X674853Y868828D01*
G01X684276Y869688D02*
X693713Y878741D01*
G01X693477D02*
X684323Y869961D01*
G01X693240Y878741D02*
X684372Y870235D01*
G01X693002Y878741D02*
X684419Y870508D01*
G01X692765Y878741D02*
X684467Y870781D01*
G01X692529Y878741D02*
X684516Y871053D01*
G01X692292Y878741D02*
X684563Y871327D01*
G01X692054Y878741D02*
X684611Y871601D01*
G01X691818Y878741D02*
X684659Y871874D01*
G01X691581Y878741D02*
X684707Y872146D01*
G01X691345Y878741D02*
X684754Y872420D01*
G01X691107Y878741D02*
X684803Y872693D01*
G01X690870Y878741D02*
X684851Y872966D01*
G01X690634Y878741D02*
X684898Y873239D01*
G01X690397Y878741D02*
X684947Y873512D01*
G01X684994Y873786D02*
X690330Y878905D01*
G01X690379Y879178D02*
X685042Y874059D01*
G01X684853Y874559D02*
X690523Y879998D01*
G01X684616Y874559D02*
X690570Y880271D01*
G01X684380Y874559D02*
X690619Y880544D01*
G01X684143Y874559D02*
X690667Y880818D01*
G01X683905Y874559D02*
X690716Y881091D01*
G01X683669Y874559D02*
X690763Y881364D01*
G01X683432Y874559D02*
X690810Y881637D01*
G01X683196Y874559D02*
X690859Y881911D01*
G01X682959Y874559D02*
X690907Y882185D01*
G01X682721Y874559D02*
X690954Y882457D01*
G01X682485Y874559D02*
X691003Y882730D01*
G01X682312Y874620D02*
X691051Y883004D01*
G01X691099Y883278D02*
X682359Y874894D01*
G01X674997Y869648D02*
X679937Y874386D01*
G01X675044Y869921D02*
X679931Y874608D01*
G01X675092Y870194D02*
X679896Y874802D01*
G01X675141Y870468D02*
X679861Y874996D01*
G01X679825Y875190D02*
X675190Y870741D01*
G01X679792Y875383D02*
X675236Y871013D01*
G01X679756Y875577D02*
X675268Y871272D01*
G01X679722Y875771D02*
X675303Y871532D01*
G01X679676Y875956D02*
X675336Y871792D01*
G01X679608Y876117D02*
X675367Y872048D01*
G01X679541Y876279D02*
X675369Y872277D01*
G01X679471Y876440D02*
X675371Y872507D01*
G01X679402Y876602D02*
X675374Y872736D01*
G01X679334Y876763D02*
X675363Y872953D01*
G01X679267Y876924D02*
X675331Y873149D01*
G01X679183Y877073D02*
X675298Y873345D01*
G01X679079Y877201D02*
X675265Y873541D01*
G01X678976Y877329D02*
X675199Y873705D01*
G01X678873Y877457D02*
X675130Y873865D01*
G01X678770Y877586D02*
X675059Y874025D01*
G01X678667Y877714D02*
X674964Y874163D01*
G01X678564Y877842D02*
X674856Y874285D01*
G01X678445Y877954D02*
X674747Y874408D01*
G01X678305Y878048D02*
X674620Y874513D01*
G01X678165Y878141D02*
X674471Y874597D01*
G01X678027Y878236D02*
X674324Y874683D01*
G01X677889Y878329D02*
X674157Y874750D01*
G01X677750Y878424D02*
X673972Y874799D01*
G01X677611Y878518D02*
X673784Y874848D01*
G01X677449Y878590D02*
X673581Y874879D01*
G01X677274Y878649D02*
X673360Y874894D01*
G01X677097Y878707D02*
X673139Y874909D01*
G01X676920Y878765D02*
X672896Y874904D01*
G01X676744Y878823D02*
X672641Y874886D01*
G01X676568Y878881D02*
X672385Y874867D01*
G01X676391Y878939D02*
X672069Y874792D01*
G01X684994Y873786D02*
X684947Y873512D01*
G01X684853Y874559D02*
X685091D01*
G01Y874331D02*
X685042Y874059D01*
G01D02*
X684994Y873786D01*
G01X684898Y873239D02*
X684851Y872966D01*
G01X684947Y873512D02*
X684898Y873239D01*
G01X683669Y874559D02*
X683905D01*
G01X683432D02*
X683669D01*
G01X683196D02*
X683432D01*
G01X684380D02*
X684616D01*
G01X683905D02*
X684143D01*
G01D02*
X684380D01*
G01X684851Y872966D02*
X684803Y872693D01*
G01X684372Y870235D02*
X684323Y869961D01*
G01X684467Y870781D02*
X684419Y870508D01*
G01D02*
X684372Y870235D01*
G01X684323Y869961D02*
X684276Y869688D01*
G01X684516Y871053D02*
X684467Y870781D01*
G01X684659Y871874D02*
X684611Y871601D01*
G01X684707Y872146D02*
X684659Y871874D01*
G01X684754Y872420D02*
X684707Y872146D01*
G01X684803Y872693D02*
X684754Y872420D01*
G01X684563Y871327D02*
X684516Y871053D01*
G01X684611Y871601D02*
X684563Y871327D01*
G01X684616Y874559D02*
X684853D01*
G01X682959D02*
X683196D01*
G01X682408Y875167D02*
X682359Y874894D01*
G01D02*
X682312Y874620D01*
G01X682721Y874559D02*
X682959D01*
G01X682301D02*
X682485D01*
G01X682312Y874620D02*
X682301Y874559D01*
G01X682485D02*
X682721D01*
G01X675190Y870741D02*
X675141Y870468D01*
G01X679615Y870671D02*
X679568Y870398D01*
G01X679663Y870943D02*
X679615Y870671D01*
G01X675141Y870468D02*
X675092Y870194D01*
G01X679519Y870124D02*
X679471Y869851D01*
G01D02*
X679424Y869578D01*
G01X679568Y870398D02*
X679519Y870124D01*
G01X675044Y869921D02*
X674997Y869648D01*
G01X679712Y871217D02*
X679663Y870943D01*
G01X675092Y870194D02*
X675044Y869921D01*
G01X684276Y869688D02*
X693713Y878741D01*
G01X693477D02*
X684323Y869961D01*
G01X693240Y878741D02*
X684372Y870235D01*
G01X693002Y878741D02*
X684419Y870508D01*
G01X692765Y878741D02*
X684467Y870781D01*
G01X692529Y878741D02*
X684516Y871053D01*
G01X692292Y878741D02*
X684563Y871327D01*
G01X692054Y878741D02*
X684611Y871601D01*
G01X691818Y878741D02*
X684659Y871874D01*
G01X691581Y878741D02*
X684707Y872146D01*
G01X691345Y878741D02*
X684754Y872420D01*
G01X691107Y878741D02*
X684803Y872693D01*
G01X690870Y878741D02*
X684851Y872966D01*
G01X690634Y878741D02*
X684898Y873239D01*
G01X690397Y878741D02*
X684947Y873512D01*
G01X684994Y873786D02*
X690330Y878905D01*
G01X690379Y879178D02*
X685042Y874059D01*
G01X684853Y874559D02*
X690523Y879998D01*
G01X684616Y874559D02*
X690570Y880271D01*
G01X684380Y874559D02*
X690619Y880544D01*
G01X684143Y874559D02*
X690667Y880818D01*
G01X683905Y874559D02*
X690716Y881091D01*
G01X683669Y874559D02*
X690763Y881364D01*
G01X683432Y874559D02*
X690810Y881637D01*
G01X683196Y874559D02*
X690859Y881911D01*
G01X682959Y874559D02*
X690907Y882185D01*
G01X682721Y874559D02*
X690954Y882457D01*
G01X682485Y874559D02*
X691003Y882730D01*
G01X682312Y874620D02*
X691051Y883004D01*
G01X691099Y883278D02*
X682359Y874894D01*
G01X674997Y869648D02*
X679937Y874386D01*
G01X675044Y869921D02*
X679931Y874608D01*
G01X675092Y870194D02*
X679896Y874802D01*
G01X675141Y870468D02*
X679861Y874996D01*
G01X679825Y875190D02*
X675190Y870741D01*
G01X679792Y875383D02*
X675236Y871013D01*
G01X679756Y875577D02*
X675268Y871272D01*
G01X679722Y875771D02*
X675303Y871532D01*
G01X679676Y875956D02*
X675336Y871792D01*
G01X679608Y876117D02*
X675367Y872048D01*
G01X679541Y876279D02*
X675369Y872277D01*
G01X679471Y876440D02*
X675371Y872507D01*
G01X679402Y876602D02*
X675374Y872736D01*
G01X679334Y876763D02*
X675363Y872953D01*
G01X679267Y876924D02*
X675331Y873149D01*
G01X679183Y877073D02*
X675298Y873345D01*
G01X679079Y877201D02*
X675265Y873541D01*
G01X678976Y877329D02*
X675199Y873705D01*
G01X678873Y877457D02*
X675130Y873865D01*
G01X678770Y877586D02*
X675059Y874025D01*
G01X678667Y877714D02*
X674964Y874163D01*
G01X678564Y877842D02*
X674856Y874285D01*
G01X678445Y877954D02*
X674747Y874408D01*
G01X678305Y878048D02*
X674620Y874513D01*
G01X678165Y878141D02*
X674471Y874597D01*
G01X678027Y878236D02*
X674324Y874683D01*
G01X677889Y878329D02*
X674157Y874750D01*
G01X677750Y878424D02*
X673972Y874799D01*
G01X677611Y878518D02*
X673784Y874848D01*
G01X677449Y878590D02*
X673581Y874879D01*
G01X677274Y878649D02*
X673360Y874894D01*
G01X677097Y878707D02*
X673139Y874909D01*
G01X676920Y878765D02*
X672896Y874904D01*
G01X676744Y878823D02*
X672641Y874886D01*
G01X676568Y878881D02*
X672385Y874867D01*
G01X676391Y878939D02*
X672069Y874792D01*
G01X684994Y873786D02*
X684947Y873512D01*
G01X684853Y874559D02*
X685091D01*
G01Y874331D02*
X685042Y874059D01*
G01D02*
X684994Y873786D01*
G01X684898Y873239D02*
X684851Y872966D01*
G01X684947Y873512D02*
X684898Y873239D01*
G01X683669Y874559D02*
X683905D01*
G01X683432D02*
X683669D01*
G01X683196D02*
X683432D01*
G01X684380D02*
X684616D01*
G01X683905D02*
X684143D01*
G01D02*
X684380D01*
G01X684851Y872966D02*
X684803Y872693D01*
G01X684372Y870235D02*
X684323Y869961D01*
G01X684467Y870781D02*
X684419Y870508D01*
G01D02*
X684372Y870235D01*
G01X684323Y869961D02*
X684276Y869688D01*
G01X684516Y871053D02*
X684467Y870781D01*
G01X684659Y871874D02*
X684611Y871601D01*
G01X684707Y872146D02*
X684659Y871874D01*
G01X684754Y872420D02*
X684707Y872146D01*
G01X684803Y872693D02*
X684754Y872420D01*
G01X684563Y871327D02*
X684516Y871053D01*
G01X684611Y871601D02*
X684563Y871327D01*
G01X684616Y874559D02*
X684853D01*
G01X682959D02*
X683196D01*
G01X682408Y875167D02*
X682359Y874894D01*
G01D02*
X682312Y874620D01*
G01X682721Y874559D02*
X682959D01*
G01X682301D02*
X682485D01*
G01X682312Y874620D02*
X682301Y874559D01*
G01X682485D02*
X682721D01*
G01X675190Y870741D02*
X675141Y870468D01*
G01X679615Y870671D02*
X679568Y870398D01*
G01X679663Y870943D02*
X679615Y870671D01*
G01X675141Y870468D02*
X675092Y870194D01*
G01X679519Y870124D02*
X679471Y869851D01*
G01D02*
X679424Y869578D01*
G01X679568Y870398D02*
X679519Y870124D01*
G01X675044Y869921D02*
X674997Y869648D01*
G01X679712Y871217D02*
X679663Y870943D01*
G01X675092Y870194D02*
X675044Y869921D01*
G01X670837Y878741D02*
X670738D01*
G01X670809Y878582D02*
X670837Y878741D01*
G01X670761Y878309D02*
X670809Y878582D01*
G01X670665Y877762D02*
X670714Y878036D01*
G01D02*
X670761Y878309D01*
G01X670263Y878741D02*
X670027D01*
G01D02*
X669791D01*
G01X670738D02*
X670501D01*
G01D02*
X670263D01*
G01X669791D02*
X669554D01*
G01D02*
X669317D01*
G01X669081D02*
X668843D01*
G01X669317D02*
X669081D01*
G01X670837D02*
X670738D01*
G01X670809Y878582D02*
X670837Y878741D01*
G01X670761Y878309D02*
X670809Y878582D01*
G01X670665Y877762D02*
X670714Y878036D01*
G01D02*
X670761Y878309D01*
G01X670263Y878741D02*
X670027D01*
G01D02*
X669791D01*
G01X670738D02*
X670501D01*
G01D02*
X670263D01*
G01X669791D02*
X669554D01*
G01D02*
X669317D01*
G01X669081D02*
X668843D01*
G01X669317D02*
X669081D01*
G01X691147Y883551D02*
X682408Y875167D01*
G01X691196Y883823D02*
X682455Y875440D01*
G01X682504Y875714D02*
X685659Y878741D01*
G01X682552Y875987D02*
X685423Y878741D01*
G01X682599Y876260D02*
X685186Y878741D01*
G01X682648Y876533D02*
X684950Y878741D01*
G01X682695Y876807D02*
X684712Y878741D01*
G01X682744Y877080D02*
X684475Y878741D01*
G01X682792Y877353D02*
X684239Y878741D01*
G01X682841Y877626D02*
X684002Y878741D01*
G01X683764D02*
X682888Y877900D01*
G01X682936Y878173D02*
X683528Y878741D01*
G01X682984Y878447D02*
X683291Y878741D01*
G01X683032Y878719D02*
X683055Y878741D01*
G01X682599Y876260D02*
X682648Y876533D01*
G01X682936Y878173D02*
X682984Y878447D01*
G01X682888Y877900D02*
X682841Y877626D01*
G01X682936Y878173D02*
X682888Y877900D01*
G01X682695Y876807D02*
X682744Y877080D01*
G01X682792Y877353D02*
X682841Y877626D01*
G01X682744Y877080D02*
X682792Y877353D01*
G01X685186Y878741D02*
X684950D01*
G01X682552Y875987D02*
X682599Y876260D01*
G01X682504Y875714D02*
X682552Y875987D01*
G01X682648Y876533D02*
X682695Y876807D01*
G01X682455Y875440D02*
X682408Y875167D01*
G01X682455Y875440D02*
X682504Y875714D01*
G01X684712Y878741D02*
X684475D01*
G01X684950D02*
X684712D01*
G01X682984Y878447D02*
X683032Y878719D01*
G01X683036Y878741D02*
X683055D01*
G01X683032Y878719D02*
X683036Y878741D01*
G01X683528D02*
X683291D01*
G01D02*
X683055D01*
G01X684239D02*
X684002D01*
G01X684475D02*
X684239D01*
G01X683528D02*
X683764D01*
G01D02*
X684002D01*
G01X691147Y883551D02*
X682408Y875167D01*
G01X691196Y883823D02*
X682455Y875440D01*
G01X682504Y875714D02*
X685659Y878741D01*
G01X682552Y875987D02*
X685423Y878741D01*
G01X682599Y876260D02*
X685186Y878741D01*
G01X682648Y876533D02*
X684950Y878741D01*
G01X682695Y876807D02*
X684712Y878741D01*
G01X682744Y877080D02*
X684475Y878741D01*
G01X682792Y877353D02*
X684239Y878741D01*
G01X682841Y877626D02*
X684002Y878741D01*
G01X683764D02*
X682888Y877900D01*
G01X682936Y878173D02*
X683528Y878741D01*
G01X682984Y878447D02*
X683291Y878741D01*
G01X683032Y878719D02*
X683055Y878741D01*
G01X682599Y876260D02*
X682648Y876533D01*
G01X682936Y878173D02*
X682984Y878447D01*
G01X682888Y877900D02*
X682841Y877626D01*
G01X682936Y878173D02*
X682888Y877900D01*
G01X682695Y876807D02*
X682744Y877080D01*
G01X682792Y877353D02*
X682841Y877626D01*
G01X682744Y877080D02*
X682792Y877353D01*
G01X685186Y878741D02*
X684950D01*
G01X682552Y875987D02*
X682599Y876260D01*
G01X682504Y875714D02*
X682552Y875987D01*
G01X682648Y876533D02*
X682695Y876807D01*
G01X682455Y875440D02*
X682408Y875167D01*
G01X682455Y875440D02*
X682504Y875714D01*
G01X684712Y878741D02*
X684475D01*
G01X684950D02*
X684712D01*
G01X682984Y878447D02*
X683032Y878719D01*
G01X683036Y878741D02*
X683055D01*
G01X683032Y878719D02*
X683036Y878741D01*
G01X683528D02*
X683291D01*
G01D02*
X683055D01*
G01X684239D02*
X684002D01*
G01X684475D02*
X684239D01*
G01X683528D02*
X683764D01*
G01D02*
X684002D01*
G01X686693Y81575D02*
G02X694567I3937J0D01*
G02X686693I-3937J0D01*
G01X701280Y861688D02*
X709512Y869584D01*
G01X700961Y861610D02*
X709559Y869858D01*
G01X700697Y861583D02*
X709607Y870131D01*
G01X700434Y861559D02*
X709654Y870404D01*
G01X700171Y861532D02*
X709703Y870676D01*
G01X699906Y861507D02*
X709750Y870950D01*
G01X699673Y861510D02*
X709798Y871223D01*
G01X699445Y861518D02*
X709847Y871496D01*
G01X709894Y871769D02*
X699222Y861532D01*
G01X699011Y861556D02*
X703648Y866005D01*
G01X698801Y861582D02*
X703076Y865683D01*
G01X698599Y861614D02*
X702695Y865544D01*
G01X698403Y861654D02*
X702314Y865405D01*
G01X698208Y861694D02*
X702031Y865363D01*
G01X698022Y861745D02*
X701759Y865329D01*
G01X697842Y861798D02*
X701488Y865296D01*
G01X697661Y861852D02*
X701219Y865265D01*
G01X697492Y861917D02*
X700999Y865281D01*
G01X697325Y861985D02*
X700780Y865298D01*
G01X697158Y862052D02*
X700563Y865317D01*
G01X697002Y862129D02*
X700377Y865366D01*
G01X696849Y862210D02*
X700191Y865414D01*
G01X696697Y862291D02*
X700013Y865473D01*
G01X696552Y862379D02*
X699861Y865553D01*
G01X696415Y862473D02*
X699708Y865633D01*
G01X696275Y862568D02*
X699575Y865734D01*
G01X696142Y862668D02*
X699456Y865846D01*
G01X696019Y862775D02*
X699339Y865962D01*
G01X695894Y862883D02*
X699252Y866105D01*
G01X695772Y862994D02*
X699167Y866250D01*
G01X695662Y863116D02*
X699107Y866421D01*
G01X695554Y863238D02*
X699056Y866598D01*
G01X695444Y863361D02*
X699027Y866797D01*
G01X695349Y863496D02*
X699011Y867010D01*
G01X695254Y863633D02*
X699023Y867249D01*
G01X690547Y862299D02*
X691040Y862771D01*
G01X690063Y862061D02*
X691144Y863099D01*
G01X689677Y861918D02*
X691249Y863426D01*
G01X689305Y861788D02*
X691352Y863753D01*
G01X688997Y861719D02*
X691456Y864079D01*
G01X688688Y861651D02*
X691561Y864406D01*
G01X688380Y861583D02*
X691665Y864734D01*
G01X688122Y861562D02*
X691768Y865060D01*
G01X687864Y861543D02*
X691872Y865387D01*
G01X687607Y861524D02*
X691976Y865714D01*
G01X687349Y861502D02*
X692080Y866042D01*
G01X687135Y861524D02*
X692184Y866368D01*
G01X686920Y861545D02*
X692288Y866695D01*
G01X686705Y861567D02*
X692392Y867022D01*
G01X686491Y861589D02*
X691539Y866431D01*
G01X686297Y861629D02*
X690947Y866090D01*
G01X686122Y861689D02*
X690534Y865921D01*
G01X685947Y861747D02*
X690180Y865809D01*
G01X685770Y861807D02*
X689910Y865777D01*
G01X685597Y861865D02*
X689644Y865749D01*
G01X685448Y861949D02*
X689420Y865761D01*
G01X685306Y862042D02*
X689210Y865787D01*
G01X685164Y862134D02*
X689016Y865829D01*
G01X691352Y863753D02*
X691249Y863426D01*
G01D02*
X691144Y863099D01*
G01D02*
X691040Y862771D01*
G01X701280Y861688D02*
X709512Y869584D01*
G01X700961Y861610D02*
X709559Y869858D01*
G01X700697Y861583D02*
X709607Y870131D01*
G01X700434Y861559D02*
X709654Y870404D01*
G01X700171Y861532D02*
X709703Y870676D01*
G01X699906Y861507D02*
X709750Y870950D01*
G01X699673Y861510D02*
X709798Y871223D01*
G01X699445Y861518D02*
X709847Y871496D01*
G01X709894Y871769D02*
X699222Y861532D01*
G01X699011Y861556D02*
X703648Y866005D01*
G01X698801Y861582D02*
X703076Y865683D01*
G01X698599Y861614D02*
X702695Y865544D01*
G01X698403Y861654D02*
X702314Y865405D01*
G01X698208Y861694D02*
X702031Y865363D01*
G01X698022Y861745D02*
X701759Y865329D01*
G01X697842Y861798D02*
X701488Y865296D01*
G01X697661Y861852D02*
X701219Y865265D01*
G01X697492Y861917D02*
X700999Y865281D01*
G01X697325Y861985D02*
X700780Y865298D01*
G01X697158Y862052D02*
X700563Y865317D01*
G01X697002Y862129D02*
X700377Y865366D01*
G01X696849Y862210D02*
X700191Y865414D01*
G01X696697Y862291D02*
X700013Y865473D01*
G01X696552Y862379D02*
X699861Y865553D01*
G01X696415Y862473D02*
X699708Y865633D01*
G01X696275Y862568D02*
X699575Y865734D01*
G01X696142Y862668D02*
X699456Y865846D01*
G01X696019Y862775D02*
X699339Y865962D01*
G01X695894Y862883D02*
X699252Y866105D01*
G01X695772Y862994D02*
X699167Y866250D01*
G01X695662Y863116D02*
X699107Y866421D01*
G01X695554Y863238D02*
X699056Y866598D01*
G01X695444Y863361D02*
X699027Y866797D01*
G01X695349Y863496D02*
X699011Y867010D01*
G01X695254Y863633D02*
X699023Y867249D01*
G01X690547Y862299D02*
X691040Y862771D01*
G01X690063Y862061D02*
X691144Y863099D01*
G01X689677Y861918D02*
X691249Y863426D01*
G01X689305Y861788D02*
X691352Y863753D01*
G01X688997Y861719D02*
X691456Y864079D01*
G01X688688Y861651D02*
X691561Y864406D01*
G01X688380Y861583D02*
X691665Y864734D01*
G01X688122Y861562D02*
X691768Y865060D01*
G01X687864Y861543D02*
X691872Y865387D01*
G01X687607Y861524D02*
X691976Y865714D01*
G01X687349Y861502D02*
X692080Y866042D01*
G01X687135Y861524D02*
X692184Y866368D01*
G01X686920Y861545D02*
X692288Y866695D01*
G01X686705Y861567D02*
X692392Y867022D01*
G01X686491Y861589D02*
X691539Y866431D01*
G01X686297Y861629D02*
X690947Y866090D01*
G01X686122Y861689D02*
X690534Y865921D01*
G01X685947Y861747D02*
X690180Y865809D01*
G01X685770Y861807D02*
X689910Y865777D01*
G01X685597Y861865D02*
X689644Y865749D01*
G01X685448Y861949D02*
X689420Y865761D01*
G01X685306Y862042D02*
X689210Y865787D01*
G01X685164Y862134D02*
X689016Y865829D01*
G01X691352Y863753D02*
X691249Y863426D01*
G01D02*
X691144Y863099D01*
G01D02*
X691040Y862771D01*
G01X695160Y863770D02*
X699049Y867500D01*
G01X695077Y863918D02*
X699167Y867841D01*
G01X695000Y864071D02*
X699293Y868189D01*
G01X700459Y869308D02*
X704233Y872928D01*
G01X694923Y864224D02*
X699955Y869052D01*
G01X699994Y869089D02*
X704032Y872963D01*
G01X694852Y864384D02*
X703833Y872998D01*
G01X694793Y864554D02*
X703632Y873033D01*
G01X694733Y864724D02*
X703423Y873061D01*
G01X694679Y864899D02*
X703199Y873072D01*
G01X694638Y865087D02*
X702974Y873084D01*
G01X694599Y865275D02*
X702750Y873096D01*
G01X694561Y865466D02*
X702527Y873108D01*
G01X694542Y865676D02*
X702282Y873102D01*
G01X694523Y865885D02*
X702030Y873086D01*
G01X701776Y873071D02*
X694505Y866095D01*
G01X694511Y866328D02*
X701523Y873054D01*
G01X694516Y866560D02*
X701269Y873039D01*
G01X694523Y866794D02*
X701013Y873020D01*
G01X694555Y867053D02*
X700716Y872962D01*
G01X694589Y867312D02*
X700417Y872903D01*
G01X694633Y867582D02*
X700119Y872844D01*
G01X694719Y867892D02*
X699822Y872786D01*
G01X694806Y868202D02*
X699479Y872685D01*
G01X694894Y868513D02*
X699104Y872553D01*
G01X694981Y868824D02*
X698730Y872420D01*
G01X695216Y869277D02*
X698307Y872243D01*
G01X691768Y865060D02*
X691665Y864734D01*
G01X691872Y865387D02*
X691768Y865060D01*
G01X691665Y864734D02*
X691561Y864406D01*
G01X691976Y865714D02*
X691872Y865387D01*
G01X691561Y864406D02*
X691456Y864079D01*
G01X692080Y866042D02*
X691976Y865714D01*
G01X691456Y864079D02*
X691352Y863753D01*
G01X692184Y866368D02*
X692080Y866042D01*
G01X692288Y866695D02*
X692184Y866368D01*
G01X692392Y867022D02*
X692288Y866695D01*
G01X688510Y868524D02*
X688463Y868251D01*
G01D02*
X688414Y867978D01*
G01X688559Y868798D02*
X688606Y869072D01*
G01D02*
X688654Y869344D01*
G01X688559Y868798D02*
X688510Y868524D01*
G01X688654Y869344D02*
X688703Y869617D01*
G01X695160Y863770D02*
X699049Y867500D01*
G01X695077Y863918D02*
X699167Y867841D01*
G01X695000Y864071D02*
X699293Y868189D01*
G01X700459Y869308D02*
X704233Y872928D01*
G01X694923Y864224D02*
X699955Y869052D01*
G01X699994Y869089D02*
X704032Y872963D01*
G01X694852Y864384D02*
X703833Y872998D01*
G01X694793Y864554D02*
X703632Y873033D01*
G01X694733Y864724D02*
X703423Y873061D01*
G01X694679Y864899D02*
X703199Y873072D01*
G01X694638Y865087D02*
X702974Y873084D01*
G01X694599Y865275D02*
X702750Y873096D01*
G01X694561Y865466D02*
X702527Y873108D01*
G01X694542Y865676D02*
X702282Y873102D01*
G01X694523Y865885D02*
X702030Y873086D01*
G01X701776Y873071D02*
X694505Y866095D01*
G01X694511Y866328D02*
X701523Y873054D01*
G01X694516Y866560D02*
X701269Y873039D01*
G01X694523Y866794D02*
X701013Y873020D01*
G01X694555Y867053D02*
X700716Y872962D01*
G01X694589Y867312D02*
X700417Y872903D01*
G01X694633Y867582D02*
X700119Y872844D01*
G01X694719Y867892D02*
X699822Y872786D01*
G01X694806Y868202D02*
X699479Y872685D01*
G01X694894Y868513D02*
X699104Y872553D01*
G01X694981Y868824D02*
X698730Y872420D01*
G01X695216Y869277D02*
X698307Y872243D01*
G01X691768Y865060D02*
X691665Y864734D01*
G01X691872Y865387D02*
X691768Y865060D01*
G01X691665Y864734D02*
X691561Y864406D01*
G01X691976Y865714D02*
X691872Y865387D01*
G01X691561Y864406D02*
X691456Y864079D01*
G01X692080Y866042D02*
X691976Y865714D01*
G01X691456Y864079D02*
X691352Y863753D01*
G01X692184Y866368D02*
X692080Y866042D01*
G01X692288Y866695D02*
X692184Y866368D01*
G01X692392Y867022D02*
X692288Y866695D01*
G01X688510Y868524D02*
X688463Y868251D01*
G01D02*
X688414Y867978D01*
G01X688559Y868798D02*
X688606Y869072D01*
G01D02*
X688654Y869344D01*
G01X688559Y868798D02*
X688510Y868524D01*
G01X688654Y869344D02*
X688703Y869617D01*
G01X701172Y869537D02*
X704602Y872827D01*
G01X700899Y869503D02*
X704424Y872884D01*
G01X695455Y869732D02*
X697758Y871942D01*
G01X700442Y874971D02*
X704712Y879068D01*
G01X700067Y874839D02*
X704490Y879083D01*
G01X699651Y874667D02*
X704264Y879092D01*
G01X699202Y874464D02*
X704020Y879085D01*
G01X698843Y874346D02*
X703776Y879079D01*
G01X698779Y874513D02*
X703532Y879072D01*
G01X698717Y874679D02*
X703283Y879061D01*
G01X698654Y874847D02*
X703023Y879037D01*
G01X698590Y875014D02*
X702761Y879014D01*
G01X693624Y874565D02*
X693617Y874559D01*
G01X693671Y874839D02*
X693379Y874559D01*
G01X693718Y875111D02*
X693143Y874559D01*
G01X693767Y875384D02*
X692907Y874559D01*
G01X693815Y875657D02*
X692670Y874559D01*
G01X693862Y875931D02*
X692433Y874559D01*
G01X693910Y876204D02*
X692197Y874559D01*
G01X693959Y876477D02*
X691959Y874559D01*
G01X694006Y876750D02*
X691722Y874559D01*
G01X694053Y877024D02*
X691485Y874559D01*
G01X694101Y877296D02*
X691249Y874559D01*
G01X694150Y877569D02*
X691013Y874559D01*
G01X694197Y877842D02*
X690775Y874559D01*
G01X694245Y878116D02*
X690538Y874559D01*
G01X694294Y878388D02*
X690300Y874559D01*
G01X694341Y878661D02*
X690064Y874559D01*
G01X694186Y878741D02*
X689827Y874559D01*
G01X689567Y874537D02*
X689590Y874559D01*
G01X693949Y878741D02*
X689590Y874559D01*
G01X690427Y879451D02*
X685091Y874331D01*
G01Y874559D02*
X690474Y879724D01*
G01X698779Y874513D02*
X698843Y874346D01*
G01X698717Y874679D02*
X698779Y874513D01*
G01X698654Y874847D02*
X698717Y874679D01*
G01X698590Y875014D02*
X698654Y874847D01*
G01X698528Y875181D02*
X698590Y875014D01*
G01X689375Y873444D02*
X689423Y873716D01*
G01D02*
X689470Y873990D01*
G01X685130Y874559D02*
X685091Y874331D01*
G01Y874559D02*
X685130D01*
G01X689470Y873990D02*
X689519Y874263D01*
G01X689327Y873170D02*
X689375Y873444D01*
G01X693624Y874565D02*
X693671Y874839D01*
G01X691722Y874559D02*
X691959D01*
G01X691485D02*
X691722D01*
G01X691249D02*
X691013D01*
G01X691249D02*
X691485D01*
G01X691959D02*
X692197D01*
G01X692670D02*
X692907D01*
G01X692197D02*
X692433D01*
G01D02*
X692670D01*
G01X691013D02*
X690775D01*
G01X693671Y874839D02*
X693718Y875111D01*
G01X690538Y874559D02*
X690300D01*
G01X690775D02*
X690538D01*
G01X690300D02*
X690064D01*
G01X689827D02*
X689590D01*
G01X690064D02*
X689827D01*
G01X689087Y871803D02*
X689134Y872077D01*
G01X689230Y872624D02*
X689183Y872351D01*
G01D02*
X689134Y872077D01*
G01X688750Y869891D02*
X688799Y870165D01*
G01X689279Y872896D02*
X689327Y873170D01*
G01X693622Y874559D02*
X693617D01*
G01X693624Y874565D02*
X693622Y874559D01*
G01X688703Y869617D02*
X688750Y869891D01*
G01X693379Y874559D02*
X693617D01*
G01X689230Y872624D02*
X689279Y872896D01*
G01X693143Y874559D02*
X693379D01*
G01X688990Y871257D02*
X689039Y871531D01*
G01X688799Y870165D02*
X688846Y870437D01*
G01X692907Y874559D02*
X693143D01*
G01X688943Y870984D02*
X688990Y871257D01*
G01X688846Y870437D02*
X688894Y870710D01*
G01D02*
X688943Y870984D01*
G01X689039Y871531D02*
X689087Y871803D01*
G01X689519Y874263D02*
X689567Y874537D01*
G01X689571Y874559D02*
X689590D01*
G01X689567Y874537D02*
X689571Y874559D01*
G01X701172Y869537D02*
X704602Y872827D01*
G01X700899Y869503D02*
X704424Y872884D01*
G01X695455Y869732D02*
X697758Y871942D01*
G01X700442Y874971D02*
X704712Y879068D01*
G01X700067Y874839D02*
X704490Y879083D01*
G01X699651Y874667D02*
X704264Y879092D01*
G01X699202Y874464D02*
X704020Y879085D01*
G01X698843Y874346D02*
X703776Y879079D01*
G01X698779Y874513D02*
X703532Y879072D01*
G01X698717Y874679D02*
X703283Y879061D01*
G01X698654Y874847D02*
X703023Y879037D01*
G01X698590Y875014D02*
X702761Y879014D01*
G01X693624Y874565D02*
X693617Y874559D01*
G01X693671Y874839D02*
X693379Y874559D01*
G01X693718Y875111D02*
X693143Y874559D01*
G01X693767Y875384D02*
X692907Y874559D01*
G01X693815Y875657D02*
X692670Y874559D01*
G01X693862Y875931D02*
X692433Y874559D01*
G01X693910Y876204D02*
X692197Y874559D01*
G01X693959Y876477D02*
X691959Y874559D01*
G01X694006Y876750D02*
X691722Y874559D01*
G01X694053Y877024D02*
X691485Y874559D01*
G01X694101Y877296D02*
X691249Y874559D01*
G01X694150Y877569D02*
X691013Y874559D01*
G01X694197Y877842D02*
X690775Y874559D01*
G01X694245Y878116D02*
X690538Y874559D01*
G01X694294Y878388D02*
X690300Y874559D01*
G01X694341Y878661D02*
X690064Y874559D01*
G01X694186Y878741D02*
X689827Y874559D01*
G01X689567Y874537D02*
X689590Y874559D01*
G01X693949Y878741D02*
X689590Y874559D01*
G01X690427Y879451D02*
X685091Y874331D01*
G01Y874559D02*
X690474Y879724D01*
G01X698779Y874513D02*
X698843Y874346D01*
G01X698717Y874679D02*
X698779Y874513D01*
G01X698654Y874847D02*
X698717Y874679D01*
G01X698590Y875014D02*
X698654Y874847D01*
G01X698528Y875181D02*
X698590Y875014D01*
G01X689375Y873444D02*
X689423Y873716D01*
G01D02*
X689470Y873990D01*
G01X685130Y874559D02*
X685091Y874331D01*
G01Y874559D02*
X685130D01*
G01X689470Y873990D02*
X689519Y874263D01*
G01X689327Y873170D02*
X689375Y873444D01*
G01X693624Y874565D02*
X693671Y874839D01*
G01X691722Y874559D02*
X691959D01*
G01X691485D02*
X691722D01*
G01X691249D02*
X691013D01*
G01X691249D02*
X691485D01*
G01X691959D02*
X692197D01*
G01X692670D02*
X692907D01*
G01X692197D02*
X692433D01*
G01D02*
X692670D01*
G01X691013D02*
X690775D01*
G01X693671Y874839D02*
X693718Y875111D01*
G01X690538Y874559D02*
X690300D01*
G01X690775D02*
X690538D01*
G01X690300D02*
X690064D01*
G01X689827D02*
X689590D01*
G01X690064D02*
X689827D01*
G01X689087Y871803D02*
X689134Y872077D01*
G01X689230Y872624D02*
X689183Y872351D01*
G01D02*
X689134Y872077D01*
G01X688750Y869891D02*
X688799Y870165D01*
G01X689279Y872896D02*
X689327Y873170D01*
G01X693622Y874559D02*
X693617D01*
G01X693624Y874565D02*
X693622Y874559D01*
G01X688703Y869617D02*
X688750Y869891D01*
G01X693379Y874559D02*
X693617D01*
G01X689230Y872624D02*
X689279Y872896D01*
G01X693143Y874559D02*
X693379D01*
G01X688990Y871257D02*
X689039Y871531D01*
G01X688799Y870165D02*
X688846Y870437D01*
G01X692907Y874559D02*
X693143D01*
G01X688943Y870984D02*
X688990Y871257D01*
G01X688846Y870437D02*
X688894Y870710D01*
G01D02*
X688943Y870984D01*
G01X689039Y871531D02*
X689087Y871803D01*
G01X689519Y874263D02*
X689567Y874537D01*
G01X689571Y874559D02*
X689590D01*
G01X689567Y874537D02*
X689571Y874559D01*
G01X705155Y879037D02*
X701125Y875172D01*
G01X704933Y879053D02*
X700792Y875080D01*
G01X698528Y875181D02*
X702499Y878991D01*
G01X698466Y875347D02*
X702221Y878950D01*
G01X698402Y875514D02*
X701938Y878905D01*
G01X698339Y875682D02*
X701653Y878860D01*
G01X698277Y875848D02*
X701345Y878792D01*
G01X698213Y876015D02*
X701033Y878719D01*
G01X698151Y876182D02*
X700710Y878637D01*
G01X698089Y876349D02*
X700359Y878528D01*
G01X698025Y876516D02*
X700008Y878418D01*
G01X697962Y876683D02*
X699614Y878267D01*
G01X697900Y876850D02*
X699214Y878110D01*
G01X697836Y877017D02*
X698768Y877911D01*
G01X697774Y877184D02*
X698306Y877694D01*
G01X697712Y877350D02*
X697811Y877446D01*
G01X691243Y884097D02*
X685903Y878975D01*
G01X691291Y884370D02*
X685952Y879248D01*
G01X691339Y884644D02*
X686000Y879522D01*
G01X691387Y884916D02*
X686047Y879794D01*
G01X698025Y876516D02*
X698089Y876349D01*
G01X697962Y876683D02*
X698025Y876516D01*
G01X698213Y876015D02*
X698277Y875848D01*
G01X698089Y876349D02*
X698151Y876182D01*
G01X698277Y875848D02*
X698339Y875682D01*
G01X697900Y876850D02*
X697962Y876683D01*
G01X698151Y876182D02*
X698213Y876015D01*
G01X697836Y877017D02*
X697900Y876850D01*
G01X697712Y877350D02*
X697774Y877184D01*
G01D02*
X697836Y877017D01*
G01X698402Y875514D02*
X698466Y875347D01*
G01D02*
X698528Y875181D01*
G01X698339Y875682D02*
X698402Y875514D01*
G01X685423Y878741D02*
X685186D01*
G01X685659D02*
X685423D01*
G01X694053Y877024D02*
X694101Y877296D01*
G01D02*
X694150Y877569D01*
G01X693959Y876477D02*
X694006Y876750D01*
G01X693910Y876204D02*
X693959Y876477D01*
G01X694006Y876750D02*
X694053Y877024D01*
G01X694245Y878116D02*
X694294Y878388D01*
G01X694197Y877842D02*
X694245Y878116D01*
G01X693862Y875931D02*
X693910Y876204D01*
G01X693767Y875384D02*
X693815Y875657D01*
G01D02*
X693862Y875931D01*
G01X694294Y878388D02*
X694341Y878661D01*
G01X693718Y875111D02*
X693767Y875384D01*
G01X694150Y877569D02*
X694197Y877842D01*
G01X691581Y878741D02*
X691345D01*
G01X691818D02*
X691581D01*
G01X692292D02*
X692054D01*
G01D02*
X691818D01*
G01X692765D02*
X692529D01*
G01D02*
X692292D01*
G01X690870D02*
X690634D01*
G01X690427Y879451D02*
X690474Y879724D01*
G01D02*
X690523Y879998D01*
G01X693002Y878741D02*
X692765D01*
G01X691345D02*
X691107D01*
G01D02*
X690870D01*
G01X690330Y878905D02*
X690379Y879178D01*
G01D02*
X690427Y879451D01*
G01X690634Y878741D02*
X690397D01*
G01X694355D02*
X694186D01*
G01X694341Y878661D02*
X694355Y878741D01*
G01X693713D02*
X693477D01*
G01X693240D02*
X693002D01*
G01X693477D02*
X693240D01*
G01X694186D02*
X693949D01*
G01D02*
X693713D01*
G01X690302D02*
X690397D01*
G01X690330Y878905D02*
X690302Y878741D01*
G01X686096Y880068D02*
X686047Y879794D01*
G01X685952Y879248D02*
X685903Y878975D01*
G01X685863Y878741D02*
X685903Y878975D01*
G01X685659Y878741D02*
X685863D01*
G01X686000Y879522D02*
X685952Y879248D01*
G01X686047Y879794D02*
X686000Y879522D01*
G01X705155Y879037D02*
X701125Y875172D01*
G01X704933Y879053D02*
X700792Y875080D01*
G01X698528Y875181D02*
X702499Y878991D01*
G01X698466Y875347D02*
X702221Y878950D01*
G01X698402Y875514D02*
X701938Y878905D01*
G01X698339Y875682D02*
X701653Y878860D01*
G01X698277Y875848D02*
X701345Y878792D01*
G01X698213Y876015D02*
X701033Y878719D01*
G01X698151Y876182D02*
X700710Y878637D01*
G01X698089Y876349D02*
X700359Y878528D01*
G01X698025Y876516D02*
X700008Y878418D01*
G01X697962Y876683D02*
X699614Y878267D01*
G01X697900Y876850D02*
X699214Y878110D01*
G01X697836Y877017D02*
X698768Y877911D01*
G01X697774Y877184D02*
X698306Y877694D01*
G01X697712Y877350D02*
X697811Y877446D01*
G01X691243Y884097D02*
X685903Y878975D01*
G01X691291Y884370D02*
X685952Y879248D01*
G01X691339Y884644D02*
X686000Y879522D01*
G01X691387Y884916D02*
X686047Y879794D01*
G01X698025Y876516D02*
X698089Y876349D01*
G01X697962Y876683D02*
X698025Y876516D01*
G01X698213Y876015D02*
X698277Y875848D01*
G01X698089Y876349D02*
X698151Y876182D01*
G01X698277Y875848D02*
X698339Y875682D01*
G01X697900Y876850D02*
X697962Y876683D01*
G01X698151Y876182D02*
X698213Y876015D01*
G01X697836Y877017D02*
X697900Y876850D01*
G01X697712Y877350D02*
X697774Y877184D01*
G01D02*
X697836Y877017D01*
G01X698402Y875514D02*
X698466Y875347D01*
G01D02*
X698528Y875181D01*
G01X698339Y875682D02*
X698402Y875514D01*
G01X685423Y878741D02*
X685186D01*
G01X685659D02*
X685423D01*
G01X694053Y877024D02*
X694101Y877296D01*
G01D02*
X694150Y877569D01*
G01X693959Y876477D02*
X694006Y876750D01*
G01X693910Y876204D02*
X693959Y876477D01*
G01X694006Y876750D02*
X694053Y877024D01*
G01X694245Y878116D02*
X694294Y878388D01*
G01X694197Y877842D02*
X694245Y878116D01*
G01X693862Y875931D02*
X693910Y876204D01*
G01X693767Y875384D02*
X693815Y875657D01*
G01D02*
X693862Y875931D01*
G01X694294Y878388D02*
X694341Y878661D01*
G01X693718Y875111D02*
X693767Y875384D01*
G01X694150Y877569D02*
X694197Y877842D01*
G01X691581Y878741D02*
X691345D01*
G01X691818D02*
X691581D01*
G01X692292D02*
X692054D01*
G01D02*
X691818D01*
G01X692765D02*
X692529D01*
G01D02*
X692292D01*
G01X690870D02*
X690634D01*
G01X690427Y879451D02*
X690474Y879724D01*
G01D02*
X690523Y879998D01*
G01X693002Y878741D02*
X692765D01*
G01X691345D02*
X691107D01*
G01D02*
X690870D01*
G01X690330Y878905D02*
X690379Y879178D01*
G01D02*
X690427Y879451D01*
G01X690634Y878741D02*
X690397D01*
G01X694355D02*
X694186D01*
G01X694341Y878661D02*
X694355Y878741D01*
G01X693713D02*
X693477D01*
G01X693240D02*
X693002D01*
G01X693477D02*
X693240D01*
G01X694186D02*
X693949D01*
G01D02*
X693713D01*
G01X690302D02*
X690397D01*
G01X690330Y878905D02*
X690302Y878741D01*
G01X686096Y880068D02*
X686047Y879794D01*
G01X685952Y879248D02*
X685903Y878975D01*
G01X685863Y878741D02*
X685903Y878975D01*
G01X685659Y878741D02*
X685863D01*
G01X686000Y879522D02*
X685952Y879248D01*
G01X686047Y879794D02*
X686000Y879522D01*
G01X691436Y885190D02*
X686096Y880068D01*
G01X691185Y885177D02*
X686143Y880341D01*
G01X690730Y884969D02*
X686192Y880614D01*
G01X690277Y884760D02*
X686240Y880887D01*
G01X689822Y884551D02*
X686287Y881161D01*
G01X689366Y884342D02*
X686336Y881435D01*
G01X688912Y884133D02*
X686383Y881707D01*
G01X688459Y883924D02*
X686431Y881980D01*
G01X688003Y883715D02*
X686480Y882254D01*
G01X687547Y883506D02*
X686527Y882527D01*
G01X687094Y883298D02*
X686576Y882800D01*
G01X686640Y883089D02*
X686623Y883073D01*
G01X686480Y882254D02*
X686431Y881980D01*
G01X686480Y882254D02*
X686527Y882527D01*
G01X686336Y881435D02*
X686287Y881161D01*
G01X686431Y881980D02*
X686383Y881707D01*
G01X686287Y881161D02*
X686240Y880887D01*
G01X686527Y882527D02*
X686576Y882800D01*
G01X686383Y881707D02*
X686336Y881435D01*
G01X686625Y883082D02*
X686623Y883073D01*
G01X686640Y883089D02*
X686625Y883082D01*
G01X686576Y882800D02*
X686623Y883073D01*
G01X686240Y880887D02*
X686192Y880614D01*
G01X686143Y880341D02*
X686096Y880068D01*
G01X686192Y880614D02*
X686143Y880341D01*
G01X691185Y885177D02*
X690730Y884969D01*
G01X691003Y882730D02*
X691051Y883004D01*
G01X690730Y884969D02*
X690277Y884760D01*
G01X689822Y884551D02*
X689366Y884342D01*
G01X690277Y884760D02*
X689822Y884551D01*
G01X691455Y885302D02*
X691185Y885177D01*
G01X691436Y885190D02*
X691455Y885302D01*
G01X691099Y883278D02*
X691147Y883551D01*
G01D02*
X691196Y883823D01*
G01X691051Y883004D02*
X691099Y883278D01*
G01X691339Y884644D02*
X691387Y884916D01*
G01X691291Y884370D02*
X691339Y884644D01*
G01X691196Y883823D02*
X691243Y884097D01*
G01D02*
X691291Y884370D01*
G01X691387Y884916D02*
X691436Y885190D01*
G01X688003Y883715D02*
X687547Y883506D01*
G01X689366Y884342D02*
X688912Y884133D01*
G01X687094Y883298D02*
X686640Y883089D01*
G01X687547Y883506D02*
X687094Y883298D01*
G01X688912Y884133D02*
X688459Y883924D01*
G01X690523Y879998D02*
X690570Y880271D01*
G01X688459Y883924D02*
X688003Y883715D01*
G01X690907Y882185D02*
X690954Y882457D01*
G01X690716Y881091D02*
X690763Y881364D01*
G01X690570Y880271D02*
X690619Y880544D01*
G01X690859Y881911D02*
X690907Y882185D01*
G01X690763Y881364D02*
X690810Y881637D01*
G01X690954Y882457D02*
X691003Y882730D01*
G01X690619Y880544D02*
X690667Y880818D01*
G01X690810Y881637D02*
X690859Y881911D01*
G01X690667Y880818D02*
X690716Y881091D01*
G01X691436Y885190D02*
X686096Y880068D01*
G01X691185Y885177D02*
X686143Y880341D01*
G01X690730Y884969D02*
X686192Y880614D01*
G01X690277Y884760D02*
X686240Y880887D01*
G01X689822Y884551D02*
X686287Y881161D01*
G01X689366Y884342D02*
X686336Y881435D01*
G01X688912Y884133D02*
X686383Y881707D01*
G01X688459Y883924D02*
X686431Y881980D01*
G01X688003Y883715D02*
X686480Y882254D01*
G01X687547Y883506D02*
X686527Y882527D01*
G01X687094Y883298D02*
X686576Y882800D01*
G01X686640Y883089D02*
X686623Y883073D01*
G01X686480Y882254D02*
X686431Y881980D01*
G01X686480Y882254D02*
X686527Y882527D01*
G01X686336Y881435D02*
X686287Y881161D01*
G01X686431Y881980D02*
X686383Y881707D01*
G01X686287Y881161D02*
X686240Y880887D01*
G01X686527Y882527D02*
X686576Y882800D01*
G01X686383Y881707D02*
X686336Y881435D01*
G01X686625Y883082D02*
X686623Y883073D01*
G01X686640Y883089D02*
X686625Y883082D01*
G01X686576Y882800D02*
X686623Y883073D01*
G01X686240Y880887D02*
X686192Y880614D01*
G01X686143Y880341D02*
X686096Y880068D01*
G01X686192Y880614D02*
X686143Y880341D01*
G01X691185Y885177D02*
X690730Y884969D01*
G01X691003Y882730D02*
X691051Y883004D01*
G01X690730Y884969D02*
X690277Y884760D01*
G01X689822Y884551D02*
X689366Y884342D01*
G01X690277Y884760D02*
X689822Y884551D01*
G01X691455Y885302D02*
X691185Y885177D01*
G01X691436Y885190D02*
X691455Y885302D01*
G01X691099Y883278D02*
X691147Y883551D01*
G01D02*
X691196Y883823D01*
G01X691051Y883004D02*
X691099Y883278D01*
G01X691339Y884644D02*
X691387Y884916D01*
G01X691291Y884370D02*
X691339Y884644D01*
G01X691196Y883823D02*
X691243Y884097D01*
G01D02*
X691291Y884370D01*
G01X691387Y884916D02*
X691436Y885190D01*
G01X688003Y883715D02*
X687547Y883506D01*
G01X689366Y884342D02*
X688912Y884133D01*
G01X687094Y883298D02*
X686640Y883089D01*
G01X687547Y883506D02*
X687094Y883298D01*
G01X688912Y884133D02*
X688459Y883924D01*
G01X690523Y879998D02*
X690570Y880271D01*
G01X688459Y883924D02*
X688003Y883715D01*
G01X690907Y882185D02*
X690954Y882457D01*
G01X690716Y881091D02*
X690763Y881364D01*
G01X690570Y880271D02*
X690619Y880544D01*
G01X690859Y881911D02*
X690907Y882185D01*
G01X690763Y881364D02*
X690810Y881637D01*
G01X690954Y882457D02*
X691003Y882730D01*
G01X690619Y880544D02*
X690667Y880818D01*
G01X690810Y881637D02*
X690859Y881911D01*
G01X690667Y880818D02*
X690716Y881091D01*
G01X708087Y861856D02*
X708170Y861936D01*
G01X707850Y861856D02*
X708219Y862210D01*
G01X707613Y861856D02*
X708267Y862484D01*
G01X707377Y861856D02*
X708314Y862756D01*
G01X707139Y861856D02*
X708361Y863028D01*
G01X706902Y861856D02*
X708410Y863302D01*
G01X706665Y861856D02*
X708458Y863576D01*
G01X706429Y861856D02*
X708505Y863848D01*
G01X706193Y861856D02*
X708554Y864121D01*
G01X705955Y861856D02*
X708602Y864395D01*
G01X705718Y861856D02*
X708649Y864669D01*
G01X705481Y861856D02*
X708698Y864941D01*
G01X705245Y861856D02*
X708745Y865214D01*
G01X705007Y861856D02*
X708793Y865487D01*
G01X704770Y861856D02*
X708842Y865761D01*
G01X704534Y861856D02*
X708889Y866033D01*
G01X704298Y861856D02*
X708937Y866306D01*
G01X704061Y861856D02*
X708984Y866580D01*
G01X703823Y861856D02*
X709033Y866853D01*
G01X703746Y862008D02*
X709080Y867126D01*
G01X703793Y862282D02*
X709128Y867399D01*
G01X703842Y862555D02*
X709177Y867673D01*
G01X709224Y867946D02*
X703890Y862829D01*
G01X703506Y862688D02*
X709272Y868218D01*
G01X702832Y862268D02*
X709319Y868491D01*
G01X702358Y862041D02*
X709368Y868765D01*
G01X701953Y861879D02*
X709415Y869038D01*
G01X701616Y861784D02*
X709463Y869311D01*
G01X706902Y861856D02*
X707139D01*
G01X706429D02*
X706665D01*
G01D02*
X706902D01*
G01X705955D02*
X706193D01*
G01D02*
X706429D01*
G01X707850D02*
X708087D01*
G01X708157D02*
X708170Y861936D01*
G01X708087Y861856D02*
X708157D01*
G01X705718D02*
X705955D01*
G01X707139D02*
X707377D01*
G01X707613D02*
X707850D01*
G01X707377D02*
X707613D01*
G01X703823D02*
X704061D01*
G01X703842Y862555D02*
X703793Y862282D01*
G01X703719Y861856D02*
X703823D01*
G01X703746Y862008D02*
X703719Y861856D01*
G01X703793Y862282D02*
X703746Y862008D01*
G01X705245Y861856D02*
X705481D01*
G01X705007D02*
X705245D01*
G01X705481D02*
X705718D01*
G01X704298D02*
X704534D01*
G01D02*
X704770D01*
G01D02*
X705007D01*
G01X708170Y861936D02*
X708219Y862210D01*
G01X708361Y863028D02*
X708410Y863302D01*
G01X708458Y863576D02*
X708505Y863848D01*
G01X708410Y863302D02*
X708458Y863576D01*
G01X708314Y862756D02*
X708361Y863028D01*
G01X708219Y862210D02*
X708267Y862484D01*
G01D02*
X708314Y862756D01*
G01X704061Y861856D02*
X704298D01*
G01X703890Y862829D02*
X703842Y862555D01*
G01X708087Y861856D02*
X708170Y861936D01*
G01X707850Y861856D02*
X708219Y862210D01*
G01X707613Y861856D02*
X708267Y862484D01*
G01X707377Y861856D02*
X708314Y862756D01*
G01X707139Y861856D02*
X708361Y863028D01*
G01X706902Y861856D02*
X708410Y863302D01*
G01X706665Y861856D02*
X708458Y863576D01*
G01X706429Y861856D02*
X708505Y863848D01*
G01X706193Y861856D02*
X708554Y864121D01*
G01X705955Y861856D02*
X708602Y864395D01*
G01X705718Y861856D02*
X708649Y864669D01*
G01X705481Y861856D02*
X708698Y864941D01*
G01X705245Y861856D02*
X708745Y865214D01*
G01X705007Y861856D02*
X708793Y865487D01*
G01X704770Y861856D02*
X708842Y865761D01*
G01X704534Y861856D02*
X708889Y866033D01*
G01X704298Y861856D02*
X708937Y866306D01*
G01X704061Y861856D02*
X708984Y866580D01*
G01X703823Y861856D02*
X709033Y866853D01*
G01X703746Y862008D02*
X709080Y867126D01*
G01X703793Y862282D02*
X709128Y867399D01*
G01X703842Y862555D02*
X709177Y867673D01*
G01X709224Y867946D02*
X703890Y862829D01*
G01X703506Y862688D02*
X709272Y868218D01*
G01X702832Y862268D02*
X709319Y868491D01*
G01X702358Y862041D02*
X709368Y868765D01*
G01X701953Y861879D02*
X709415Y869038D01*
G01X701616Y861784D02*
X709463Y869311D01*
G01X706902Y861856D02*
X707139D01*
G01X706429D02*
X706665D01*
G01D02*
X706902D01*
G01X705955D02*
X706193D01*
G01D02*
X706429D01*
G01X707850D02*
X708087D01*
G01X708157D02*
X708170Y861936D01*
G01X708087Y861856D02*
X708157D01*
G01X705718D02*
X705955D01*
G01X707139D02*
X707377D01*
G01X707613D02*
X707850D01*
G01X707377D02*
X707613D01*
G01X703823D02*
X704061D01*
G01X703842Y862555D02*
X703793Y862282D01*
G01X703719Y861856D02*
X703823D01*
G01X703746Y862008D02*
X703719Y861856D01*
G01X703793Y862282D02*
X703746Y862008D01*
G01X705245Y861856D02*
X705481D01*
G01X705007D02*
X705245D01*
G01X705481D02*
X705718D01*
G01X704298D02*
X704534D01*
G01D02*
X704770D01*
G01D02*
X705007D01*
G01X708170Y861936D02*
X708219Y862210D01*
G01X708361Y863028D02*
X708410Y863302D01*
G01X708458Y863576D02*
X708505Y863848D01*
G01X708410Y863302D02*
X708458Y863576D01*
G01X708314Y862756D02*
X708361Y863028D01*
G01X708219Y862210D02*
X708267Y862484D01*
G01D02*
X708314Y862756D01*
G01X704061Y861856D02*
X704298D01*
G01X703890Y862829D02*
X703842Y862555D01*
G01X709942Y872043D02*
X704608Y866927D01*
G01X709990Y872316D02*
X704656Y867200D01*
G01X710038Y872589D02*
X704705Y867472D01*
G01X710085Y872861D02*
X704752Y867745D01*
G01X710133Y873135D02*
X704800Y868019D01*
G01X710159Y873386D02*
X704849Y868292D01*
G01X710178Y873632D02*
X704896Y868565D01*
G01X710198Y873878D02*
X704943Y868838D01*
G01X710218Y874125D02*
X704868Y868992D01*
G01X710239Y874373D02*
X704725Y869084D01*
G01X710240Y874601D02*
X704576Y869167D01*
G01X710213Y874801D02*
X704424Y869248D01*
G01X710186Y875003D02*
X704259Y869317D01*
G01X710157Y875204D02*
X704089Y869382D01*
G01X710130Y875404D02*
X703910Y869437D01*
G01X709177Y867673D02*
X709224Y867946D01*
G01D02*
X709272Y868218D01*
G01D02*
X709319Y868491D01*
G01X709080Y867126D02*
X709128Y867399D01*
G01X709033Y866853D02*
X709080Y867126D01*
G01X709128Y867399D02*
X709177Y867673D01*
G01X708984Y866580D02*
X709033Y866853D01*
G01X709463Y869311D02*
X709512Y869584D01*
G01X709415Y869038D02*
X709463Y869311D01*
G01X709319Y868491D02*
X709368Y868765D01*
G01D02*
X709415Y869038D01*
G01X708937Y866306D02*
X708984Y866580D01*
G01X708793Y865487D02*
X708842Y865761D01*
G01X708889Y866033D02*
X708937Y866306D01*
G01X708745Y865214D02*
X708793Y865487D01*
G01X708842Y865761D02*
X708889Y866033D01*
G01X708554Y864121D02*
X708602Y864395D01*
G01X708505Y863848D02*
X708554Y864121D01*
G01X708602Y864395D02*
X708649Y864669D01*
G01D02*
X708698Y864941D01*
G01D02*
X708745Y865214D01*
G01X704849Y868292D02*
X704800Y868019D01*
G01D02*
X704752Y867745D01*
G01X704943Y868838D02*
X704896Y868565D01*
G01D02*
X704849Y868292D01*
G01X704656Y867200D02*
X704608Y866927D01*
G01X704752Y867745D02*
X704705Y867472D01*
G01D02*
X704656Y867200D01*
G01X709942Y872043D02*
X704608Y866927D01*
G01X709990Y872316D02*
X704656Y867200D01*
G01X710038Y872589D02*
X704705Y867472D01*
G01X710085Y872861D02*
X704752Y867745D01*
G01X710133Y873135D02*
X704800Y868019D01*
G01X710159Y873386D02*
X704849Y868292D01*
G01X710178Y873632D02*
X704896Y868565D01*
G01X710198Y873878D02*
X704943Y868838D01*
G01X710218Y874125D02*
X704868Y868992D01*
G01X710239Y874373D02*
X704725Y869084D01*
G01X710240Y874601D02*
X704576Y869167D01*
G01X710213Y874801D02*
X704424Y869248D01*
G01X710186Y875003D02*
X704259Y869317D01*
G01X710157Y875204D02*
X704089Y869382D01*
G01X710130Y875404D02*
X703910Y869437D01*
G01X709177Y867673D02*
X709224Y867946D01*
G01D02*
X709272Y868218D01*
G01D02*
X709319Y868491D01*
G01X709080Y867126D02*
X709128Y867399D01*
G01X709033Y866853D02*
X709080Y867126D01*
G01X709128Y867399D02*
X709177Y867673D01*
G01X708984Y866580D02*
X709033Y866853D01*
G01X709463Y869311D02*
X709512Y869584D01*
G01X709415Y869038D02*
X709463Y869311D01*
G01X709319Y868491D02*
X709368Y868765D01*
G01D02*
X709415Y869038D01*
G01X708937Y866306D02*
X708984Y866580D01*
G01X708793Y865487D02*
X708842Y865761D01*
G01X708889Y866033D02*
X708937Y866306D01*
G01X708745Y865214D02*
X708793Y865487D01*
G01X708842Y865761D02*
X708889Y866033D01*
G01X708554Y864121D02*
X708602Y864395D01*
G01X708505Y863848D02*
X708554Y864121D01*
G01X708602Y864395D02*
X708649Y864669D01*
G01D02*
X708698Y864941D01*
G01D02*
X708745Y865214D01*
G01X704849Y868292D02*
X704800Y868019D01*
G01D02*
X704752Y867745D01*
G01X704943Y868838D02*
X704896Y868565D01*
G01D02*
X704849Y868292D01*
G01X704656Y867200D02*
X704608Y866927D01*
G01X704752Y867745D02*
X704705Y867472D01*
G01D02*
X704656Y867200D01*
G01X710103Y875605D02*
X703724Y869485D01*
G01X710056Y875787D02*
X703529Y869526D01*
G01X709988Y875950D02*
X703325Y869559D01*
G01X709921Y876112D02*
X703118Y869586D01*
G01X709855Y876275D02*
X702902Y869605D01*
G01X709788Y876439D02*
X702680Y869620D01*
G01X709721Y876602D02*
X705615Y872663D01*
G01X705443Y872499D02*
X702453Y869631D01*
G01X709643Y876755D02*
X705664Y872937D01*
G01X705284Y872574D02*
X702223Y869636D01*
G01X705125Y872648D02*
X701989Y869639D01*
G01X709543Y876885D02*
X705711Y873210D01*
G01X704958Y872715D02*
X701717Y869605D01*
G01X709441Y877015D02*
X705740Y873465D01*
G01X704779Y872772D02*
X701443Y869571D01*
G01X709339Y877146D02*
X705761Y873712D01*
G01X709239Y877275D02*
X705740Y873918D01*
G01X709137Y877405D02*
X705715Y874123D01*
G01X709036Y877536D02*
X705657Y874294D01*
G01X708909Y877641D02*
X705599Y874466D01*
G01X708777Y877741D02*
X705510Y874608D01*
G01X708645Y877841D02*
X705420Y874747D01*
G01X708512Y877941D02*
X705308Y874868D01*
G01X708379Y878042D02*
X705185Y874978D01*
G01X709750Y870950D02*
X709798Y871223D01*
G01X710085Y872861D02*
X710133Y873135D01*
G01X710038Y872589D02*
X710085Y872861D01*
G01X709990Y872316D02*
X710038Y872589D01*
G01X709942Y872043D02*
X709990Y872316D01*
G01X709847Y871496D02*
X709894Y871769D01*
G01X709798Y871223D02*
X709847Y871496D01*
G01X709894Y871769D02*
X709942Y872043D01*
G01X709512Y869584D02*
X709559Y869858D01*
G01X709607Y870131D02*
X709654Y870404D01*
G01D02*
X709703Y870676D01*
G01D02*
X709750Y870950D01*
G01X709559Y869858D02*
X709607Y870131D01*
G01X705711Y873210D02*
X705664Y872937D01*
G01D02*
X705615Y872663D01*
G01X710103Y875605D02*
X703724Y869485D01*
G01X710056Y875787D02*
X703529Y869526D01*
G01X709988Y875950D02*
X703325Y869559D01*
G01X709921Y876112D02*
X703118Y869586D01*
G01X709855Y876275D02*
X702902Y869605D01*
G01X709788Y876439D02*
X702680Y869620D01*
G01X709721Y876602D02*
X705615Y872663D01*
G01X705443Y872499D02*
X702453Y869631D01*
G01X709643Y876755D02*
X705664Y872937D01*
G01X705284Y872574D02*
X702223Y869636D01*
G01X705125Y872648D02*
X701989Y869639D01*
G01X709543Y876885D02*
X705711Y873210D01*
G01X704958Y872715D02*
X701717Y869605D01*
G01X709441Y877015D02*
X705740Y873465D01*
G01X704779Y872772D02*
X701443Y869571D01*
G01X709339Y877146D02*
X705761Y873712D01*
G01X709239Y877275D02*
X705740Y873918D01*
G01X709137Y877405D02*
X705715Y874123D01*
G01X709036Y877536D02*
X705657Y874294D01*
G01X708909Y877641D02*
X705599Y874466D01*
G01X708777Y877741D02*
X705510Y874608D01*
G01X708645Y877841D02*
X705420Y874747D01*
G01X708512Y877941D02*
X705308Y874868D01*
G01X708379Y878042D02*
X705185Y874978D01*
G01X709750Y870950D02*
X709798Y871223D01*
G01X710085Y872861D02*
X710133Y873135D01*
G01X710038Y872589D02*
X710085Y872861D01*
G01X709990Y872316D02*
X710038Y872589D01*
G01X709942Y872043D02*
X709990Y872316D01*
G01X709847Y871496D02*
X709894Y871769D01*
G01X709798Y871223D02*
X709847Y871496D01*
G01X709894Y871769D02*
X709942Y872043D01*
G01X709512Y869584D02*
X709559Y869858D01*
G01X709607Y870131D02*
X709654Y870404D01*
G01D02*
X709703Y870676D01*
G01D02*
X709750Y870950D01*
G01X709559Y869858D02*
X709607Y870131D01*
G01X705711Y873210D02*
X705664Y872937D01*
G01D02*
X705615Y872663D01*
G01X708248Y878141D02*
X705055Y875080D01*
G01X708109Y878236D02*
X704903Y875160D01*
G01X707946Y878308D02*
X704748Y875240D01*
G01X707784Y878380D02*
X704571Y875297D01*
G01X707622Y878451D02*
X704386Y875347D01*
G01X707461Y878523D02*
X704192Y875388D01*
G01X707298Y878595D02*
X703972Y875405D01*
G01X707137Y878667D02*
X703754Y875423D01*
G01X706959Y878725D02*
X703519Y875424D01*
G01X706769Y878768D02*
X703278Y875419D01*
G01X706578Y878812D02*
X703035Y875415D01*
G01X706385Y878856D02*
X702784Y875401D01*
G01X706195Y878900D02*
X702529Y875383D01*
G01X706004Y878944D02*
X702272Y875364D01*
G01X705813Y878988D02*
X701998Y875328D01*
G01X705596Y879007D02*
X701724Y875293D01*
G01X705375Y879022D02*
X701427Y875234D01*
G01X708248Y878141D02*
X705055Y875080D01*
G01X708109Y878236D02*
X704903Y875160D01*
G01X707946Y878308D02*
X704748Y875240D01*
G01X707784Y878380D02*
X704571Y875297D01*
G01X707622Y878451D02*
X704386Y875347D01*
G01X707461Y878523D02*
X704192Y875388D01*
G01X707298Y878595D02*
X703972Y875405D01*
G01X707137Y878667D02*
X703754Y875423D01*
G01X706959Y878725D02*
X703519Y875424D01*
G01X706769Y878768D02*
X703278Y875419D01*
G01X706578Y878812D02*
X703035Y875415D01*
G01X706385Y878856D02*
X702784Y875401D01*
G01X706195Y878900D02*
X702529Y875383D01*
G01X706004Y878944D02*
X702272Y875364D01*
G01X705813Y878988D02*
X701998Y875328D01*
G01X705596Y879007D02*
X701724Y875293D01*
G01X705375Y879022D02*
X701427Y875234D01*
G01X731181Y61614D02*
G02X739055I3937J0D01*
G02X731181I-3937J0D01*
G01X763780Y1490945D02*
G02X777165I6693J0D01*
G02X763780I-6692J0D01*
G01X774016Y1547638D02*
G02X796063I11024J0D01*
G02X774016I-11023J0D01*
G01X789055Y81575D02*
G02X796929I3937J0D01*
G02X789055I-3937J0D01*
G01X813386Y388583D02*
G02X826772I6693J0D01*
G02X813386I-6693J0D01*
G01X801181Y1066535D02*
G02X818898I8859J0D01*
G02X801181I-8858J0D01*
G01Y1263386D02*
G02X818898I8859J0D01*
G02X801181I-8858J0D01*
G01X833543Y61614D02*
G02X841417I3937J0D01*
G02X833543I-3937J0D01*
G01X841173Y1367717D02*
G02X857709I8268J0D01*
G02X841173I-8268J0D01*
G01X847992Y1225118D02*
G02X860591I6300J0D01*
G02X847992I-6299J0D01*
G01X879193Y23622D02*
G02X901240I11024J0D01*
G02X879193I-11023J0D01*
G01X909449Y765197D02*
G02X931496I11023J0D01*
G02X909449I-11023J0D01*
G01X939055Y81575D02*
G02X946929I3937J0D01*
G02X939055I-3937J0D01*
G01X983543Y61614D02*
G02X991417I3937J0D01*
G02X983543I-3937J0D01*
G01X987205Y1170748D02*
G02X999803I6299J0D01*
G02X987205I-6299J0D01*
G01X1014173Y388583D02*
G02X1027559I6693J0D01*
G02X1014173I-6693J0D01*
G01X1022047Y1066535D02*
G02X1039764I8859J0D01*
G02X1022047I-8858J0D01*
G01Y1263386D02*
G02X1039764I8859J0D01*
G02X1022047I-8858J0D01*
G01X1041417Y81575D02*
G02X1049291I3937J0D01*
G02X1041417I-3937J0D01*
G01X1044882Y1547638D02*
G02X1066929I11024J0D01*
G02X1044882I-11024J0D01*
G01X1063780Y1490945D02*
G02X1077165I6692J0D01*
G02X1063780I-6692J0D01*
G01X1085906Y61614D02*
G02X1093780I3937J0D01*
G02X1085906I-3937J0D01*
G01X1107736Y23622D02*
G02X1129783I11023J0D01*
G02X1107736I-11023J0D01*
G01X1143780Y81575D02*
G02X1151654I3937J0D01*
G02X1143780I-3937J0D01*
G01X1188268Y61614D02*
G02X1196142I3937J0D01*
G02X1188268I-3937J0D01*
G01X1246142Y81575D02*
G02X1254016I3937J0D01*
G02X1246142I-3937J0D01*
G01X1265305Y1580079D02*
G02X1252805I-6250J0D01*
G02X1265305I6250J0D01*
G01Y1606142D02*
G02X1252805I-6250J0D01*
G02X1265305I6250J0D01*
G01Y1626339D02*
G02X1252805I-6250J0D01*
G02X1265305I6250J0D01*
G01X1258268Y1066535D02*
G02X1275984I8858J0D01*
G02X1258268I-8858J0D01*
G01Y1263386D02*
G02X1275984I8858J0D01*
G02X1258268I-8858J0D01*
G01X1290630Y61614D02*
G02X1298504I3937J0D01*
G02X1290630I-3937J0D01*
G01X1298228Y1141024D02*
G02X1310827I6299J0D01*
G02X1298228I-6300J0D01*
G01X1336280Y70866D02*
G02X1358327I11023J0D01*
G02X1336280I-11024J0D01*
G01X1366535Y286220D02*
G02X1388583I11024J0D01*
G02X1366535I-11024J0D01*
G01Y765197D02*
G02X1388583I11024J0D01*
G02X1366535I-11024J0D01*
G01X1396142Y81575D02*
G02X1404016I3937J0D01*
G02X1396142I-3937J0D01*
G01X1420433Y1604724D02*
G02X1442480I11023J0D01*
G02X1420433I-11023J0D01*
G01X1440630Y61614D02*
G02X1448504I3937J0D01*
G02X1440630I-3937J0D01*
G01X1444291Y1086654D02*
G02X1456890I6300J0D01*
G02X1444291I-6299J0D01*
G01X1479134Y1066535D02*
G02X1496850I8858J0D01*
G02X1479134I-8858J0D01*
G01Y1263386D02*
G02X1496850I8858J0D01*
G02X1479134I-8858J0D01*
G01X1498504Y81575D02*
G02X1506378I3937J0D01*
G02X1498504I-3937J0D01*
G01X1542992Y61614D02*
G02X1550866I3937J0D01*
G02X1542992I-3937J0D01*
G01X1564823Y23622D02*
G02X1586870I11024J0D01*
G02X1564823I-11023J0D01*
G01X1600866Y81575D02*
G02X1608740I3937J0D01*
G02X1600866I-3937J0D01*
G01X1611801Y1580079D02*
G02X1599301I-6250J0D01*
G02X1611801I6250J0D01*
G01X1611762Y1606142D02*
G02X1599262I-6250J0D01*
G02X1611762I6250J0D01*
G01X1611801Y1626339D02*
G02X1599301I-6250J0D01*
G02X1611801I6250J0D01*
G01X1645354Y61614D02*
G02X1653228I3937J0D01*
G02X1645354I-3937J0D01*
G01X1703228Y81575D02*
G02X1711102I3937J0D01*
G02X1703228I-3937J0D01*
G01X1715354Y1066535D02*
G02X1733071I8859J0D01*
G02X1715354I-8858J0D01*
G01Y1263386D02*
G02X1733071I8859J0D01*
G02X1715354I-8858J0D01*
G01X1747717Y61614D02*
G02X1755591I3937J0D01*
G02X1747717I-3937J0D01*
G01X1755906Y333465D02*
G02X1777953I11023J0D01*
G02X1755906I-11023J0D01*
G01X1755315Y1215000D02*
G02X1767913I6299J0D01*
G02X1755315I-6299J0D01*
G01X1767717Y765197D02*
G02X1789764I11023J0D01*
G02X1767717I-11023J0D01*
G01X1783986Y23622D02*
G02X1806033I11023J0D01*
G02X1783986I-11023J0D01*
G01X1823425Y59843D02*
Y53543D01*
G02X1811220I-6103J0D01*
G01Y59843D01*
G02X1823425I6102J0D01*
G01X1820866Y1235630D02*
G02X1833465I6299J0D01*
G02X1820866I-6300J0D01*
G01X1811220Y1567323D02*
G02X1823425I6102J0D01*
G02X1811220I-6103J0D01*
G01X1806299Y1604724D02*
G02X1828346I11023J0D01*
G02X1806299I-11023J0D01*
G01X1900999Y2076561D02*
Y2077561D01*
X1901199D01*
X1901266Y2077511D01*
X1901316Y2077394D01*
X1901333Y2077261D01*
X1901316Y2077128D01*
X1901274Y2077028D01*
X1901199Y2076978D01*
X1900999D01*
G01X1901933Y2076561D02*
X1901599D01*
Y2077561D01*
X1901933D01*
G01X1901799Y2077078D02*
X1901599D01*
G01X1902191Y2076561D02*
X1902541Y2077561D01*
G01X1902191D02*
X1902541Y2076561D01*
G01X1902808Y2077394D02*
X1902858Y2077494D01*
X1902916Y2077544D01*
X1902983Y2077561D01*
X1903066Y2077528D01*
X1903124Y2077444D01*
X1903141Y2077344D01*
X1903133Y2077244D01*
X1903099Y2077161D01*
X1902933Y2076994D01*
X1902858Y2076878D01*
X1902808Y2076711D01*
X1902791Y2076561D01*
X1903141D01*
G01X1903316Y2076228D02*
X1903816D01*
G01X1903991Y2076561D02*
Y2077561D01*
G01X1904341D02*
Y2076561D01*
G01Y2077061D02*
X1903991D01*
G01X1904591Y2076694D02*
X1904658Y2076611D01*
X1904733Y2076561D01*
X1904799D01*
X1904866Y2076611D01*
X1904916Y2076694D01*
X1904941Y2076811D01*
X1904924Y2076928D01*
X1904883Y2077028D01*
X1904808Y2077094D01*
X1904708Y2077128D01*
X1904649Y2077194D01*
X1904624Y2077311D01*
X1904641Y2077428D01*
X1904683Y2077511D01*
X1904741Y2077561D01*
X1904799D01*
X1904858Y2077528D01*
X1904908Y2077444D01*
G01X1913099Y2076561D02*
Y2077561D01*
X1913299D01*
X1913366Y2077511D01*
X1913416Y2077394D01*
X1913433Y2077261D01*
X1913416Y2077128D01*
X1913374Y2077028D01*
X1913299Y2076978D01*
X1913099D01*
G01X1914033Y2076561D02*
X1913699D01*
Y2077561D01*
X1914033D01*
G01X1913899Y2077078D02*
X1913699D01*
G01X1914291Y2076561D02*
X1914641Y2077561D01*
G01X1914291D02*
X1914641Y2076561D01*
G01X1915066D02*
Y2077561D01*
X1914966Y2077361D01*
G01Y2076561D02*
X1915166D01*
G01X1915416Y2076228D02*
X1915916D01*
G01X1916091Y2076561D02*
Y2077561D01*
G01X1916441D02*
Y2076561D01*
G01Y2077061D02*
X1916091D01*
G01X1916691Y2076694D02*
X1916758Y2076611D01*
X1916833Y2076561D01*
X1916899D01*
X1916966Y2076611D01*
X1917016Y2076694D01*
X1917041Y2076811D01*
X1917024Y2076928D01*
X1916983Y2077028D01*
X1916908Y2077094D01*
X1916808Y2077128D01*
X1916749Y2077194D01*
X1916724Y2077311D01*
X1916741Y2077428D01*
X1916783Y2077511D01*
X1916841Y2077561D01*
X1916899D01*
X1916958Y2077528D01*
X1917008Y2077444D01*
G01X1925199Y2064461D02*
Y2065461D01*
X1925399D01*
X1925466Y2065411D01*
X1925516Y2065294D01*
X1925533Y2065161D01*
X1925516Y2065028D01*
X1925474Y2064928D01*
X1925399Y2064878D01*
X1925199D01*
G01X1926133Y2064461D02*
X1925799D01*
Y2065461D01*
X1926133D01*
G01X1925999Y2064978D02*
X1925799D01*
G01X1926391Y2064461D02*
X1926741Y2065461D01*
G01X1926391D02*
X1926741Y2064461D01*
G01X1926983Y2064661D02*
X1927033Y2064544D01*
X1927099Y2064478D01*
X1927174Y2064461D01*
X1927241Y2064478D01*
X1927308Y2064561D01*
X1927349Y2064661D01*
X1927358Y2064761D01*
X1927341Y2064878D01*
X1927283Y2064961D01*
X1927224Y2064994D01*
X1927149D01*
G01X1927224D02*
X1927274Y2065044D01*
X1927316Y2065128D01*
X1927333Y2065228D01*
X1927316Y2065328D01*
X1927274Y2065411D01*
X1927199Y2065461D01*
X1927124Y2065444D01*
X1927049Y2065378D01*
G01X1927516Y2064128D02*
X1928016D01*
G01X1928191Y2064461D02*
Y2065461D01*
G01X1928541D02*
Y2064461D01*
G01Y2064961D02*
X1928191D01*
G01X1928791Y2064594D02*
X1928858Y2064511D01*
X1928933Y2064461D01*
X1928999D01*
X1929066Y2064511D01*
X1929116Y2064594D01*
X1929141Y2064711D01*
X1929124Y2064828D01*
X1929083Y2064928D01*
X1929008Y2064994D01*
X1928908Y2065028D01*
X1928849Y2065094D01*
X1928824Y2065211D01*
X1928841Y2065328D01*
X1928883Y2065411D01*
X1928941Y2065461D01*
X1928999D01*
X1929058Y2065428D01*
X1929108Y2065344D01*
G01X1925199Y2076561D02*
Y2077561D01*
X1925399D01*
X1925466Y2077511D01*
X1925516Y2077394D01*
X1925533Y2077261D01*
X1925516Y2077128D01*
X1925474Y2077028D01*
X1925399Y2076978D01*
X1925199D01*
G01X1926133Y2076561D02*
X1925799D01*
Y2077561D01*
X1926133D01*
G01X1925999Y2077078D02*
X1925799D01*
G01X1926391Y2076561D02*
X1926741Y2077561D01*
G01X1926391D02*
X1926741Y2076561D01*
G01X1927166Y2077561D02*
X1927099Y2077528D01*
X1927049Y2077444D01*
X1927016Y2077344D01*
X1926991Y2077211D01*
X1926983Y2077061D01*
X1926991Y2076911D01*
X1927016Y2076778D01*
X1927049Y2076678D01*
X1927099Y2076594D01*
X1927166Y2076561D01*
X1927233Y2076594D01*
X1927283Y2076678D01*
X1927316Y2076778D01*
X1927341Y2076911D01*
X1927349Y2077061D01*
X1927341Y2077211D01*
X1927316Y2077344D01*
X1927283Y2077444D01*
X1927233Y2077528D01*
X1927166Y2077561D01*
G01X1927516Y2076228D02*
X1928016D01*
G01X1928191Y2076561D02*
Y2077561D01*
G01X1928541D02*
Y2076561D01*
G01Y2077061D02*
X1928191D01*
G01X1928791Y2076694D02*
X1928858Y2076611D01*
X1928933Y2076561D01*
X1928999D01*
X1929066Y2076611D01*
X1929116Y2076694D01*
X1929141Y2076811D01*
X1929124Y2076928D01*
X1929083Y2077028D01*
X1929008Y2077094D01*
X1928908Y2077128D01*
X1928849Y2077194D01*
X1928824Y2077311D01*
X1928841Y2077428D01*
X1928883Y2077511D01*
X1928941Y2077561D01*
X1928999D01*
X1929058Y2077528D01*
X1929108Y2077444D01*
G01X1946951Y2054590D02*
X1947951Y2054798D01*
X1946951Y2055006D01*
G01X1947951Y2055231D02*
X1946951D01*
Y2055440D01*
X1947001Y2055506D01*
X1947068Y2055548D01*
X1947201Y2055565D01*
X1947334Y2055548D01*
X1947418Y2055498D01*
X1947468Y2055440D01*
Y2055231D01*
G01Y2055440D02*
X1947951Y2055565D01*
G01X1948284Y2055748D02*
Y2056248D01*
G01X1947951Y2056423D02*
X1946951D01*
G01Y2056773D02*
X1947951D01*
G01X1947451D02*
Y2056423D01*
G01X1947818Y2057023D02*
X1947901Y2057090D01*
X1947951Y2057165D01*
Y2057231D01*
X1947901Y2057298D01*
X1947818Y2057348D01*
X1947701Y2057373D01*
X1947584Y2057356D01*
X1947484Y2057315D01*
X1947418Y2057240D01*
X1947384Y2057140D01*
X1947318Y2057081D01*
X1947201Y2057056D01*
X1947084Y2057073D01*
X1947001Y2057115D01*
X1946951Y2057173D01*
Y2057231D01*
X1946984Y2057290D01*
X1947068Y2057340D01*
G01X1946951Y2057798D02*
X1946984Y2057731D01*
X1947068Y2057681D01*
X1947168Y2057648D01*
X1947301Y2057623D01*
X1947451Y2057615D01*
X1947601Y2057623D01*
X1947734Y2057648D01*
X1947834Y2057681D01*
X1947918Y2057731D01*
X1947951Y2057798D01*
X1947918Y2057865D01*
X1947834Y2057915D01*
X1947734Y2057948D01*
X1947601Y2057973D01*
X1947451Y2057981D01*
X1947301Y2057973D01*
X1947168Y2057948D01*
X1947068Y2057915D01*
X1946984Y2057865D01*
X1946951Y2057798D01*
G01X1936738Y2055885D02*
X1937738Y2056093D01*
X1936738Y2056301D01*
G01X1937738Y2056526D02*
X1936738D01*
Y2056735D01*
X1936788Y2056801D01*
X1936855Y2056843D01*
X1936988Y2056860D01*
X1937121Y2056843D01*
X1937205Y2056793D01*
X1937255Y2056735D01*
Y2056526D01*
G01Y2056735D02*
X1937738Y2056860D01*
G01X1938071Y2057043D02*
Y2057543D01*
G01X1937738Y2057718D02*
X1936738D01*
G01Y2058068D02*
X1937738D01*
G01X1937238D02*
Y2057718D01*
G01X1937605Y2058318D02*
X1937688Y2058385D01*
X1937738Y2058460D01*
Y2058526D01*
X1937688Y2058593D01*
X1937605Y2058643D01*
X1937488Y2058668D01*
X1937371Y2058651D01*
X1937271Y2058610D01*
X1937205Y2058535D01*
X1937171Y2058435D01*
X1937105Y2058376D01*
X1936988Y2058351D01*
X1936871Y2058368D01*
X1936788Y2058410D01*
X1936738Y2058468D01*
Y2058526D01*
X1936771Y2058585D01*
X1936855Y2058635D01*
G01X1937738Y2059093D02*
X1936738D01*
X1936938Y2058993D01*
G01X1937738D02*
Y2059193D01*
G01X-1490433Y-1677216D02*
Y3837819D01*
X4496476D01*
Y-1677216D01*
X-1490433D01*
G01X-7782Y-515685D02*
X-6215D01*
Y-517575D01*
X-6685Y-518205D01*
X-7234Y-518625D01*
X-8017Y-518835D01*
X-8800Y-518625D01*
X-9349Y-518205D01*
X-9819Y-517575D01*
X-10132Y-516840D01*
X-10289Y-516000D01*
Y-515265D01*
X-10132Y-514635D01*
X-9819Y-513900D01*
X-9349Y-513270D01*
X-8879Y-512850D01*
X-8252Y-512535D01*
X-7704D01*
X-7077Y-512745D01*
X-6607Y-513165D01*
G01X-3675Y-512535D02*
Y-517050D01*
X-3362Y-517995D01*
X-2735Y-518625D01*
X-1952Y-518835D01*
X-1169Y-518625D01*
X-542Y-517995D01*
X-229Y-517050D01*
Y-512535D01*
G01X3408D02*
X5288D01*
G01X4348D02*
Y-518835D01*
G01X3408D02*
X5288D01*
G01X9003Y-517995D02*
X9630Y-518520D01*
X10335Y-518835D01*
X10961D01*
X11588Y-518520D01*
X12058Y-517995D01*
X12293Y-517260D01*
X12136Y-516525D01*
X11745Y-515895D01*
X11040Y-515475D01*
X10100Y-515265D01*
X9551Y-514845D01*
X9316Y-514110D01*
X9473Y-513375D01*
X9865Y-512850D01*
X10413Y-512535D01*
X10961D01*
X11510Y-512745D01*
X11980Y-513270D01*
G01X15303Y-518835D02*
Y-512535D01*
G01X18593D02*
Y-518835D01*
G01Y-515685D02*
X15303D01*
G01X21290Y-518835D02*
X23248Y-512535D01*
X25206Y-518835D01*
G01X24501Y-516630D02*
X21995D01*
G01X27746Y-518835D02*
Y-512535D01*
X31350Y-518835D01*
Y-512535D01*
G01X40425Y-518835D02*
Y-512535D01*
X41991D01*
X42618Y-512850D01*
X43088Y-513270D01*
X43480Y-513900D01*
X43793Y-514635D01*
X43871Y-515685D01*
X43793Y-516735D01*
X43480Y-517470D01*
X43088Y-518100D01*
X42618Y-518520D01*
X41991Y-518835D01*
X40425D01*
G01X47508Y-512535D02*
X49388D01*
G01X48448D02*
Y-518835D01*
G01X47508D02*
X49388D01*
G01X53103Y-517995D02*
X53730Y-518520D01*
X54435Y-518835D01*
X55061D01*
X55688Y-518520D01*
X56158Y-517995D01*
X56393Y-517260D01*
X56236Y-516525D01*
X55845Y-515895D01*
X55140Y-515475D01*
X54200Y-515265D01*
X53651Y-514845D01*
X53416Y-514110D01*
X53573Y-513375D01*
X53965Y-512850D01*
X54513Y-512535D01*
X55061D01*
X55610Y-512745D01*
X56080Y-513270D01*
G01X61048Y-512535D02*
Y-518835D01*
G01X59246Y-512535D02*
X62850D01*
G01X67348Y-519045D02*
X67191Y-518940D01*
Y-518730D01*
X67348Y-518625D01*
X67505Y-518730D01*
Y-518940D01*
X67348Y-519045D01*
G01X73491Y-519990D02*
X73805Y-518625D01*
G01X79948Y-512535D02*
Y-518835D01*
G01X78146Y-512535D02*
X81750D01*
G01X84290Y-518835D02*
X86248Y-512535D01*
X88206Y-518835D01*
G01X87501Y-516630D02*
X84995D01*
G01X92548Y-518835D02*
X91921Y-518730D01*
X91373Y-518310D01*
X90903Y-517680D01*
X90590Y-516945D01*
X90433Y-516105D01*
Y-515265D01*
X90590Y-514425D01*
X90903Y-513690D01*
X91373Y-513060D01*
X91921Y-512640D01*
X92548Y-512535D01*
X93175Y-512640D01*
X93723Y-513060D01*
X94193Y-513690D01*
X94506Y-514425D01*
X94663Y-515265D01*
Y-516105D01*
X94506Y-516945D01*
X94193Y-517680D01*
X93723Y-518310D01*
X93175Y-518730D01*
X92548Y-518835D01*
G01X98848D02*
Y-516000D01*
X97281Y-512535D01*
G01X100415D02*
X98848Y-516000D01*
G01X103425Y-512535D02*
Y-517050D01*
X103738Y-517995D01*
X104365Y-518625D01*
X105148Y-518835D01*
X105931Y-518625D01*
X106558Y-517995D01*
X106871Y-517050D01*
Y-512535D01*
G01X109490Y-518835D02*
X111448Y-512535D01*
X113406Y-518835D01*
G01X112701Y-516630D02*
X110195D01*
G01X115946Y-518835D02*
Y-512535D01*
X119550Y-518835D01*
Y-512535D01*
G01X-6529Y-523060D02*
X-6999Y-522745D01*
X-7547Y-522535D01*
X-8174D01*
X-8879Y-522850D01*
X-9427Y-523375D01*
X-9819Y-524005D01*
X-10132Y-525055D01*
X-10210Y-526000D01*
X-10054Y-526945D01*
X-9819Y-527575D01*
X-9349Y-528205D01*
X-8800Y-528625D01*
X-8252Y-528835D01*
X-7704D01*
X-7155Y-528625D01*
X-6685Y-528310D01*
X-6294Y-527890D01*
G01X-2892Y-522535D02*
X-1012D01*
G01X-1952D02*
Y-528835D01*
G01X-2892D02*
X-1012D01*
G01X4348Y-522535D02*
Y-528835D01*
G01X2546Y-522535D02*
X6150D01*
G01X10648Y-528835D02*
Y-526000D01*
X9081Y-522535D01*
G01X12215D02*
X10648Y-526000D01*
G01X21525Y-527575D02*
X21995Y-528310D01*
X22621Y-528730D01*
X23326Y-528835D01*
X23953Y-528730D01*
X24580Y-528205D01*
X24971Y-527575D01*
X25050Y-526945D01*
X24893Y-526210D01*
X24345Y-525685D01*
X23796Y-525475D01*
X23091D01*
G01X23796D02*
X24266Y-525160D01*
X24658Y-524635D01*
X24815Y-524005D01*
X24658Y-523375D01*
X24266Y-522850D01*
X23561Y-522535D01*
X22856Y-522640D01*
X22151Y-523060D01*
G01X27825Y-527575D02*
X28295Y-528310D01*
X28921Y-528730D01*
X29626Y-528835D01*
X30253Y-528730D01*
X30880Y-528205D01*
X31271Y-527575D01*
X31350Y-526945D01*
X31193Y-526210D01*
X30645Y-525685D01*
X30096Y-525475D01*
X29391D01*
G01X30096D02*
X30566Y-525160D01*
X30958Y-524635D01*
X31115Y-524005D01*
X30958Y-523375D01*
X30566Y-522850D01*
X29861Y-522535D01*
X29156Y-522640D01*
X28451Y-523060D01*
G01X34125Y-527575D02*
X34595Y-528310D01*
X35221Y-528730D01*
X35926Y-528835D01*
X36553Y-528730D01*
X37180Y-528205D01*
X37571Y-527575D01*
X37650Y-526945D01*
X37493Y-526210D01*
X36945Y-525685D01*
X36396Y-525475D01*
X35691D01*
G01X36396D02*
X36866Y-525160D01*
X37258Y-524635D01*
X37415Y-524005D01*
X37258Y-523375D01*
X36866Y-522850D01*
X36161Y-522535D01*
X35456Y-522640D01*
X34751Y-523060D01*
G01X41991Y-528835D02*
X42148Y-527470D01*
X42383Y-526315D01*
X42696Y-525265D01*
X43088Y-524110D01*
X43715Y-522535D01*
X40581D01*
G01X48291Y-528835D02*
X48448Y-527470D01*
X48683Y-526315D01*
X48996Y-525265D01*
X49388Y-524110D01*
X50015Y-522535D01*
X46881D01*
G01X54591Y-529990D02*
X54905Y-528625D01*
G01X61048Y-522535D02*
Y-528835D01*
G01X59246Y-522535D02*
X62850D01*
G01X65390Y-528835D02*
X67348Y-522535D01*
X69306Y-528835D01*
G01X68601Y-526630D02*
X66095D01*
G01X72708Y-522535D02*
X74588D01*
G01X73648D02*
Y-528835D01*
G01X72708D02*
X74588D01*
G01X77598Y-522535D02*
X78695Y-528835D01*
X79948Y-522535D01*
X81201Y-528835D01*
X82298Y-522535D01*
G01X84290Y-528835D02*
X86248Y-522535D01*
X88206Y-528835D01*
G01X87501Y-526630D02*
X84995D01*
G01X90746Y-528835D02*
Y-522535D01*
X94350Y-528835D01*
Y-522535D01*
G01X104756Y-530935D02*
X103973Y-529885D01*
X103581Y-528835D01*
Y-524635D01*
X103973Y-523585D01*
X104756Y-522535D01*
G01X116181Y-528835D02*
Y-522535D01*
X118140D01*
X118766Y-522850D01*
X119158Y-523270D01*
X119315Y-524110D01*
X119158Y-524950D01*
X118688Y-525475D01*
X118140Y-525790D01*
X116181D01*
G01X118140D02*
X119315Y-528835D01*
G01X124048Y-529045D02*
X123891Y-528940D01*
Y-528730D01*
X124048Y-528625D01*
X124205Y-528730D01*
Y-528940D01*
X124048Y-529045D01*
G01X130348Y-528835D02*
X129721Y-528730D01*
X129173Y-528310D01*
X128703Y-527680D01*
X128390Y-526945D01*
X128233Y-526105D01*
Y-525265D01*
X128390Y-524425D01*
X128703Y-523690D01*
X129173Y-523060D01*
X129721Y-522640D01*
X130348Y-522535D01*
X130975Y-522640D01*
X131523Y-523060D01*
X131993Y-523690D01*
X132306Y-524425D01*
X132463Y-525265D01*
Y-526105D01*
X132306Y-526945D01*
X131993Y-527680D01*
X131523Y-528310D01*
X130975Y-528730D01*
X130348Y-528835D01*
G01X136648Y-529045D02*
X136491Y-528940D01*
Y-528730D01*
X136648Y-528625D01*
X136805Y-528730D01*
Y-528940D01*
X136648Y-529045D01*
G01X144671Y-523060D02*
X144201Y-522745D01*
X143653Y-522535D01*
X143026D01*
X142321Y-522850D01*
X141773Y-523375D01*
X141381Y-524005D01*
X141068Y-525055D01*
X140990Y-526000D01*
X141146Y-526945D01*
X141381Y-527575D01*
X141851Y-528205D01*
X142400Y-528625D01*
X142948Y-528835D01*
X143496D01*
X144045Y-528625D01*
X144515Y-528310D01*
X144906Y-527890D01*
G01X149248Y-529045D02*
X149091Y-528940D01*
Y-528730D01*
X149248Y-528625D01*
X149405Y-528730D01*
Y-528940D01*
X149248Y-529045D01*
G01X155940Y-530935D02*
X156723Y-529885D01*
X157115Y-528835D01*
Y-524635D01*
X156723Y-523585D01*
X155940Y-522535D01*
G01X-10054Y-508835D02*
Y-502535D01*
X-6450Y-508835D01*
Y-502535D01*
G01X-1952Y-508835D02*
X-2579Y-508730D01*
X-3127Y-508310D01*
X-3597Y-507680D01*
X-3910Y-506945D01*
X-4067Y-506105D01*
Y-505265D01*
X-3910Y-504425D01*
X-3597Y-503690D01*
X-3127Y-503060D01*
X-2579Y-502640D01*
X-1952Y-502535D01*
X-1325Y-502640D01*
X-777Y-503060D01*
X-307Y-503690D01*
X6Y-504425D01*
X163Y-505265D01*
Y-506105D01*
X6Y-506945D01*
X-307Y-507680D01*
X-777Y-508310D01*
X-1325Y-508730D01*
X-1952Y-508835D01*
G01X4348Y-509045D02*
X4191Y-508940D01*
Y-508730D01*
X4348Y-508625D01*
X4505Y-508730D01*
Y-508940D01*
X4348Y-509045D01*
G01X9160Y-503585D02*
X9630Y-502955D01*
X10178Y-502640D01*
X10805Y-502535D01*
X11588Y-502745D01*
X12136Y-503270D01*
X12293Y-503900D01*
X12215Y-504530D01*
X11901Y-505055D01*
X10335Y-506105D01*
X9630Y-506840D01*
X9160Y-507890D01*
X9003Y-508835D01*
X12293D01*
G01X16948D02*
Y-502535D01*
X16008Y-503795D01*
G01Y-508835D02*
X17888D01*
G01X23248D02*
Y-502535D01*
X22308Y-503795D01*
G01Y-508835D02*
X24188D01*
G01X29391Y-509990D02*
X29705Y-508625D01*
G01X33498Y-502535D02*
X34595Y-508835D01*
X35848Y-502535D01*
X37101Y-508835D01*
X38198Y-502535D01*
G01X43715Y-508835D02*
X40581D01*
Y-502535D01*
X43715D01*
G01X42461Y-505580D02*
X40581D01*
G01X46646Y-508835D02*
Y-502535D01*
X50250Y-508835D01*
Y-502535D01*
G01X53103Y-508835D02*
Y-502535D01*
G01X56393D02*
Y-508835D01*
G01Y-505685D02*
X53103D01*
G01X59325Y-502535D02*
Y-507050D01*
X59638Y-507995D01*
X60265Y-508625D01*
X61048Y-508835D01*
X61831Y-508625D01*
X62458Y-507995D01*
X62771Y-507050D01*
Y-502535D01*
G01X65390Y-508835D02*
X67348Y-502535D01*
X69306Y-508835D01*
G01X68601Y-506630D02*
X66095D01*
G01X78460Y-503585D02*
X78930Y-502955D01*
X79478Y-502640D01*
X80105Y-502535D01*
X80888Y-502745D01*
X81436Y-503270D01*
X81593Y-503900D01*
X81515Y-504530D01*
X81201Y-505055D01*
X79635Y-506105D01*
X78930Y-506840D01*
X78460Y-507890D01*
X78303Y-508835D01*
X81593D01*
G01X84446D02*
Y-502535D01*
X88050Y-508835D01*
Y-502535D01*
G01X90825Y-508835D02*
Y-502535D01*
X92391D01*
X93018Y-502850D01*
X93488Y-503270D01*
X93880Y-503900D01*
X94193Y-504635D01*
X94271Y-505685D01*
X94193Y-506735D01*
X93880Y-507470D01*
X93488Y-508100D01*
X93018Y-508520D01*
X92391Y-508835D01*
X90825D01*
G01X103581D02*
Y-502535D01*
X105540D01*
X106166Y-502850D01*
X106558Y-503270D01*
X106715Y-504110D01*
X106558Y-504950D01*
X106088Y-505475D01*
X105540Y-505790D01*
X103581D01*
G01X105540D02*
X106715Y-508835D01*
G01X109725D02*
Y-502535D01*
X111291D01*
X111918Y-502850D01*
X112388Y-503270D01*
X112780Y-503900D01*
X113093Y-504635D01*
X113171Y-505685D01*
X113093Y-506735D01*
X112780Y-507470D01*
X112388Y-508100D01*
X111918Y-508520D01*
X111291Y-508835D01*
X109725D01*
G01X117748Y-509045D02*
X117591Y-508940D01*
Y-508730D01*
X117748Y-508625D01*
X117905Y-508730D01*
Y-508940D01*
X117748Y-509045D01*
G01X2765Y116186D02*
X4987D01*
X5452Y116339D01*
X5762Y116646D01*
X5865Y117029D01*
X5762Y117412D01*
X5452Y117719D01*
X4987Y117872D01*
X2765D01*
G01X5865Y120129D02*
X2765D01*
X3385Y119669D01*
G01X5865D02*
Y120589D01*
G01X3282Y122501D02*
X2972Y122731D01*
X2817Y122999D01*
X2765Y123306D01*
X2868Y123689D01*
X3127Y123957D01*
X3437Y124034D01*
X3747Y123996D01*
X4005Y123842D01*
X4522Y123076D01*
X4883Y122731D01*
X5400Y122501D01*
X5865Y122424D01*
Y124034D01*
G01X4573Y125601D02*
X4212Y125869D01*
X4005Y126099D01*
X3902Y126406D01*
X4005Y126674D01*
X4212Y126866D01*
X4522Y127019D01*
X4883Y127057D01*
X5193Y127019D01*
X5503Y126866D01*
X5762Y126636D01*
X5865Y126367D01*
X5762Y126061D01*
X5452Y125792D01*
X4987Y125639D01*
X4470Y125601D01*
X3798Y125677D01*
X3437Y125792D01*
X3075Y125984D01*
X2817Y126252D01*
X2765Y126521D01*
X2868Y126789D01*
X3127Y126981D01*
G01X14048Y-498135D02*
X11528Y-497718D01*
X9323Y-496052D01*
X7433Y-493552D01*
X6173Y-490635D01*
X5543Y-487302D01*
Y-483968D01*
X6173Y-480635D01*
X7433Y-477718D01*
X9323Y-475219D01*
X11528Y-473552D01*
X14048Y-473135D01*
X16568Y-473552D01*
X18773Y-475219D01*
X20663Y-477718D01*
X21923Y-480635D01*
X22553Y-483968D01*
Y-487302D01*
X21923Y-490635D01*
X20663Y-493552D01*
X18773Y-496052D01*
X16568Y-497718D01*
X14048Y-498135D01*
G01X16568Y-491468D02*
X20348Y-498135D01*
G01X33893Y-481469D02*
Y-493135D01*
X35153Y-496052D01*
X37043Y-497718D01*
X39248Y-498135D01*
X41453Y-497718D01*
X43343Y-496052D01*
X44603Y-493135D01*
G01Y-498135D02*
Y-481469D01*
G01X70118Y-498135D02*
Y-481469D01*
G01Y-484385D02*
X68858Y-482719D01*
X66968Y-481885D01*
X64763Y-481469D01*
X62558Y-482302D01*
X60668Y-483968D01*
X59408Y-486469D01*
X58778Y-489802D01*
X59408Y-493135D01*
X60668Y-495636D01*
X62558Y-497302D01*
X64763Y-498135D01*
X66968Y-497718D01*
X68858Y-496469D01*
X70118Y-494802D01*
G01X84293Y-498135D02*
Y-481469D01*
G01Y-485635D02*
X85553Y-483552D01*
X87443Y-481885D01*
X89963Y-481469D01*
X92168Y-481885D01*
X94058Y-483552D01*
X95003Y-486469D01*
Y-498135D01*
G01X114848Y-473135D02*
Y-498135D01*
G01X110438Y-481469D02*
X119258D01*
G01X145718Y-498135D02*
Y-481469D01*
G01Y-484385D02*
X144458Y-482719D01*
X142568Y-481885D01*
X140363Y-481469D01*
X138158Y-482302D01*
X136268Y-483968D01*
X135008Y-486469D01*
X134378Y-489802D01*
X135008Y-493135D01*
X136268Y-495636D01*
X138158Y-497302D01*
X140363Y-498135D01*
X142568Y-497718D01*
X144458Y-496469D01*
X145718Y-494802D01*
G01X18500Y58307D02*
X20722D01*
X21187Y58460D01*
X21497Y58767D01*
X21600Y59150D01*
X21497Y59533D01*
X21187Y59840D01*
X20722Y59993D01*
X18500D01*
G01X20980Y61407D02*
X21342Y61637D01*
X21548Y61943D01*
X21600Y62288D01*
X21548Y62595D01*
X21290Y62902D01*
X20980Y63093D01*
X20670Y63132D01*
X20308Y63055D01*
X20050Y62787D01*
X19947Y62518D01*
Y62173D01*
G01Y62518D02*
X19792Y62748D01*
X19533Y62940D01*
X19223Y63017D01*
X18913Y62940D01*
X18655Y62748D01*
X18500Y62403D01*
X18552Y62058D01*
X18758Y61713D01*
G01X21238Y64698D02*
X21497Y64967D01*
X21600Y65273D01*
X21497Y65580D01*
X21187Y65848D01*
X20722Y66040D01*
X20257Y66117D01*
X19688D01*
X19223Y66040D01*
X18810Y65848D01*
X18603Y65618D01*
X18500Y65350D01*
X18603Y65043D01*
X18810Y64813D01*
X19120Y64660D01*
X19533Y64583D01*
X19895Y64660D01*
X20257Y64852D01*
X20463Y65082D01*
X20515Y65350D01*
X20412Y65657D01*
X20153Y65887D01*
X19688Y66117D01*
G01X21600Y68450D02*
X21548Y68718D01*
X21393Y69025D01*
X21135Y69217D01*
X20773Y69293D01*
X20412Y69217D01*
X20102Y68987D01*
X19947Y68642D01*
Y68258D01*
X19843Y68028D01*
X19585Y67837D01*
X19223Y67760D01*
X18862Y67875D01*
X18603Y68143D01*
X18500Y68450D01*
X18603Y68757D01*
X18862Y69025D01*
X19223Y69140D01*
X19585Y69063D01*
X19843Y68872D01*
X19947Y68642D01*
Y68258D01*
X20102Y67913D01*
X20412Y67683D01*
X20773Y67607D01*
X21135Y67683D01*
X21393Y67875D01*
X21548Y68182D01*
X21600Y68450D01*
G01X4672Y63335D02*
Y78689D01*
G01X17350Y63335D02*
X4672D01*
G01X17350Y78689D02*
Y63335D01*
G01X14386Y80828D02*
X11186D01*
G01X14386Y87028D02*
Y80828D01*
G01X11186D02*
Y87028D01*
G01X7186Y80828D02*
Y87028D01*
G01X10386Y80828D02*
X7186D01*
G01X10386Y87028D02*
Y80828D01*
G01X4869Y78689D02*
X17350D01*
G01X11186Y87028D02*
X14386D01*
G01X7186D02*
X10386D01*
G01X11892Y95111D02*
X8692D01*
G01X11892Y101311D02*
Y95111D01*
G01X8692D02*
Y101311D01*
G01X15892Y95111D02*
X12692D01*
G01X15892Y101311D02*
Y95111D01*
G01X12692D02*
Y101311D01*
G01X4698Y95066D02*
Y101266D01*
G01X7898Y95066D02*
X4698D01*
G01X7898Y101266D02*
Y95066D01*
G01X16698D02*
Y101266D01*
G01X19898Y95066D02*
X16698D01*
G01X18696Y114511D02*
X6492D01*
G01X18696Y126035D02*
Y114511D01*
G01X6492D02*
Y117171D01*
G01X10889Y106601D02*
Y103401D01*
G01X4689Y106601D02*
X10889D01*
G01X4689Y103401D02*
Y106601D01*
G01X10889Y103401D02*
X4689D01*
G01X8692Y101311D02*
X11892D01*
G01X12692D02*
X15892D01*
G01X4698Y101266D02*
X7898D01*
G01X16698D02*
X19898D01*
G01X6492Y126035D02*
X18696D01*
G01X6492Y123273D02*
Y126035D01*
G01X9594Y120273D02*
X6492Y123273D01*
G01Y117171D02*
X9594Y120273D01*
G01X4899Y140464D02*
X8099D01*
G01X4899Y134264D02*
Y140464D01*
G01X8099Y134264D02*
X4899D01*
G01X8099Y140464D02*
Y134264D01*
G01X17548Y134192D02*
X14348D01*
G01X17548Y140392D02*
Y134192D01*
G01X14348Y140392D02*
X17548D01*
G01X14348Y134192D02*
Y140392D01*
G01X13599Y134264D02*
X10399D01*
G01X13599Y140464D02*
Y134264D01*
G01X10399Y140464D02*
X13599D01*
G01X10399Y134264D02*
Y140464D01*
G01X21455Y134287D02*
X18255D01*
G01Y140487D02*
X21455D01*
G01X18255Y134287D02*
Y140487D01*
G01X13584Y145703D02*
Y151903D01*
G01X16784Y145703D02*
X13584D01*
G01X16784Y151903D02*
Y145703D01*
G01X17584D02*
Y151903D01*
G01X20784Y145703D02*
X17584D01*
G01X6664Y160630D02*
X9864D01*
G01X6664Y154430D02*
Y160630D01*
G01X9864Y154430D02*
X6664D01*
G01X9864Y160630D02*
Y154430D01*
G01X13584Y151903D02*
X16784D01*
G01X17584D02*
X20784D01*
G01X9485Y165830D02*
X6385D01*
Y166750D01*
X6540Y167057D01*
X6902Y167287D01*
X7315Y167364D01*
X7728Y167287D01*
X8038Y167095D01*
X8193Y166750D01*
Y165830D01*
G01X6385Y168854D02*
X8607D01*
X9072Y169007D01*
X9382Y169314D01*
X9485Y169697D01*
X9382Y170080D01*
X9072Y170387D01*
X8607Y170540D01*
X6385D01*
G01X9485Y172797D02*
X9433Y173065D01*
X9278Y173372D01*
X9020Y173564D01*
X8658Y173640D01*
X8297Y173564D01*
X7987Y173334D01*
X7832Y172989D01*
Y172605D01*
X7728Y172375D01*
X7470Y172184D01*
X7108Y172107D01*
X6747Y172222D01*
X6488Y172490D01*
X6385Y172797D01*
X6488Y173104D01*
X6747Y173372D01*
X7108Y173487D01*
X7470Y173410D01*
X7728Y173219D01*
X7832Y172989D01*
Y172605D01*
X7987Y172260D01*
X8297Y172030D01*
X8658Y171954D01*
X9020Y172030D01*
X9278Y172222D01*
X9433Y172529D01*
X9485Y172797D01*
G01Y175897D02*
X6385D01*
X7005Y175437D01*
G01X9485D02*
Y176357D01*
G01X12038Y154213D02*
Y165987D01*
G01X21800Y154213D02*
X12038D01*
G01X16595Y180149D02*
Y183249D01*
X17515D01*
X17822Y183094D01*
X18052Y182732D01*
X18129Y182319D01*
X18052Y181906D01*
X17860Y181596D01*
X17515Y181441D01*
X16595D01*
G01X19619Y180149D02*
Y183249D01*
X20385D01*
X20692Y183094D01*
X20922Y182887D01*
X21114Y182577D01*
X21267Y182216D01*
X21305Y181699D01*
X21267Y181182D01*
X21114Y180821D01*
X20922Y180511D01*
X20692Y180304D01*
X20385Y180149D01*
X19619D01*
G01X22834Y181441D02*
X23102Y181802D01*
X23332Y182009D01*
X23639Y182112D01*
X23907Y182009D01*
X24099Y181802D01*
X24252Y181492D01*
X24290Y181131D01*
X24252Y180821D01*
X24099Y180511D01*
X23869Y180252D01*
X23600Y180149D01*
X23294Y180252D01*
X23025Y180562D01*
X22872Y181027D01*
X22834Y181544D01*
X22910Y182216D01*
X23025Y182577D01*
X23217Y182939D01*
X23485Y183197D01*
X23754Y183249D01*
X24022Y183146D01*
X24214Y182887D01*
G01X26662Y183249D02*
X26355Y183146D01*
X26125Y182887D01*
X25972Y182577D01*
X25857Y182164D01*
X25819Y181699D01*
X25857Y181234D01*
X25972Y180821D01*
X26125Y180511D01*
X26355Y180252D01*
X26662Y180149D01*
X26969Y180252D01*
X27199Y180511D01*
X27352Y180821D01*
X27467Y181234D01*
X27505Y181699D01*
X27467Y182164D01*
X27352Y182577D01*
X27199Y182887D01*
X26969Y183146D01*
X26662Y183249D01*
G01X22309Y168702D02*
X19109D01*
G01Y174902D02*
X22309D01*
G01X19109Y168702D02*
Y174902D01*
G01X14309Y168702D02*
X11109D01*
G01X14309Y174902D02*
Y168702D01*
G01X11109Y174902D02*
X14309D01*
G01X11109Y168702D02*
Y174902D01*
G01X15109D02*
X18309D01*
G01X15109Y168702D02*
Y174902D01*
G01X18309Y168702D02*
X15109D01*
G01X18309Y174902D02*
Y168702D01*
G01X12038Y165987D02*
X21800D01*
G01X5628Y189435D02*
X7868D01*
G01X6655Y191060D02*
Y187810D01*
G01X9269Y195583D02*
X38828D01*
G01X9269Y184087D02*
Y195583D01*
G01X38828Y184087D02*
X9269D01*
G01X28245Y197645D02*
X16245D01*
G01D02*
Y203645D01*
G01D02*
X28245D01*
G01X9422Y204506D02*
Y216506D01*
G01X15422Y204506D02*
X9422D01*
G01X15422Y216506D02*
Y204506D01*
G01X16222Y208306D02*
Y214506D01*
G01X19422Y208306D02*
X16222D01*
G01X9422Y216506D02*
X15422D01*
G01X16222Y214506D02*
X19422D01*
G01X16588Y245521D02*
Y254969D01*
G01X27424Y245521D02*
X16588D01*
G01X20426Y231377D02*
X17226D01*
G01Y237577D02*
X20426D01*
G01X17226Y231377D02*
Y237577D01*
G01X14420Y249971D02*
Y246771D01*
G01X8220D02*
Y249971D01*
G01X14420Y246771D02*
X8220D01*
G01X19169Y243678D02*
X25369D01*
G01X19169Y240478D02*
Y243678D01*
G01X25369Y240478D02*
X19169D01*
G01X18390Y243678D02*
Y240478D01*
G01X12190Y243678D02*
X18390D01*
G01X12190Y240478D02*
Y243678D01*
G01X18390Y240478D02*
X12190D01*
G01X17392Y256195D02*
X17085Y256247D01*
X16817Y256453D01*
X16587Y256763D01*
X16434Y257125D01*
X16357Y257538D01*
Y257952D01*
X16434Y258365D01*
X16587Y258727D01*
X16817Y259037D01*
X17085Y259243D01*
X17392Y259295D01*
X17699Y259243D01*
X17967Y259037D01*
X18197Y258727D01*
X18350Y258365D01*
X18427Y257952D01*
Y257538D01*
X18350Y257125D01*
X18197Y256763D01*
X17967Y256453D01*
X17699Y256247D01*
X17392Y256195D01*
G01X17699Y257022D02*
X18159Y256195D01*
G01X20492D02*
Y259295D01*
X20032Y258675D01*
G01Y256195D02*
X20952D01*
G01X22864Y258778D02*
X23094Y259088D01*
X23362Y259243D01*
X23669Y259295D01*
X24052Y259192D01*
X24320Y258933D01*
X24397Y258623D01*
X24359Y258313D01*
X24205Y258055D01*
X23439Y257538D01*
X23094Y257177D01*
X22864Y256660D01*
X22787Y256195D01*
X24397D01*
G01X26615D02*
X26692Y256867D01*
X26807Y257435D01*
X26960Y257952D01*
X27152Y258520D01*
X27459Y259295D01*
X25925D01*
G01X16588Y254969D02*
X20006D01*
G01X8220Y249971D02*
X14420D01*
G01X18390Y263678D02*
Y260478D01*
G01X12190D02*
Y263678D01*
G01X18390Y260478D02*
X12190D01*
G01X19169D02*
Y263678D01*
G01X25369Y260478D02*
X19169D01*
G01X8220Y250771D02*
Y253971D01*
G01X14420Y250771D02*
X8220D01*
G01X14420Y253971D02*
Y250771D01*
G01X8220Y253971D02*
X14420D01*
G01X6239Y277080D02*
X5932Y277132D01*
X5664Y277338D01*
X5434Y277648D01*
X5281Y278010D01*
X5204Y278423D01*
Y278837D01*
X5281Y279250D01*
X5434Y279612D01*
X5664Y279922D01*
X5932Y280128D01*
X6239Y280180D01*
X6546Y280128D01*
X6814Y279922D01*
X7044Y279612D01*
X7197Y279250D01*
X7274Y278837D01*
Y278423D01*
X7197Y278010D01*
X7044Y277648D01*
X6814Y277338D01*
X6546Y277132D01*
X6239Y277080D01*
G01X6546Y277907D02*
X7006Y277080D01*
G01X9339D02*
Y280180D01*
X8879Y279560D01*
G01Y277080D02*
X9799D01*
G01X11596Y277700D02*
X11826Y277338D01*
X12132Y277132D01*
X12477Y277080D01*
X12784Y277132D01*
X13091Y277390D01*
X13282Y277700D01*
X13321Y278010D01*
X13244Y278372D01*
X12976Y278630D01*
X12707Y278733D01*
X12362D01*
G01X12707D02*
X12937Y278888D01*
X13129Y279147D01*
X13206Y279457D01*
X13129Y279767D01*
X12937Y280025D01*
X12592Y280180D01*
X12247Y280128D01*
X11902Y279922D01*
G01X14696Y277700D02*
X14926Y277338D01*
X15232Y277132D01*
X15577Y277080D01*
X15884Y277132D01*
X16191Y277390D01*
X16382Y277700D01*
X16421Y278010D01*
X16344Y278372D01*
X16076Y278630D01*
X15807Y278733D01*
X15462D01*
G01X15807D02*
X16037Y278888D01*
X16229Y279147D01*
X16306Y279457D01*
X16229Y279767D01*
X16037Y280025D01*
X15692Y280180D01*
X15347Y280128D01*
X15002Y279922D01*
G01X16588Y274969D02*
X20006D01*
G01X16588Y265521D02*
Y274969D01*
G01X27424Y265521D02*
X16588D01*
G01X12190Y263678D02*
X18390D01*
G01X19169D02*
X25369D01*
G01X8220Y270771D02*
Y273971D01*
G01X14420Y270771D02*
X8220D01*
G01X14420Y273971D02*
Y270771D01*
G01X8220Y273971D02*
X14420D01*
G01Y269971D02*
Y266771D01*
G01X8220Y269971D02*
X14420D01*
G01X8220Y266771D02*
Y269971D01*
G01X14420Y266771D02*
X8220D01*
G01X6810Y282518D02*
Y285718D01*
G01X13010Y282518D02*
X6810D01*
G01X13010Y285718D02*
Y282518D01*
G01X6810Y285718D02*
X13010D01*
G01X7614Y292957D02*
Y290735D01*
X7767Y290270D01*
X8074Y289960D01*
X8457Y289857D01*
X8840Y289960D01*
X9147Y290270D01*
X9300Y290735D01*
Y292957D01*
G01X10714Y290477D02*
X10944Y290115D01*
X11250Y289909D01*
X11595Y289857D01*
X11902Y289909D01*
X12209Y290167D01*
X12400Y290477D01*
X12439Y290787D01*
X12362Y291149D01*
X12094Y291407D01*
X11825Y291510D01*
X11480D01*
G01X11825D02*
X12055Y291665D01*
X12247Y291924D01*
X12324Y292234D01*
X12247Y292544D01*
X12055Y292802D01*
X11710Y292957D01*
X11365Y292905D01*
X11020Y292699D01*
G01X14657Y289857D02*
X14925Y289909D01*
X15232Y290064D01*
X15424Y290322D01*
X15500Y290684D01*
X15424Y291045D01*
X15194Y291355D01*
X14849Y291510D01*
X14465D01*
X14235Y291614D01*
X14044Y291872D01*
X13967Y292234D01*
X14082Y292595D01*
X14350Y292854D01*
X14657Y292957D01*
X14964Y292854D01*
X15232Y292595D01*
X15347Y292234D01*
X15270Y291872D01*
X15079Y291614D01*
X14849Y291510D01*
X14465D01*
X14120Y291355D01*
X13890Y291045D01*
X13814Y290684D01*
X13890Y290322D01*
X14082Y290064D01*
X14389Y289909D01*
X14657Y289857D01*
G01X16914Y290477D02*
X17144Y290115D01*
X17450Y289909D01*
X17795Y289857D01*
X18102Y289909D01*
X18409Y290167D01*
X18600Y290477D01*
X18639Y290787D01*
X18562Y291149D01*
X18294Y291407D01*
X18025Y291510D01*
X17680D01*
G01X18025D02*
X18255Y291665D01*
X18447Y291924D01*
X18524Y292234D01*
X18447Y292544D01*
X18255Y292802D01*
X17910Y292957D01*
X17565Y292905D01*
X17220Y292699D01*
G01X17318Y288782D02*
Y279482D01*
G01X27918Y288782D02*
X17318D01*
G01Y279382D02*
X27918D01*
G01X11088Y994519D02*
Y984319D01*
X6488D01*
Y994519D01*
X11088D01*
G01X16813D02*
Y984319D01*
X12213D01*
Y994519D01*
X16813D01*
G01X22306D02*
Y984319D01*
X17706D01*
Y994519D01*
X22306D01*
G01X8411Y1007221D02*
Y1001021D01*
X5211D01*
Y1007221D01*
X8411D01*
G01X12301D02*
Y1001021D01*
X9101D01*
Y1007221D01*
X12301D01*
G01X16245D02*
Y1001021D01*
X13045D01*
Y1007221D01*
X16245D01*
G01X13266Y1022029D02*
X30968D01*
G01X13266Y1035411D02*
Y1022029D01*
G01X11974Y1037229D02*
Y1046129D01*
G01X32260Y1037229D02*
X11974D01*
G01X13266Y1061329D02*
Y1048509D01*
G01X11974Y1046129D02*
X32260D01*
G01X17392Y1066629D02*
X32192D01*
G01X17392Y1097633D02*
Y1066629D01*
G01X30968Y1061329D02*
X13266D01*
G01X32192Y1097633D02*
X17392D01*
G01X9147Y1112933D02*
Y1105806D01*
X27801D01*
X30801Y1108806D01*
Y1112933D01*
G01X27801Y1127460D02*
X9147D01*
Y1120333D01*
G01X12561Y1132392D02*
Y1186328D01*
G01X30155Y1132392D02*
X12561D01*
G01Y1186328D02*
X30155D01*
G01X6762Y1242735D02*
Y1245835D01*
G01X8372D02*
Y1242735D01*
G01Y1244285D02*
X6762D01*
G01X10667Y1242735D02*
Y1245835D01*
X10207Y1245215D01*
G01Y1242735D02*
X11127D01*
G01X12924Y1243355D02*
X13154Y1242993D01*
X13460Y1242787D01*
X13805Y1242735D01*
X14112Y1242787D01*
X14419Y1243045D01*
X14610Y1243355D01*
X14649Y1243665D01*
X14572Y1244027D01*
X14304Y1244285D01*
X14035Y1244388D01*
X13690D01*
G01X14035D02*
X14265Y1244543D01*
X14457Y1244802D01*
X14534Y1245112D01*
X14457Y1245422D01*
X14265Y1245680D01*
X13920Y1245835D01*
X13575Y1245783D01*
X13230Y1245577D01*
G01X16024Y1243355D02*
X16254Y1242993D01*
X16560Y1242787D01*
X16905Y1242735D01*
X17212Y1242787D01*
X17519Y1243045D01*
X17710Y1243355D01*
X17749Y1243665D01*
X17672Y1244027D01*
X17404Y1244285D01*
X17135Y1244388D01*
X16790D01*
G01X17135D02*
X17365Y1244543D01*
X17557Y1244802D01*
X17634Y1245112D01*
X17557Y1245422D01*
X17365Y1245680D01*
X17020Y1245835D01*
X16675Y1245783D01*
X16330Y1245577D01*
G01X36239Y1373669D02*
G02I-9450J0D01*
G01X16077Y1385758D02*
Y1388858D01*
G01X17687D02*
Y1385758D01*
G01Y1387308D02*
X16077D01*
G01X20442Y1385758D02*
Y1388858D01*
X19024Y1386636D01*
X20940D01*
G01X22354Y1388341D02*
X22584Y1388651D01*
X22852Y1388806D01*
X23159Y1388858D01*
X23542Y1388755D01*
X23810Y1388496D01*
X23887Y1388186D01*
X23849Y1387876D01*
X23695Y1387618D01*
X22929Y1387101D01*
X22584Y1386740D01*
X22354Y1386223D01*
X22277Y1385758D01*
X23887D01*
G01X8839Y1432418D02*
X8787Y1432111D01*
X8581Y1431843D01*
X8271Y1431613D01*
X7909Y1431460D01*
X7496Y1431383D01*
X7082D01*
X6669Y1431460D01*
X6307Y1431613D01*
X5997Y1431843D01*
X5791Y1432111D01*
X5739Y1432418D01*
X5791Y1432725D01*
X5997Y1432993D01*
X6307Y1433223D01*
X6669Y1433376D01*
X7082Y1433453D01*
X7496D01*
X7909Y1433376D01*
X8271Y1433223D01*
X8581Y1432993D01*
X8787Y1432725D01*
X8839Y1432418D01*
G01X8012Y1432725D02*
X8839Y1433185D01*
G01X6256Y1434790D02*
X5946Y1435020D01*
X5791Y1435288D01*
X5739Y1435595D01*
X5842Y1435978D01*
X6101Y1436246D01*
X6411Y1436323D01*
X6721Y1436285D01*
X6979Y1436131D01*
X7496Y1435365D01*
X7857Y1435020D01*
X8374Y1434790D01*
X8839Y1434713D01*
Y1436323D01*
G01X8374Y1437775D02*
X8632Y1438005D01*
X8787Y1438273D01*
X8839Y1438618D01*
X8736Y1438963D01*
X8529Y1439231D01*
X8167Y1439423D01*
X7754Y1439461D01*
X7341Y1439385D01*
X7082Y1439193D01*
X6876Y1438925D01*
X6824Y1438656D01*
X6876Y1438388D01*
X7082Y1438043D01*
X5739Y1438158D01*
Y1439193D01*
G01Y1441718D02*
X5842Y1441411D01*
X6101Y1441181D01*
X6411Y1441028D01*
X6824Y1440913D01*
X7289Y1440875D01*
X7754Y1440913D01*
X8167Y1441028D01*
X8477Y1441181D01*
X8736Y1441411D01*
X8839Y1441718D01*
X8736Y1442025D01*
X8477Y1442255D01*
X8167Y1442408D01*
X7754Y1442523D01*
X7289Y1442561D01*
X6824Y1442523D01*
X6411Y1442408D01*
X6101Y1442255D01*
X5842Y1442025D01*
X5739Y1441718D01*
G01X10433Y1444080D02*
X22245D01*
Y1431456D01*
X10433D01*
Y1444080D01*
G01X8834Y1448122D02*
X8782Y1447815D01*
X8576Y1447547D01*
X8266Y1447317D01*
X7904Y1447164D01*
X7491Y1447087D01*
X7077D01*
X6664Y1447164D01*
X6302Y1447317D01*
X5992Y1447547D01*
X5786Y1447815D01*
X5734Y1448122D01*
X5786Y1448429D01*
X5992Y1448697D01*
X6302Y1448927D01*
X6664Y1449080D01*
X7077Y1449157D01*
X7491D01*
X7904Y1449080D01*
X8266Y1448927D01*
X8576Y1448697D01*
X8782Y1448429D01*
X8834Y1448122D01*
G01X8007Y1448429D02*
X8834Y1448889D01*
G01X6251Y1450494D02*
X5941Y1450724D01*
X5786Y1450992D01*
X5734Y1451299D01*
X5837Y1451682D01*
X6096Y1451950D01*
X6406Y1452027D01*
X6716Y1451989D01*
X6974Y1451835D01*
X7491Y1451069D01*
X7852Y1450724D01*
X8369Y1450494D01*
X8834Y1450417D01*
Y1452027D01*
G01X8369Y1453479D02*
X8627Y1453709D01*
X8782Y1453977D01*
X8834Y1454322D01*
X8731Y1454667D01*
X8524Y1454935D01*
X8162Y1455127D01*
X7749Y1455165D01*
X7336Y1455089D01*
X7077Y1454897D01*
X6871Y1454629D01*
X6819Y1454360D01*
X6871Y1454092D01*
X7077Y1453747D01*
X5734Y1453862D01*
Y1454897D01*
G01X8834Y1457422D02*
X5734D01*
X6354Y1456962D01*
G01X8834D02*
Y1457882D01*
G01X10317Y1447435D02*
Y1459909D01*
X22285D01*
Y1447435D01*
X10317D01*
G01X14779Y1466212D02*
X20979D01*
Y1463012D01*
X14779D01*
Y1466212D01*
G01X18604Y1470619D02*
Y1472014D01*
X17837Y1473719D01*
G01X19371D02*
X18604Y1472014D01*
G01X21052Y1470981D02*
X21321Y1470722D01*
X21627Y1470619D01*
X21934Y1470722D01*
X22202Y1471032D01*
X22394Y1471497D01*
X22471Y1471962D01*
Y1472531D01*
X22394Y1472996D01*
X22202Y1473409D01*
X21972Y1473616D01*
X21704Y1473719D01*
X21397Y1473616D01*
X21167Y1473409D01*
X21014Y1473099D01*
X20937Y1472686D01*
X21014Y1472324D01*
X21206Y1471962D01*
X21436Y1471756D01*
X21704Y1471704D01*
X22011Y1471807D01*
X22241Y1472066D01*
X22471Y1472531D01*
G01X20598Y1493017D02*
Y1477617D01*
X7998D01*
Y1493017D01*
X20598D01*
G01X14690Y1498382D02*
X20890D01*
Y1495182D01*
X14690D01*
Y1498382D01*
G01X13790Y1495182D02*
X7590D01*
Y1498382D01*
X13790D01*
Y1495182D01*
G01X11107Y1503219D02*
X17307D01*
Y1500019D01*
X11107D01*
Y1503219D01*
G01X10181Y1528884D02*
Y1533987D01*
X13381D01*
Y1528905D01*
G01X13368Y1525498D02*
Y1520673D01*
X10168D01*
Y1525582D01*
G01X4960Y1546011D02*
Y1552211D01*
X8160D01*
Y1546011D01*
X4960D01*
G01X15975Y1552173D02*
Y1545973D01*
X12775D01*
Y1552173D01*
X15975D01*
G01X11967Y1552180D02*
Y1545980D01*
X8767D01*
Y1552180D01*
X11967D01*
G01X9252Y1537022D02*
Y1543222D01*
X12452D01*
Y1537022D01*
X9252D01*
G01X11132Y1555283D02*
X4932D01*
Y1558483D01*
X11132D01*
Y1555283D01*
G01X16834Y1547082D02*
Y1553282D01*
X20034D01*
Y1547082D01*
X16834D01*
G01X8989Y1625413D02*
Y1628513D01*
G01X10599D02*
Y1625413D01*
G01Y1626963D02*
X8989D01*
G01X12051Y1625878D02*
X12281Y1625620D01*
X12549Y1625465D01*
X12894Y1625413D01*
X13239Y1625516D01*
X13507Y1625723D01*
X13699Y1626085D01*
X13737Y1626498D01*
X13661Y1626911D01*
X13469Y1627170D01*
X13201Y1627376D01*
X12932Y1627428D01*
X12664Y1627376D01*
X12319Y1627170D01*
X12434Y1628513D01*
X13469D01*
G01X15151Y1626033D02*
X15381Y1625671D01*
X15687Y1625465D01*
X16032Y1625413D01*
X16339Y1625465D01*
X16646Y1625723D01*
X16837Y1626033D01*
X16876Y1626343D01*
X16799Y1626705D01*
X16531Y1626963D01*
X16262Y1627066D01*
X15917D01*
G01X16262D02*
X16492Y1627221D01*
X16684Y1627480D01*
X16761Y1627790D01*
X16684Y1628100D01*
X16492Y1628358D01*
X16147Y1628513D01*
X15802Y1628461D01*
X15457Y1628255D01*
G01X27496Y52896D02*
Y49696D01*
G01X21296D02*
Y52896D01*
G01X27496Y49696D02*
X21296D01*
G01Y52896D02*
X27496D01*
G01Y56905D02*
Y53705D01*
G01X21296Y56905D02*
X27496D01*
G01X21296Y53705D02*
Y56905D01*
G01X27496Y53705D02*
X21296D01*
G01X31404Y69127D02*
Y65927D01*
G01X25204D02*
Y69127D01*
G01X31404Y65927D02*
X25204D01*
G01X31404Y65127D02*
Y61927D01*
G01X25204Y65127D02*
X31404D01*
G01X25204Y61927D02*
Y65127D01*
G01X31404Y61927D02*
X25204D01*
G01X31404Y61127D02*
Y57927D01*
G01X25204Y61127D02*
X31404D01*
G01X25204Y57927D02*
Y61127D01*
G01X31404Y57927D02*
X25204D01*
G01X36847Y57411D02*
X37157Y57603D01*
X37364Y57833D01*
X37467Y58101D01*
X37364Y58408D01*
X37157Y58638D01*
X36847Y58868D01*
X36434Y58945D01*
X34367D01*
G01X36847Y60435D02*
X37209Y60665D01*
X37415Y60971D01*
X37467Y61316D01*
X37415Y61623D01*
X37157Y61930D01*
X36847Y62121D01*
X36537Y62160D01*
X36175Y62083D01*
X35917Y61815D01*
X35814Y61546D01*
Y61201D01*
G01Y61546D02*
X35659Y61776D01*
X35400Y61968D01*
X35090Y62045D01*
X34780Y61968D01*
X34522Y61776D01*
X34367Y61431D01*
X34419Y61086D01*
X34625Y60741D01*
G01X34367Y64378D02*
X34470Y64071D01*
X34729Y63841D01*
X35039Y63688D01*
X35452Y63573D01*
X35917Y63535D01*
X36382Y63573D01*
X36795Y63688D01*
X37105Y63841D01*
X37364Y64071D01*
X37467Y64378D01*
X37364Y64685D01*
X37105Y64915D01*
X36795Y65068D01*
X36382Y65183D01*
X35917Y65221D01*
X35452Y65183D01*
X35039Y65068D01*
X34729Y64915D01*
X34470Y64685D01*
X34367Y64378D01*
G01X25204Y69127D02*
X31404D01*
G01X27498Y96067D02*
Y99267D01*
G01X33698Y96067D02*
X27498D01*
G01X33698Y99267D02*
Y96067D01*
G01X27498Y99267D02*
X33698D01*
G01X19898Y101266D02*
Y95066D01*
G01X29514Y108095D02*
Y104895D01*
G01X23314Y108095D02*
X29514D01*
G01X23314Y104895D02*
Y108095D01*
G01X29514Y104895D02*
X23314D01*
G01Y100895D02*
Y104095D01*
G01X29514Y100895D02*
X23314D01*
G01X29514Y104095D02*
Y100895D01*
G01X23314Y104095D02*
X29514D01*
G01X30371Y108086D02*
X33571D01*
G01X30371Y101886D02*
Y108086D01*
G01X33571Y101886D02*
X30371D01*
G01X33571Y108086D02*
Y101886D01*
G01X21584Y145703D02*
Y151903D01*
G01X24784Y145703D02*
X21584D01*
G01X24784Y151903D02*
Y145703D01*
G01X21455Y140487D02*
Y134287D01*
G01X20784Y151903D02*
Y145703D01*
G01X30201Y164651D02*
Y152651D01*
G01X24201Y164651D02*
X30201D01*
G01X24201Y152651D02*
Y164651D01*
G01X30201Y152651D02*
X24201D01*
G01X21584Y151903D02*
X24784D01*
G01X21800Y165987D02*
Y154213D01*
G01X22309Y174902D02*
Y168702D01*
G01X34032Y179048D02*
Y175848D01*
G01X27832Y179048D02*
X34032D01*
G01X27832Y175848D02*
Y179048D01*
G01X34032Y175848D02*
X27832D01*
G01X28245Y203645D02*
Y197645D01*
G01X26198Y208464D02*
Y205264D01*
G01X19998Y208464D02*
X26198D01*
G01X19998Y205264D02*
Y208464D01*
G01X26198Y205264D02*
X19998D01*
G01X19422Y214506D02*
Y208306D01*
G01X21028Y226801D02*
X33232D01*
Y211497D01*
X21028D01*
Y226801D01*
G01X27424Y254969D02*
Y245521D01*
G01X37801Y231459D02*
X34601D01*
G01Y237659D02*
X37801D01*
G01X34601Y231459D02*
Y237659D01*
G01X25691Y231446D02*
X22491D01*
G01X25691Y237646D02*
Y231446D01*
G01X22491Y237646D02*
X25691D01*
G01X22491Y231446D02*
Y237646D01*
G01X20426Y237577D02*
Y231377D01*
G01X25369Y243678D02*
Y240478D01*
G01X29566Y231434D02*
X26366D01*
G01X29566Y237634D02*
Y231434D01*
G01X26366Y237634D02*
X29566D01*
G01X26366Y231434D02*
Y237634D01*
G01X30601Y237659D02*
X33801D01*
G01X30601Y231459D02*
Y237659D01*
G01X33801Y231459D02*
X30601D01*
G01X33801Y237659D02*
Y231459D01*
G01X29227Y240081D02*
Y243281D01*
G01X35427Y240081D02*
X29227D01*
G01X35427Y243281D02*
Y240081D01*
G01X29227Y243281D02*
X35427D01*
G01X24006Y254969D02*
X27424D01*
G01X22006Y253245D02*
X24006Y254969D01*
G01X20006D02*
X22006Y253245D01*
G01X25369Y263678D02*
Y260478D01*
G01X35031Y252199D02*
Y248999D01*
G01X28831Y252199D02*
X35031D01*
G01X28831Y248999D02*
Y252199D01*
G01X35031Y248999D02*
X28831D01*
G01X24006Y274969D02*
X27424D01*
G01X22006Y273245D02*
X24006Y274969D01*
G01X20006D02*
X22006Y273245D01*
G01X27424Y274969D02*
Y265521D01*
G01X35031Y272199D02*
Y268999D01*
G01X28831Y272199D02*
X35031D01*
G01X28831Y268999D02*
Y272199D01*
G01X35031Y268999D02*
X28831D01*
G01X28154Y294208D02*
Y291008D01*
G01X21954Y294208D02*
X28154D01*
G01X21954Y291008D02*
Y294208D01*
G01X28154Y291008D02*
X21954D01*
G01X30170Y282872D02*
X36370D01*
G01X30170Y279672D02*
Y282872D01*
G01X36370Y279672D02*
X30170D01*
G01Y287672D02*
Y290872D01*
G01X36370Y287672D02*
X30170D01*
G01Y290872D02*
X36370D01*
G01X30170Y283672D02*
Y286872D01*
G01X36370Y283672D02*
X30170D01*
G01Y286872D02*
X36370D01*
G01X27918Y279382D02*
Y288782D01*
G01X35358Y503265D02*
X66450D01*
G01X35358Y518777D02*
Y503265D01*
G01X22783Y508400D02*
Y511500D01*
X23703D01*
X24010Y511345D01*
X24240Y510983D01*
X24317Y510570D01*
X24240Y510157D01*
X24048Y509847D01*
X23703Y509692D01*
X22783D01*
G01X25807Y508400D02*
Y511500D01*
X26573D01*
X26880Y511345D01*
X27110Y511138D01*
X27302Y510828D01*
X27455Y510467D01*
X27493Y509950D01*
X27455Y509433D01*
X27302Y509072D01*
X27110Y508762D01*
X26880Y508555D01*
X26573Y508400D01*
X25807D01*
G01X29022Y510983D02*
X29252Y511293D01*
X29520Y511448D01*
X29827Y511500D01*
X30210Y511397D01*
X30478Y511138D01*
X30555Y510828D01*
X30517Y510518D01*
X30363Y510260D01*
X29597Y509743D01*
X29252Y509382D01*
X29022Y508865D01*
X28945Y508400D01*
X30555D01*
G01X33310D02*
Y511500D01*
X31892Y509278D01*
X33808D01*
G01X66450Y518777D02*
X35358D01*
G01X33074Y538326D02*
Y535126D01*
G01X26874Y538326D02*
X33074D01*
G01X26874Y535126D02*
Y538326D01*
G01X33074Y535126D02*
X26874D01*
G01X33074Y533326D02*
Y530126D01*
G01X26874Y533326D02*
X33074D01*
G01X26874Y530126D02*
Y533326D01*
G01X33074Y530126D02*
X26874D01*
G01X33074Y542326D02*
Y539126D01*
G01X26874D02*
Y542326D01*
G01X33074Y539126D02*
X26874D01*
G01Y526126D02*
Y529326D01*
G01X33074Y526126D02*
X26874D01*
G01X33074Y529326D02*
Y526126D01*
G01X26874Y529326D02*
X33074D01*
G01X34407Y527143D02*
Y530243D01*
X35327D01*
X35634Y530088D01*
X35864Y529726D01*
X35941Y529313D01*
X35864Y528900D01*
X35672Y528590D01*
X35327Y528435D01*
X34407D01*
G01X37431Y530243D02*
Y528021D01*
X37584Y527556D01*
X37891Y527246D01*
X38274Y527143D01*
X38657Y527246D01*
X38964Y527556D01*
X39117Y528021D01*
Y530243D01*
G01X40646Y529726D02*
X40876Y530036D01*
X41144Y530191D01*
X41451Y530243D01*
X41834Y530140D01*
X42102Y529881D01*
X42179Y529571D01*
X42141Y529261D01*
X41987Y529003D01*
X41221Y528486D01*
X40876Y528125D01*
X40646Y527608D01*
X40569Y527143D01*
X42179D01*
G01X43746Y529726D02*
X43976Y530036D01*
X44244Y530191D01*
X44551Y530243D01*
X44934Y530140D01*
X45202Y529881D01*
X45279Y529571D01*
X45241Y529261D01*
X45087Y529003D01*
X44321Y528486D01*
X43976Y528125D01*
X43746Y527608D01*
X43669Y527143D01*
X45279D01*
G01X33074Y554326D02*
Y551126D01*
G01X26874Y554326D02*
X33074D01*
G01X26874Y551126D02*
Y554326D01*
G01X33074Y551126D02*
X26874D01*
G01Y542326D02*
X33074D01*
G01X26874Y547126D02*
Y550326D01*
G01X33074Y547126D02*
X26874D01*
G01X33074Y550326D02*
Y547126D01*
G01X26874Y550326D02*
X33074D01*
G01Y546326D02*
Y543126D01*
G01X26874Y546326D02*
X33074D01*
G01X26874Y543126D02*
Y546326D01*
G01X33074Y543126D02*
X26874D01*
G01X47459Y556194D02*
X35459D01*
G01Y562194D02*
X47459D01*
G01X35459Y556194D02*
Y562194D01*
G01X47459Y564194D02*
X35459D01*
G01Y570194D02*
X47459D01*
G01X35459Y564194D02*
Y570194D01*
G01X47459Y572194D02*
X35459D01*
G01Y578194D02*
X47459D01*
G01X35459Y572194D02*
Y578194D01*
G01X22933Y585713D02*
X25173D01*
G01X23960Y587338D02*
Y584088D01*
G01X26574Y580365D02*
Y591861D01*
G01X56133Y580365D02*
X26574D01*
G01X32092Y604111D02*
X42292D01*
G01X32092Y599511D02*
Y604111D01*
G01X42292Y599511D02*
X32092D01*
G01X26743Y593480D02*
Y596580D01*
X27663D01*
X27970Y596425D01*
X28200Y596063D01*
X28277Y595650D01*
X28200Y595237D01*
X28008Y594927D01*
X27663Y594772D01*
X26743D01*
G01X29767Y593480D02*
Y596580D01*
X30533D01*
X30840Y596425D01*
X31070Y596218D01*
X31262Y595908D01*
X31415Y595547D01*
X31453Y595030D01*
X31415Y594513D01*
X31262Y594152D01*
X31070Y593842D01*
X30840Y593635D01*
X30533Y593480D01*
X29767D01*
G01X33633D02*
X33710Y594152D01*
X33825Y594720D01*
X33978Y595237D01*
X34170Y595805D01*
X34477Y596580D01*
X32943D01*
G01X36810Y593480D02*
X37078Y593532D01*
X37385Y593687D01*
X37577Y593945D01*
X37653Y594307D01*
X37577Y594668D01*
X37347Y594978D01*
X37002Y595133D01*
X36618D01*
X36388Y595237D01*
X36197Y595495D01*
X36120Y595857D01*
X36235Y596218D01*
X36503Y596477D01*
X36810Y596580D01*
X37117Y596477D01*
X37385Y596218D01*
X37500Y595857D01*
X37423Y595495D01*
X37232Y595237D01*
X37002Y595133D01*
X36618D01*
X36273Y594978D01*
X36043Y594668D01*
X35967Y594307D01*
X36043Y593945D01*
X36235Y593687D01*
X36542Y593532D01*
X36810Y593480D01*
G01X26574Y591861D02*
X56133D01*
G01X32092Y605011D02*
Y609611D01*
G01X42292Y605011D02*
X32092D01*
G01Y609611D02*
X42292D01*
G01X24592Y618411D02*
X27792D01*
G01X24592Y612211D02*
Y618411D01*
G01X27792Y612211D02*
X24592D01*
G01X27792Y618411D02*
Y612211D01*
G01X28592Y618411D02*
X31792D01*
G01X28592Y612211D02*
Y618411D01*
G01X31792Y612211D02*
X28592D01*
G01X31792Y618411D02*
Y612211D01*
G01X28592Y619711D02*
Y622911D01*
G01X34792Y619711D02*
X28592D01*
G01X34792Y622911D02*
Y619711D01*
G01X32392Y618411D02*
X35592D01*
G01X32392Y612211D02*
Y618411D01*
G01X35592Y612211D02*
X32392D01*
G01X35592Y618411D02*
Y612211D01*
G01X36299Y615754D02*
X38799D01*
X38299Y616074D01*
G01X36299D02*
Y615434D01*
G01Y613554D02*
X38799D01*
X38299Y613874D01*
G01X36299D02*
Y613234D01*
G01X28592Y622911D02*
X34792D01*
G01X38292Y634711D02*
X35092D01*
G01D02*
Y640911D01*
G01X34792Y630911D02*
Y627711D01*
G01X28592Y630911D02*
X34792D01*
G01X28592Y627711D02*
Y630911D01*
G01X34792Y627711D02*
X28592D01*
G01X34792Y626911D02*
Y623711D01*
G01X28592Y626911D02*
X34792D01*
G01X28592Y623711D02*
Y626911D01*
G01X34792Y623711D02*
X28592D01*
G01X36081Y626011D02*
X38581D01*
X38081Y626331D01*
G01X36081D02*
Y625691D01*
G01X38581Y623811D02*
X38498Y624024D01*
X38289Y624184D01*
X38039Y624291D01*
X37706Y624371D01*
X37331Y624398D01*
X36956Y624371D01*
X36623Y624291D01*
X36373Y624184D01*
X36164Y624024D01*
X36081Y623811D01*
X36164Y623598D01*
X36373Y623438D01*
X36623Y623331D01*
X36956Y623251D01*
X37331Y623224D01*
X37706Y623251D01*
X38039Y623331D01*
X38289Y623438D01*
X38498Y623598D01*
X38581Y623811D01*
G01X35092Y640911D02*
X38292D01*
G01X38924Y664294D02*
X26924D01*
G01D02*
Y670294D01*
G01D02*
X38924D01*
G01Y672765D02*
X26924D01*
G01Y678765D02*
X38924D01*
G01X26924Y672765D02*
Y678765D01*
G01X28957Y857677D02*
Y917913D01*
G01X78032Y857677D02*
X28957D01*
G01Y917913D02*
X127107D01*
G01X33203Y994519D02*
Y984319D01*
X28603D01*
Y994519D01*
X33203D01*
G01X38593D02*
Y984319D01*
X33993D01*
Y994519D01*
X38593D01*
G01X27762D02*
Y984319D01*
X23162D01*
Y994519D01*
X27762D01*
G01X29156Y1007221D02*
Y1001021D01*
X25956D01*
Y1007221D01*
X29156D01*
G01X35259D02*
Y1001021D01*
X32059D01*
Y1007221D01*
X35259D01*
G01X23106D02*
Y1001021D01*
X19906D01*
Y1007221D01*
X23106D01*
G01X30968Y1022029D02*
Y1035022D01*
G01X34999Y1021721D02*
X52701D01*
G01X34999Y1034052D02*
Y1021721D01*
G01X32260Y1046129D02*
Y1037229D01*
G01X33707D02*
Y1046129D01*
G01X53993Y1037229D02*
X33707D01*
G01X30968Y1048163D02*
Y1061329D01*
G01X34999Y1061021D02*
Y1048404D01*
G01X33707Y1046129D02*
X53993D01*
G01X32192Y1066629D02*
Y1097633D01*
G01X52701Y1061021D02*
X34999D01*
G01X33630Y1076772D02*
Y1079972D01*
G01X39830Y1076772D02*
X33630D01*
G01Y1079972D02*
X39830D01*
G01X30801Y1120333D02*
Y1124460D01*
X27801Y1127460D01*
G01X24580Y1189190D02*
Y1192290D01*
X25500D01*
X25807Y1192135D01*
X26037Y1191773D01*
X26114Y1191360D01*
X26037Y1190947D01*
X25845Y1190637D01*
X25500Y1190482D01*
X24580D01*
G01X27604Y1192290D02*
Y1190068D01*
X27757Y1189603D01*
X28064Y1189293D01*
X28447Y1189190D01*
X28830Y1189293D01*
X29137Y1189603D01*
X29290Y1190068D01*
Y1192290D01*
G01X31547Y1189190D02*
Y1192290D01*
X31087Y1191670D01*
G01Y1189190D02*
X32007D01*
G01X33919Y1190482D02*
X34187Y1190843D01*
X34417Y1191050D01*
X34724Y1191153D01*
X34992Y1191050D01*
X35184Y1190843D01*
X35337Y1190533D01*
X35375Y1190172D01*
X35337Y1189862D01*
X35184Y1189552D01*
X34954Y1189293D01*
X34685Y1189190D01*
X34379Y1189293D01*
X34110Y1189603D01*
X33957Y1190068D01*
X33919Y1190585D01*
X33995Y1191257D01*
X34110Y1191618D01*
X34302Y1191980D01*
X34570Y1192238D01*
X34839Y1192290D01*
X35107Y1192187D01*
X35299Y1191928D01*
G01X30727Y1197099D02*
X27527D01*
G01X30727Y1203299D02*
Y1197099D01*
G01X27527Y1203299D02*
X30727D01*
G01X27527Y1197099D02*
Y1203299D01*
G01X34187Y1194356D02*
X31687D01*
X32187Y1194036D01*
G01X34187D02*
Y1194676D01*
G01X33895Y1196103D02*
X34104Y1196289D01*
X34187Y1196503D01*
X34104Y1196716D01*
X33854Y1196903D01*
X33479Y1197036D01*
X33104Y1197089D01*
X32645D01*
X32270Y1197036D01*
X31937Y1196903D01*
X31770Y1196743D01*
X31687Y1196556D01*
X31770Y1196343D01*
X31937Y1196183D01*
X32187Y1196076D01*
X32520Y1196023D01*
X32812Y1196076D01*
X33104Y1196209D01*
X33270Y1196369D01*
X33312Y1196556D01*
X33229Y1196769D01*
X33020Y1196929D01*
X32645Y1197089D01*
G01X31476Y1205334D02*
X28976D01*
X29476Y1205014D01*
G01X31476D02*
Y1205654D01*
G01Y1207534D02*
X28976D01*
X29476Y1207214D01*
G01X31476D02*
Y1207854D01*
G01X32309Y1208934D02*
Y1210534D01*
G01X31476Y1211934D02*
X28976D01*
X29476Y1211614D01*
G01X31476D02*
Y1212254D01*
G01Y1214134D02*
X31434Y1214321D01*
X31309Y1214534D01*
X31101Y1214667D01*
X30809Y1214721D01*
X30518Y1214667D01*
X30268Y1214507D01*
X30143Y1214267D01*
Y1214001D01*
X30059Y1213841D01*
X29851Y1213707D01*
X29559Y1213654D01*
X29268Y1213734D01*
X29059Y1213921D01*
X28976Y1214134D01*
X29059Y1214347D01*
X29268Y1214534D01*
X29559Y1214614D01*
X29851Y1214561D01*
X30059Y1214427D01*
X30143Y1214267D01*
Y1214001D01*
X30268Y1213761D01*
X30518Y1213601D01*
X30809Y1213547D01*
X31101Y1213601D01*
X31309Y1213734D01*
X31434Y1213947D01*
X31476Y1214134D01*
G01X34141Y1198034D02*
Y1197763D01*
X37943D01*
G01X43910Y1217505D02*
X31910D01*
G01D02*
Y1223505D01*
G01X40243Y1213905D02*
X34141D01*
Y1213434D01*
G01X31910Y1223505D02*
X43910D01*
G01Y1231305D02*
X31910D01*
G01Y1237305D02*
X43910D01*
G01X31910Y1231305D02*
Y1237305D01*
G01X43910Y1224405D02*
X31910D01*
G01Y1230405D02*
X43910D01*
G01X31910Y1224405D02*
Y1230405D01*
G01X43910Y1238205D02*
X31910D01*
G01Y1244205D02*
X43910D01*
G01X31910Y1238205D02*
Y1244205D01*
G01X25622Y1437027D02*
Y1443227D01*
X28822D01*
Y1437027D01*
X25622D01*
G01X27274Y1493391D02*
Y1487191D01*
X24074D01*
Y1493391D01*
X27274D01*
G01X22166Y1503728D02*
Y1505835D01*
G01X24273Y1503728D02*
X22166D01*
G01Y1539554D02*
X24273D01*
G01X22166Y1537447D02*
Y1539554D01*
G01X37450Y1554830D02*
Y1548630D01*
X34250D01*
Y1554830D01*
X37450D01*
G01X27831Y1553259D02*
Y1547059D01*
X24631D01*
Y1553259D01*
X27831D01*
G01X23981Y1553277D02*
Y1547077D01*
X20781D01*
Y1553277D01*
X23981D01*
G01X30163Y1764596D02*
X27063D01*
Y1765516D01*
X27218Y1765823D01*
X27580Y1766053D01*
X27993Y1766130D01*
X28406Y1766053D01*
X28716Y1765861D01*
X28871Y1765516D01*
Y1764596D01*
G01X30266Y1767773D02*
X27063Y1769153D01*
G01X30163Y1770681D02*
X27063D01*
X30163Y1772445D01*
X27063D01*
G01X30266Y1774663D02*
X30215Y1774586D01*
X30111D01*
X30060Y1774663D01*
X30111Y1774740D01*
X30215D01*
X30266Y1774663D01*
G01X28871D02*
X28820Y1774586D01*
X28716D01*
X28665Y1774663D01*
X28716Y1774740D01*
X28820D01*
X28871Y1774663D01*
G01X30163Y1776920D02*
X27063D01*
Y1777686D01*
X27218Y1777993D01*
X27425Y1778223D01*
X27735Y1778415D01*
X28096Y1778568D01*
X28613Y1778606D01*
X29130Y1778568D01*
X29491Y1778415D01*
X29801Y1778223D01*
X30008Y1777993D01*
X30163Y1777686D01*
Y1776920D01*
G01Y1779905D02*
X27063Y1780863D01*
X30163Y1781821D01*
G01X29078Y1781476D02*
Y1780250D01*
G01X27063Y1783963D02*
X27166Y1783656D01*
X27425Y1783426D01*
X27735Y1783273D01*
X28148Y1783158D01*
X28613Y1783120D01*
X29078Y1783158D01*
X29491Y1783273D01*
X29801Y1783426D01*
X30060Y1783656D01*
X30163Y1783963D01*
X30060Y1784270D01*
X29801Y1784500D01*
X29491Y1784653D01*
X29078Y1784768D01*
X28613Y1784806D01*
X28148Y1784768D01*
X27735Y1784653D01*
X27425Y1784500D01*
X27166Y1784270D01*
X27063Y1783963D01*
G01X30163Y1786335D02*
X27063D01*
Y1787791D01*
G01X28561Y1787255D02*
Y1786335D01*
G01X27063Y1790163D02*
X27166Y1789856D01*
X27425Y1789626D01*
X27735Y1789473D01*
X28148Y1789358D01*
X28613Y1789320D01*
X29078Y1789358D01*
X29491Y1789473D01*
X29801Y1789626D01*
X30060Y1789856D01*
X30163Y1790163D01*
X30060Y1790470D01*
X29801Y1790700D01*
X29491Y1790853D01*
X29078Y1790968D01*
X28613Y1791006D01*
X28148Y1790968D01*
X27735Y1790853D01*
X27425Y1790700D01*
X27166Y1790470D01*
X27063Y1790163D01*
G01Y1793263D02*
X30163D01*
G01X27063Y1792381D02*
Y1794145D01*
G01X30163Y1797130D02*
Y1795596D01*
X27063D01*
Y1797130D01*
G01X28561Y1796516D02*
Y1795596D01*
G01X28510Y1799770D02*
X28355Y1799923D01*
X28096Y1800038D01*
X27735Y1800115D01*
X27425Y1800038D01*
X27218Y1799885D01*
X27063Y1799616D01*
Y1798581D01*
X30163D01*
Y1799846D01*
X29956Y1800115D01*
X29646Y1800268D01*
X29285Y1800345D01*
X28923Y1800268D01*
X28613Y1800038D01*
X28510Y1799770D01*
Y1798581D01*
G01X27063Y1802103D02*
Y1803023D01*
G01Y1802563D02*
X30163D01*
G01Y1802103D02*
Y1803023D01*
G01Y1804935D02*
X27063D01*
Y1806391D01*
G01X28561Y1805855D02*
Y1804935D01*
G01X27063Y1808763D02*
X27166Y1808456D01*
X27425Y1808226D01*
X27735Y1808073D01*
X28148Y1807958D01*
X28613Y1807920D01*
X29078Y1807958D01*
X29491Y1808073D01*
X29801Y1808226D01*
X30060Y1808456D01*
X30163Y1808763D01*
X30060Y1809070D01*
X29801Y1809300D01*
X29491Y1809453D01*
X29078Y1809568D01*
X28613Y1809606D01*
X28148Y1809568D01*
X27735Y1809453D01*
X27425Y1809300D01*
X27166Y1809070D01*
X27063Y1808763D01*
G01X38641Y57756D02*
Y111776D01*
G01X38937Y58150D02*
Y111776D01*
G01X45022Y57756D02*
X38641D01*
G01X44617Y58150D02*
X38937D01*
G01X38641Y118848D02*
Y114048D01*
G01X38937Y118848D02*
Y114048D01*
G01Y125781D02*
Y121219D01*
G01X38641Y125781D02*
Y121219D01*
G01Y132607D02*
Y128340D01*
G01X38937Y132607D02*
Y128340D01*
G01Y152756D02*
Y135584D01*
G01X38641Y153150D02*
Y135584D01*
G01X52095Y156615D02*
X52842Y155990D01*
X53682Y155615D01*
X54428D01*
X55175Y155990D01*
X55735Y156615D01*
X56015Y157490D01*
X55828Y158365D01*
X55362Y159115D01*
X54522Y159615D01*
X53402Y159865D01*
X52748Y160365D01*
X52468Y161240D01*
X52655Y162115D01*
X53122Y162740D01*
X53775Y163115D01*
X54428D01*
X55082Y162865D01*
X55642Y162240D01*
G01X59595Y156615D02*
X60342Y155990D01*
X61182Y155615D01*
X61928D01*
X62675Y155990D01*
X63235Y156615D01*
X63515Y157490D01*
X63328Y158365D01*
X62862Y159115D01*
X62022Y159615D01*
X60902Y159865D01*
X60248Y160365D01*
X59968Y161240D01*
X60155Y162115D01*
X60622Y162740D01*
X61275Y163115D01*
X61928D01*
X62582Y162865D01*
X63142Y162240D01*
G01X67002Y155615D02*
Y163115D01*
X68868D01*
X69615Y162740D01*
X70175Y162240D01*
X70642Y161490D01*
X71015Y160615D01*
X71108Y159365D01*
X71015Y158115D01*
X70642Y157240D01*
X70175Y156490D01*
X69615Y155990D01*
X68868Y155615D01*
X67002D01*
G01X76555Y163115D02*
X75808Y162865D01*
X75248Y162240D01*
X74875Y161490D01*
X74595Y160490D01*
X74502Y159365D01*
X74595Y158240D01*
X74875Y157240D01*
X75248Y156490D01*
X75808Y155865D01*
X76555Y155615D01*
X77302Y155865D01*
X77862Y156490D01*
X78235Y157240D01*
X78515Y158240D01*
X78608Y159365D01*
X78515Y160490D01*
X78235Y161490D01*
X77862Y162240D01*
X77302Y162865D01*
X76555Y163115D01*
G01X38707Y159500D02*
Y157278D01*
X38860Y156813D01*
X39167Y156503D01*
X39550Y156400D01*
X39933Y156503D01*
X40240Y156813D01*
X40393Y157278D01*
Y159500D01*
G01X41807Y157020D02*
X42037Y156658D01*
X42343Y156452D01*
X42688Y156400D01*
X42995Y156452D01*
X43302Y156710D01*
X43493Y157020D01*
X43532Y157330D01*
X43455Y157692D01*
X43187Y157950D01*
X42918Y158053D01*
X42573D01*
G01X42918D02*
X43148Y158208D01*
X43340Y158467D01*
X43417Y158777D01*
X43340Y159087D01*
X43148Y159345D01*
X42803Y159500D01*
X42458Y159448D01*
X42113Y159242D01*
G01X45022Y157692D02*
X45290Y158053D01*
X45520Y158260D01*
X45827Y158363D01*
X46095Y158260D01*
X46287Y158053D01*
X46440Y157743D01*
X46478Y157382D01*
X46440Y157072D01*
X46287Y156762D01*
X46057Y156503D01*
X45788Y156400D01*
X45482Y156503D01*
X45213Y156813D01*
X45060Y157278D01*
X45022Y157795D01*
X45098Y158467D01*
X45213Y158828D01*
X45405Y159190D01*
X45673Y159448D01*
X45942Y159500D01*
X46210Y159397D01*
X46402Y159138D01*
G01X48007Y157020D02*
X48237Y156658D01*
X48543Y156452D01*
X48888Y156400D01*
X49195Y156452D01*
X49502Y156710D01*
X49693Y157020D01*
X49732Y157330D01*
X49655Y157692D01*
X49387Y157950D01*
X49118Y158053D01*
X48773D01*
G01X49118D02*
X49348Y158208D01*
X49540Y158467D01*
X49617Y158777D01*
X49540Y159087D01*
X49348Y159345D01*
X49003Y159500D01*
X48658Y159448D01*
X48313Y159242D01*
G01X36077Y160665D02*
Y173343D01*
G01X51431Y160665D02*
X36077D01*
G01X51431Y173146D02*
Y160665D01*
G01X38641Y153150D02*
X45022D01*
G01X38937Y152756D02*
X44617D01*
G01X36440Y176006D02*
Y179206D01*
G01X42640Y176006D02*
X36440D01*
G01X42640Y179206D02*
Y176006D01*
G01X36440Y179206D02*
X42640D01*
G01X50001D02*
Y176006D01*
G01X43801Y179206D02*
X50001D01*
G01X43801Y176006D02*
Y179206D01*
G01X50001Y176006D02*
X43801D01*
G01X36077Y173343D02*
X51431D01*
G01X42368Y189535D02*
X39942D01*
G01X38828Y195583D02*
Y184087D01*
G01X52800Y215983D02*
X49700D01*
Y216903D01*
X49855Y217210D01*
X50217Y217440D01*
X50630Y217517D01*
X51043Y217440D01*
X51353Y217248D01*
X51508Y216903D01*
Y215983D01*
G01X52800Y219007D02*
X49700D01*
Y219773D01*
X49855Y220080D01*
X50062Y220310D01*
X50372Y220502D01*
X50733Y220655D01*
X51250Y220693D01*
X51767Y220655D01*
X52128Y220502D01*
X52438Y220310D01*
X52645Y220080D01*
X52800Y219773D01*
Y219007D01*
G01X50217Y222222D02*
X49907Y222452D01*
X49752Y222720D01*
X49700Y223027D01*
X49803Y223410D01*
X50062Y223678D01*
X50372Y223755D01*
X50682Y223717D01*
X50940Y223563D01*
X51457Y222797D01*
X51818Y222452D01*
X52335Y222222D01*
X52800Y222145D01*
Y223755D01*
G01X50217Y225322D02*
X49907Y225552D01*
X49752Y225820D01*
X49700Y226127D01*
X49803Y226510D01*
X50062Y226778D01*
X50372Y226855D01*
X50682Y226817D01*
X50940Y226663D01*
X51457Y225897D01*
X51818Y225552D01*
X52335Y225322D01*
X52800Y225245D01*
Y226855D01*
G01X39517Y214688D02*
X36417D01*
Y215608D01*
X36572Y215915D01*
X36934Y216145D01*
X37347Y216222D01*
X37760Y216145D01*
X38070Y215953D01*
X38225Y215608D01*
Y214688D01*
G01X36417Y217712D02*
X38639D01*
X39104Y217865D01*
X39414Y218172D01*
X39517Y218555D01*
X39414Y218938D01*
X39104Y219245D01*
X38639Y219398D01*
X36417D01*
G01X39052Y220812D02*
X39310Y221042D01*
X39465Y221310D01*
X39517Y221655D01*
X39414Y222000D01*
X39207Y222268D01*
X38845Y222460D01*
X38432Y222498D01*
X38019Y222422D01*
X37760Y222230D01*
X37554Y221962D01*
X37502Y221693D01*
X37554Y221425D01*
X37760Y221080D01*
X36417Y221195D01*
Y222230D01*
G01X39517Y225215D02*
X36417D01*
X38639Y223797D01*
Y225713D01*
G01X37801Y237659D02*
Y231459D01*
G01X52400Y270983D02*
X49300D01*
Y271903D01*
X49455Y272210D01*
X49817Y272440D01*
X50230Y272517D01*
X50643Y272440D01*
X50953Y272248D01*
X51108Y271903D01*
Y270983D01*
G01X52400Y274007D02*
X49300D01*
Y274773D01*
X49455Y275080D01*
X49662Y275310D01*
X49972Y275502D01*
X50333Y275655D01*
X50850Y275693D01*
X51367Y275655D01*
X51728Y275502D01*
X52038Y275310D01*
X52245Y275080D01*
X52400Y274773D01*
Y274007D01*
G01Y277950D02*
X52348Y278218D01*
X52193Y278525D01*
X51935Y278717D01*
X51573Y278793D01*
X51212Y278717D01*
X50902Y278487D01*
X50747Y278142D01*
Y277758D01*
X50643Y277528D01*
X50385Y277337D01*
X50023Y277260D01*
X49662Y277375D01*
X49403Y277643D01*
X49300Y277950D01*
X49403Y278257D01*
X49662Y278525D01*
X50023Y278640D01*
X50385Y278563D01*
X50643Y278372D01*
X50747Y278142D01*
Y277758D01*
X50902Y277413D01*
X51212Y277183D01*
X51573Y277107D01*
X51935Y277183D01*
X52193Y277375D01*
X52348Y277682D01*
X52400Y277950D01*
G01X51108Y280322D02*
X50747Y280590D01*
X50540Y280820D01*
X50437Y281127D01*
X50540Y281395D01*
X50747Y281587D01*
X51057Y281740D01*
X51418Y281778D01*
X51728Y281740D01*
X52038Y281587D01*
X52297Y281357D01*
X52400Y281088D01*
X52297Y280782D01*
X51987Y280513D01*
X51522Y280360D01*
X51005Y280322D01*
X50333Y280398D01*
X49972Y280513D01*
X49610Y280705D01*
X49352Y280973D01*
X49300Y281242D01*
X49403Y281510D01*
X49662Y281702D01*
G01X36370Y282872D02*
Y279672D01*
G01Y290872D02*
Y287672D01*
G01Y286872D02*
Y283672D01*
G01X39200Y453150D02*
X39148Y452843D01*
X38942Y452575D01*
X38632Y452345D01*
X38270Y452192D01*
X37857Y452115D01*
X37443D01*
X37030Y452192D01*
X36668Y452345D01*
X36358Y452575D01*
X36152Y452843D01*
X36100Y453150D01*
X36152Y453457D01*
X36358Y453725D01*
X36668Y453955D01*
X37030Y454108D01*
X37443Y454185D01*
X37857D01*
X38270Y454108D01*
X38632Y453955D01*
X38942Y453725D01*
X39148Y453457D01*
X39200Y453150D01*
G01X38373Y453457D02*
X39200Y453917D01*
G01X36617Y455522D02*
X36307Y455752D01*
X36152Y456020D01*
X36100Y456327D01*
X36203Y456710D01*
X36462Y456978D01*
X36772Y457055D01*
X37082Y457017D01*
X37340Y456863D01*
X37857Y456097D01*
X38218Y455752D01*
X38735Y455522D01*
X39200Y455445D01*
Y457055D01*
G01Y459350D02*
X36100D01*
X36720Y458890D01*
G01X39200D02*
Y459810D01*
G01X36617Y461722D02*
X36307Y461952D01*
X36152Y462220D01*
X36100Y462527D01*
X36203Y462910D01*
X36462Y463178D01*
X36772Y463255D01*
X37082Y463217D01*
X37340Y463063D01*
X37857Y462297D01*
X38218Y461952D01*
X38735Y461722D01*
X39200Y461645D01*
Y463255D01*
G01X50367Y455919D02*
Y452501D01*
G01X48643Y457919D02*
X50367Y455919D01*
G01Y459919D02*
X48643Y457919D01*
G01X40919Y452501D02*
Y463337D01*
G01X50367Y452501D02*
X40919D01*
G01X50243Y443819D02*
X47043D01*
G01X50243Y450019D02*
Y443819D01*
G01X47043Y450019D02*
X50243D01*
G01X47043Y443819D02*
Y450019D01*
G01X50367Y463337D02*
Y459919D01*
G01X40919Y463337D02*
X50367D01*
G01X43243Y465819D02*
X40043D01*
G01X43243Y472019D02*
Y465819D01*
G01X40043Y472019D02*
X43243D01*
G01X40043Y465819D02*
Y472019D01*
G01X44043D02*
X47243D01*
G01X44043Y465819D02*
Y472019D01*
G01X47243Y465819D02*
X44043D01*
G01X47243Y472019D02*
Y465819D01*
G01X48043Y472019D02*
X51243D01*
G01X48043Y465819D02*
Y472019D01*
G01X51243Y465819D02*
X48043D01*
G01X51243Y472019D02*
Y465819D01*
G01X42905Y480582D02*
Y477382D01*
G01X36705Y480582D02*
X42905D01*
G01X36705Y477382D02*
Y480582D01*
G01X42905Y477382D02*
X36705D01*
G01X42905Y485582D02*
Y482382D01*
G01X36705Y485582D02*
X42905D01*
G01X36705Y482382D02*
Y485582D01*
G01X42905Y482382D02*
X36705D01*
G01X42905Y493582D02*
Y490382D01*
G01X36705D02*
Y493582D01*
G01X42905Y490382D02*
X36705D01*
G01X42905Y486382D02*
X36705D01*
Y489582D01*
X42905D01*
Y486382D01*
G01X44145Y478081D02*
Y481181D01*
X45065D01*
X45372Y481026D01*
X45602Y480664D01*
X45679Y480251D01*
X45602Y479838D01*
X45410Y479528D01*
X45065Y479373D01*
X44145D01*
G01X47169Y481181D02*
Y478959D01*
X47322Y478494D01*
X47629Y478184D01*
X48012Y478081D01*
X48395Y478184D01*
X48702Y478494D01*
X48855Y478959D01*
Y481181D01*
G01X51572Y478081D02*
Y481181D01*
X50154Y478959D01*
X52070D01*
G01X53484Y479373D02*
X53752Y479734D01*
X53982Y479941D01*
X54289Y480044D01*
X54557Y479941D01*
X54749Y479734D01*
X54902Y479424D01*
X54940Y479063D01*
X54902Y478753D01*
X54749Y478443D01*
X54519Y478184D01*
X54250Y478081D01*
X53944Y478184D01*
X53675Y478494D01*
X53522Y478959D01*
X53484Y479476D01*
X53560Y480148D01*
X53675Y480509D01*
X53867Y480871D01*
X54135Y481129D01*
X54404Y481181D01*
X54672Y481078D01*
X54864Y480819D01*
G01X46408Y486594D02*
Y498798D01*
X61712D01*
Y486594D01*
X46408D01*
G01X42905Y501582D02*
Y498382D01*
G01X36705Y501582D02*
X42905D01*
G01X36705Y498382D02*
Y501582D01*
G01X42905Y498382D02*
X36705D01*
G01Y493582D02*
X42905D01*
G01X36705Y494382D02*
Y497582D01*
G01X42905Y494382D02*
X36705D01*
G01X42905Y497582D02*
Y494382D01*
G01X36705Y497582D02*
X42905D01*
G01X58893Y520969D02*
X46893D01*
G01D02*
Y526969D01*
G01D02*
X58893D01*
G01X48893Y527669D02*
Y530869D01*
G01X55093Y527669D02*
X48893D01*
G01Y530869D02*
X55093D01*
G01X36577Y533338D02*
Y545542D01*
X51881D01*
Y533338D01*
X36577D01*
G01X47459Y562194D02*
Y556194D01*
G01Y570194D02*
Y564194D01*
G01Y578194D02*
Y572194D01*
G01X42292Y604111D02*
Y599511D01*
G01X45199Y598993D02*
Y595793D01*
G01X38999Y598993D02*
X45199D01*
G01X38999Y595793D02*
Y598993D01*
G01X45199Y595793D02*
X38999D01*
G01X42292Y609611D02*
Y605011D01*
G01X46076Y610664D02*
Y608164D01*
X46396Y608664D01*
G01Y610664D02*
X45756D01*
G01X44383Y608581D02*
X44223Y608331D01*
X44036Y608206D01*
X43823Y608164D01*
X43556Y608247D01*
X43369Y608456D01*
X43316Y608706D01*
X43343Y608956D01*
X43449Y609164D01*
X43983Y609581D01*
X44223Y609872D01*
X44383Y610289D01*
X44436Y610664D01*
X43316D01*
G01X39153Y620279D02*
Y618343D01*
G01Y613209D02*
X40318D01*
G01X39153Y616343D02*
Y613209D01*
G01X47792Y634711D02*
X44592D01*
G01X47792Y640911D02*
Y634711D01*
G01X44592D02*
Y640911D01*
G01X43792Y634711D02*
X40592D01*
G01X43792Y640911D02*
Y634711D01*
G01X40592D02*
Y640911D01*
G01X51792Y634711D02*
X48592D01*
G01X51792Y640911D02*
Y634711D01*
G01X48592D02*
Y640911D01*
G01X51854Y632812D02*
Y629612D01*
G01X45654Y632812D02*
X51854D01*
G01X45654Y629612D02*
Y632812D01*
G01X51854Y629612D02*
X45654D01*
G01X38292Y640911D02*
Y634711D01*
G01X39445Y629352D02*
X39259Y629561D01*
X39045Y629644D01*
X38832Y629561D01*
X38645Y629311D01*
X38512Y628936D01*
X38459Y628561D01*
Y628102D01*
X38512Y627727D01*
X38645Y627394D01*
X38805Y627227D01*
X38992Y627144D01*
X39205Y627227D01*
X39365Y627394D01*
X39472Y627644D01*
X39525Y627977D01*
X39472Y628269D01*
X39339Y628561D01*
X39179Y628727D01*
X38992Y628769D01*
X38779Y628686D01*
X38619Y628477D01*
X38459Y628102D01*
G01X39153Y625413D02*
Y622279D01*
G01X40318Y625413D02*
X39153D01*
G01X44592Y640911D02*
X47792D01*
G01X40592D02*
X43792D01*
G01X48592D02*
X51792D01*
G01X38924Y670294D02*
Y664294D01*
G01X42783Y654000D02*
Y657100D01*
X43703D01*
X44010Y656945D01*
X44240Y656583D01*
X44317Y656170D01*
X44240Y655757D01*
X44048Y655447D01*
X43703Y655292D01*
X42783D01*
G01X45883Y657100D02*
Y654000D01*
X47417D01*
G01X49022Y656583D02*
X49252Y656893D01*
X49520Y657048D01*
X49827Y657100D01*
X50210Y656997D01*
X50478Y656738D01*
X50555Y656428D01*
X50517Y656118D01*
X50363Y655860D01*
X49597Y655343D01*
X49252Y654982D01*
X49022Y654465D01*
X48945Y654000D01*
X50555D01*
G01X42551Y658396D02*
Y664332D01*
G01X69323Y658396D02*
X42551D01*
G01X38924Y678765D02*
Y672765D01*
G01X42551Y685168D02*
X69323D01*
G01X42551Y679232D02*
Y685168D01*
G01X47924Y686873D02*
Y690073D01*
G01X54124Y686873D02*
X47924D01*
G01Y690073D02*
X54124D01*
G01X44972Y783720D02*
Y786820D01*
G01X46582D02*
Y783720D01*
G01Y785270D02*
X44972D01*
G01X48149Y785012D02*
X48417Y785373D01*
X48647Y785580D01*
X48954Y785683D01*
X49222Y785580D01*
X49414Y785373D01*
X49567Y785063D01*
X49605Y784702D01*
X49567Y784392D01*
X49414Y784082D01*
X49184Y783823D01*
X48915Y783720D01*
X48609Y783823D01*
X48340Y784133D01*
X48187Y784598D01*
X48149Y785115D01*
X48225Y785787D01*
X48340Y786148D01*
X48532Y786510D01*
X48800Y786768D01*
X49069Y786820D01*
X49337Y786717D01*
X49529Y786458D01*
G01X51900Y783720D02*
X51977Y784392D01*
X52092Y784960D01*
X52245Y785477D01*
X52437Y786045D01*
X52744Y786820D01*
X51210D01*
G01X51949Y824218D02*
X45949D01*
Y836218D01*
X51949D01*
Y824218D01*
G01X50689Y857677D02*
X78032D01*
G01X50689D02*
Y917913D01*
G01X49932Y868345D02*
X46832D01*
X47452Y867885D01*
G01X49932D02*
Y868805D01*
G01X48640Y870717D02*
X48279Y870985D01*
X48072Y871215D01*
X47969Y871522D01*
X48072Y871790D01*
X48279Y871982D01*
X48589Y872135D01*
X48950Y872173D01*
X49260Y872135D01*
X49570Y871982D01*
X49829Y871752D01*
X49932Y871483D01*
X49829Y871177D01*
X49519Y870908D01*
X49054Y870755D01*
X48537Y870717D01*
X47865Y870793D01*
X47504Y870908D01*
X47142Y871100D01*
X46884Y871368D01*
X46832Y871637D01*
X46935Y871905D01*
X47194Y872097D01*
G01X49470Y904693D02*
X49729Y904962D01*
X49832Y905268D01*
X49729Y905575D01*
X49419Y905843D01*
X48954Y906035D01*
X48489Y906112D01*
X47920D01*
X47455Y906035D01*
X47042Y905843D01*
X46835Y905613D01*
X46732Y905345D01*
X46835Y905038D01*
X47042Y904808D01*
X47352Y904655D01*
X47765Y904578D01*
X48127Y904655D01*
X48489Y904847D01*
X48695Y905077D01*
X48747Y905345D01*
X48644Y905652D01*
X48385Y905882D01*
X47920Y906112D01*
G01X50689Y917913D02*
X105375D01*
G01X53602Y968796D02*
X47602D01*
Y980796D01*
X53602D01*
Y968796D01*
G01X44092Y994519D02*
Y984319D01*
X39492D01*
Y994519D01*
X44092D01*
G01X49534D02*
Y984319D01*
X44934D01*
Y994519D01*
X49534D01*
G01X41149Y1007221D02*
Y1001021D01*
X37949D01*
Y1007221D01*
X41149D01*
G01X47458D02*
Y1001021D01*
X44258D01*
Y1007221D01*
X47458D01*
G01X53546D02*
Y1001021D01*
X50346D01*
Y1007221D01*
X53546D01*
G01X51204Y1069168D02*
Y1066946D01*
X51357Y1066481D01*
X51664Y1066171D01*
X52047Y1066068D01*
X52430Y1066171D01*
X52737Y1066481D01*
X52890Y1066946D01*
Y1069168D01*
G01X55147Y1066068D02*
X55415Y1066120D01*
X55722Y1066275D01*
X55914Y1066533D01*
X55990Y1066895D01*
X55914Y1067256D01*
X55684Y1067566D01*
X55339Y1067721D01*
X54955D01*
X54725Y1067825D01*
X54534Y1068083D01*
X54457Y1068445D01*
X54572Y1068806D01*
X54840Y1069065D01*
X55147Y1069168D01*
X55454Y1069065D01*
X55722Y1068806D01*
X55837Y1068445D01*
X55760Y1068083D01*
X55569Y1067825D01*
X55339Y1067721D01*
X54955D01*
X54610Y1067566D01*
X54380Y1067256D01*
X54304Y1066895D01*
X54380Y1066533D01*
X54572Y1066275D01*
X54879Y1066120D01*
X55147Y1066068D01*
G01X58170D02*
X58247Y1066740D01*
X58362Y1067308D01*
X58515Y1067825D01*
X58707Y1068393D01*
X59014Y1069168D01*
X57480D01*
G01X47723Y1074984D02*
X45461Y1072722D01*
G01X43339Y1079368D02*
X47723Y1074984D01*
G01X45461Y1072722D02*
X41077Y1077106D01*
G01X48624Y1074361D02*
X54824D01*
G01X48624Y1071161D02*
Y1074361D01*
G01X54824Y1071161D02*
X48624D01*
G01X46801Y1090572D02*
X48754D01*
G01X46801Y1088619D02*
Y1090572D01*
G01Y1078760D02*
Y1080713D01*
G01X48754Y1078760D02*
X46801D01*
G01X41077Y1077106D02*
X43339Y1079368D01*
G01X42300Y1085046D02*
X39100D01*
G01X42300Y1091246D02*
Y1085046D01*
G01X39100Y1091246D02*
X42300D01*
G01X39100Y1085046D02*
Y1091246D01*
G01X39830Y1079972D02*
Y1076772D01*
G01X45291Y1095357D02*
Y1092157D01*
G01X39091Y1095357D02*
X45291D01*
G01X39091Y1092157D02*
Y1095357D01*
G01X45291Y1092157D02*
X39091D01*
G01X41454Y1106400D02*
Y1102273D01*
X44454Y1099273D01*
G01D02*
X63108D01*
Y1106400D01*
G01X50063Y1123323D02*
Y1126523D01*
G01X56263Y1123323D02*
X50063D01*
G01X63108Y1113800D02*
Y1120927D01*
X44454D01*
X41454Y1117927D01*
Y1113800D01*
G01X50063Y1126523D02*
X56263D01*
G01X63349Y1132392D02*
X45755D01*
G01Y1186328D02*
X63349D01*
G01X40285Y1191663D02*
Y1194863D01*
G01X46485Y1191663D02*
X40285D01*
G01X46485Y1194863D02*
Y1191663D01*
G01X40285Y1194863D02*
X46485D01*
G01X47324Y1190650D02*
Y1193850D01*
G01X53524Y1190650D02*
X47324D01*
G01Y1193850D02*
X53524D01*
G01X42543Y1197763D02*
X46345D01*
Y1198034D01*
G01X39043Y1196134D02*
Y1193134D01*
G01X43910Y1223505D02*
Y1217505D01*
G01X45250Y1218988D02*
Y1224988D01*
G01X57250Y1218988D02*
X45250D01*
G01X54656Y1205264D02*
X51456D01*
G01Y1211464D02*
X54656D01*
G01X51456Y1205264D02*
Y1211464D01*
G01X49811Y1212109D02*
Y1215309D01*
G01X56011Y1212109D02*
X49811D01*
G01Y1215309D02*
X56011D01*
G01X48608Y1214747D02*
X48817Y1214933D01*
X48900Y1215147D01*
X48817Y1215360D01*
X48567Y1215547D01*
X48192Y1215680D01*
X47817Y1215733D01*
X47358D01*
X46983Y1215680D01*
X46650Y1215547D01*
X46483Y1215387D01*
X46400Y1215200D01*
X46483Y1214987D01*
X46650Y1214827D01*
X46900Y1214720D01*
X47233Y1214667D01*
X47525Y1214720D01*
X47817Y1214853D01*
X47983Y1215013D01*
X48025Y1215200D01*
X47942Y1215413D01*
X47733Y1215573D01*
X47358Y1215733D01*
G01X46345Y1213634D02*
Y1213905D01*
G01X48043Y1205834D02*
X49543D01*
G01X46345Y1213905D02*
X42543D01*
G01X41443Y1215534D02*
Y1218534D01*
G01X43910Y1237305D02*
Y1231305D01*
G01Y1230405D02*
Y1224405D01*
G01X45250Y1224988D02*
X57250D01*
G01X45250Y1231888D02*
X57250D01*
G01X45250Y1225888D02*
Y1231888D01*
G01X57250Y1225888D02*
X45250D01*
G01Y1232788D02*
Y1238788D01*
G01X57250Y1232788D02*
X45250D01*
G01X45125Y1240519D02*
Y1250519D01*
G01X49725D02*
Y1240519D01*
G01X49625Y1250519D02*
X49725D01*
G01X45125Y1240519D02*
X49725D01*
G01X45125Y1250519D02*
X49725D01*
G01X45250Y1238788D02*
X57250D01*
G01X43910Y1244205D02*
Y1238205D01*
G01X44127Y1250048D02*
Y1246848D01*
G01X37927Y1250048D02*
X44127D01*
G01X37927Y1246848D02*
Y1250048D01*
G01X44127Y1246848D02*
X37927D01*
G01X42551Y1554830D02*
Y1548630D01*
X39351D01*
Y1554830D01*
X42551D01*
G01X48674Y1554821D02*
Y1548621D01*
X45474D01*
Y1554821D01*
X48674D01*
G01X53648Y1554796D02*
Y1548596D01*
X50448D01*
Y1554796D01*
X53648D01*
G01X56603Y1744741D02*
X54993Y1741641D01*
G01X56603D02*
X54993Y1744741D01*
G01X53426Y1742158D02*
X53196Y1741848D01*
X52928Y1741693D01*
X52621Y1741641D01*
X52238Y1741744D01*
X51970Y1742003D01*
X51893Y1742313D01*
X51931Y1742623D01*
X52085Y1742881D01*
X52851Y1743398D01*
X53196Y1743759D01*
X53426Y1744276D01*
X53503Y1744741D01*
X51893D01*
G01X46248Y1745941D02*
X56248D01*
G01X46248Y1746491D02*
Y1745941D01*
G01Y1756491D02*
Y1755391D01*
G01X56248Y1765941D02*
X46248D01*
G01D02*
Y1765391D01*
G01X56603Y1790741D02*
X54993Y1787641D01*
G01X56603D02*
X54993Y1790741D01*
G01X53350Y1790379D02*
X53081Y1790638D01*
X52775Y1790741D01*
X52468Y1790638D01*
X52200Y1790328D01*
X52008Y1789863D01*
X51931Y1789398D01*
Y1788829D01*
X52008Y1788364D01*
X52200Y1787951D01*
X52430Y1787744D01*
X52698Y1787641D01*
X53005Y1787744D01*
X53235Y1787951D01*
X53388Y1788261D01*
X53465Y1788674D01*
X53388Y1789036D01*
X53196Y1789398D01*
X52966Y1789604D01*
X52698Y1789656D01*
X52391Y1789553D01*
X52161Y1789294D01*
X51931Y1788829D01*
G01X46248Y1802491D02*
Y1801391D01*
G01Y1792491D02*
Y1791941D01*
X56248D01*
G01Y1809441D02*
Y1811941D01*
X46248D01*
Y1811391D01*
G01X63149Y58150D02*
Y104619D01*
G01X63445Y57756D02*
Y104619D01*
G01Y57756D02*
X57064D01*
G01X63149Y58150D02*
X57469D01*
G01X70981Y86929D02*
X67781D01*
G01Y93129D02*
X70981D01*
G01X67781Y86929D02*
Y93129D01*
G01X63149Y111507D02*
Y107060D01*
G01X63445Y111507D02*
Y107060D01*
G01Y118680D02*
Y114087D01*
G01X63149Y118680D02*
Y114087D01*
G01Y125844D02*
Y121329D01*
G01X63445Y125844D02*
Y121329D01*
G01Y132859D02*
Y128325D01*
G01X63149Y132859D02*
Y128325D01*
G01Y152756D02*
Y135508D01*
G01X63445Y153150D02*
Y135508D01*
G01X55545Y164436D02*
X70345D01*
G01X55545Y195440D02*
Y164436D01*
G01X57064Y153150D02*
X63445D01*
G01X57469Y152756D02*
X63149D01*
G01X70345Y195440D02*
X55545D01*
G01X67658Y213035D02*
Y225035D01*
G01X73658Y213035D02*
X67658D01*
G01X59548Y199912D02*
Y202338D01*
G01X65596Y203452D02*
X54100D01*
G01X65596Y233011D02*
Y203452D01*
G01X54100D02*
Y233011D01*
G01X67658Y225035D02*
X73658D01*
G01X59448Y236652D02*
Y234412D01*
G01X61073Y235625D02*
X57823D01*
G01X54100Y233011D02*
X65596D01*
G01X66941Y250325D02*
Y234813D01*
G01D02*
X98033D01*
G01X59317Y259204D02*
Y261630D01*
G01X65365Y262744D02*
X53869D01*
G01X65365Y292303D02*
Y262744D01*
G01X53869D02*
Y292303D01*
G01X67120Y251936D02*
Y255036D01*
X68040D01*
X68347Y254881D01*
X68577Y254519D01*
X68654Y254106D01*
X68577Y253693D01*
X68385Y253383D01*
X68040Y253228D01*
X67120D01*
G01X70144Y251936D02*
Y255036D01*
X70910D01*
X71217Y254881D01*
X71447Y254674D01*
X71639Y254364D01*
X71792Y254003D01*
X71830Y253486D01*
X71792Y252969D01*
X71639Y252608D01*
X71447Y252298D01*
X71217Y252091D01*
X70910Y251936D01*
X70144D01*
G01X73359Y254519D02*
X73589Y254829D01*
X73857Y254984D01*
X74164Y255036D01*
X74547Y254933D01*
X74815Y254674D01*
X74892Y254364D01*
X74854Y254054D01*
X74700Y253796D01*
X73934Y253279D01*
X73589Y252918D01*
X73359Y252401D01*
X73282Y251936D01*
X74892D01*
G01X77187D02*
Y255036D01*
X76727Y254416D01*
G01Y251936D02*
X77647D01*
G01X98033Y250325D02*
X66941D01*
G01X67236Y271655D02*
Y283655D01*
G01X73236Y271655D02*
X67236D01*
G01Y283655D02*
X73236D01*
G01X64165Y295765D02*
Y293525D01*
G01X65790Y294738D02*
X62540D01*
G01X53869Y292303D02*
X65365D01*
G01X56783Y352853D02*
Y355953D01*
G01X58393D02*
Y352853D01*
G01Y354403D02*
X56783D01*
G01X61148Y352853D02*
Y355953D01*
X59730Y353731D01*
X61646D01*
G01X63711Y352853D02*
X63788Y353525D01*
X63903Y354093D01*
X64056Y354610D01*
X64248Y355178D01*
X64555Y355953D01*
X63021D01*
G01X64159Y438394D02*
Y444594D01*
G01X67359Y438394D02*
X64159D01*
G01X67359Y444594D02*
Y438394D01*
G01X60159D02*
Y444594D01*
G01X63359Y438394D02*
X60159D01*
G01X63359Y444594D02*
Y438394D01*
G01X56159D02*
Y444594D01*
G01X59359Y438394D02*
X56159D01*
G01X59359Y444594D02*
Y438394D01*
G01X55000Y437583D02*
X51900D01*
Y438503D01*
X52055Y438810D01*
X52417Y439040D01*
X52830Y439117D01*
X53243Y439040D01*
X53553Y438848D01*
X53708Y438503D01*
Y437583D01*
G01X51900Y440607D02*
X54122D01*
X54587Y440760D01*
X54897Y441067D01*
X55000Y441450D01*
X54897Y441833D01*
X54587Y442140D01*
X54122Y442293D01*
X51900D01*
G01X55000Y444550D02*
X54948Y444818D01*
X54793Y445125D01*
X54535Y445317D01*
X54173Y445393D01*
X53812Y445317D01*
X53502Y445087D01*
X53347Y444742D01*
Y444358D01*
X53243Y444128D01*
X52985Y443937D01*
X52623Y443860D01*
X52262Y443975D01*
X52003Y444243D01*
X51900Y444550D01*
X52003Y444857D01*
X52262Y445125D01*
X52623Y445240D01*
X52985Y445163D01*
X53243Y444972D01*
X53347Y444742D01*
Y444358D01*
X53502Y444013D01*
X53812Y443783D01*
X54173Y443707D01*
X54535Y443783D01*
X54793Y443975D01*
X54948Y444282D01*
X55000Y444550D01*
G01X51900Y447650D02*
X52003Y447343D01*
X52262Y447113D01*
X52572Y446960D01*
X52985Y446845D01*
X53450Y446807D01*
X53915Y446845D01*
X54328Y446960D01*
X54638Y447113D01*
X54897Y447343D01*
X55000Y447650D01*
X54897Y447957D01*
X54638Y448187D01*
X54328Y448340D01*
X53915Y448455D01*
X53450Y448493D01*
X52985Y448455D01*
X52572Y448340D01*
X52262Y448187D01*
X52003Y447957D01*
X51900Y447650D01*
G01X64159Y444594D02*
X67359D01*
G01X53336Y456438D02*
X56536D01*
G01X53336Y450238D02*
Y456438D01*
G01X56536Y450238D02*
X53336D01*
G01X56536Y456438D02*
Y450238D01*
G01X60159Y444594D02*
X63359D01*
G01X56159D02*
X59359D01*
G01X58273Y449607D02*
Y461381D01*
G01X68035Y449607D02*
X58273D01*
G01X68035Y461381D02*
Y449607D01*
G01X59824Y465959D02*
X56624D01*
G01X59824Y472159D02*
Y465959D01*
G01X56624Y472159D02*
X59824D01*
G01X56624Y465959D02*
Y472159D01*
G01X67824Y465959D02*
X64624D01*
G01X67824Y472159D02*
Y465959D01*
G01X64624Y472159D02*
X67824D01*
G01X64624Y465959D02*
Y472159D01*
G01X60624D02*
X63824D01*
G01X60624Y465959D02*
Y472159D01*
G01X63824Y465959D02*
X60624D01*
G01X63824Y472159D02*
Y465959D01*
G01X55243Y465819D02*
X52043D01*
G01X55243Y472019D02*
Y465819D01*
G01X52043Y472019D02*
X55243D01*
G01X52043Y465819D02*
Y472019D01*
G01X58273Y461381D02*
X68035D01*
G01X68703Y474988D02*
X56703D01*
G01Y480988D02*
X68703D01*
G01X56703Y474988D02*
Y480988D01*
G01X64745Y485564D02*
Y491764D01*
G01X67945Y485564D02*
X64745D01*
G01X67945Y491764D02*
Y485564D01*
G01X58703Y481788D02*
Y484988D01*
G01X64903Y481788D02*
X58703D01*
G01X64903Y484988D02*
Y481788D01*
G01X58703Y484988D02*
X64903D01*
G01X66450Y503265D02*
Y518777D01*
G01X64745Y491764D02*
X67945D01*
G01X58893Y526969D02*
Y520969D01*
G01X67795Y520579D02*
Y550138D01*
G01X79291Y520579D02*
X67795D01*
G01X65733Y540555D02*
Y528555D01*
G01X59733D02*
Y540555D01*
G01X65733Y528555D02*
X59733D01*
G01X55093Y530869D02*
Y527669D01*
G01X54914Y538508D02*
X58114D01*
G01X54914Y532308D02*
Y538508D01*
G01X58114Y532308D02*
X54914D01*
G01X58114Y538508D02*
Y532308D01*
G01X59733Y540555D02*
X65733D01*
G01X60909Y568248D02*
Y553448D01*
G01D02*
X91913D01*
G01X64506Y548058D02*
Y545632D01*
G01X67795Y550138D02*
X79291D01*
G01X91913Y568248D02*
X60909D01*
G01X67593Y581942D02*
Y583895D01*
G01X69546Y581942D02*
X67593D01*
G01X59673Y585813D02*
X57247D01*
G01X56133Y591861D02*
Y580365D01*
G01X62808Y580432D02*
X66008D01*
G01X62808Y574232D02*
Y580432D01*
G01X66008Y574232D02*
X62808D01*
G01X66008Y580432D02*
Y574232D01*
G01X67419Y577441D02*
X73619D01*
G01X67419Y574241D02*
Y577441D01*
G01X73619Y574241D02*
X67419D01*
G01X67593Y593754D02*
X69546D01*
G01X67593Y591801D02*
Y593754D01*
G01X69284Y598125D02*
X66084D01*
G01D02*
Y604325D01*
G01X62084Y598125D02*
Y604325D01*
G01X65284Y598125D02*
X62084D01*
G01X65284Y604325D02*
Y598125D01*
G01X67936Y609615D02*
X83448D01*
G01X67936Y640707D02*
Y609615D01*
G01X55592Y606711D02*
Y609911D01*
G01X61792Y606711D02*
X55592D01*
G01X61792Y609911D02*
Y606711D01*
G01X55592Y609911D02*
X61792D01*
G01X66084Y604325D02*
X69284D01*
G01X62084D02*
X65284D01*
G01X63456Y622659D02*
X63706Y622499D01*
X63831Y622312D01*
X63873Y622099D01*
X63790Y621832D01*
X63581Y621645D01*
X63331Y621592D01*
X63081Y621619D01*
X62873Y621725D01*
X62456Y622259D01*
X62165Y622499D01*
X61748Y622659D01*
X61373Y622712D01*
Y621592D01*
G01Y619952D02*
X63873D01*
X63373Y620272D01*
G01X61373D02*
Y619632D01*
G01X60540Y618552D02*
Y616952D01*
G01X63456Y616059D02*
X63706Y615899D01*
X63831Y615712D01*
X63873Y615499D01*
X63790Y615232D01*
X63581Y615045D01*
X63331Y614992D01*
X63081Y615019D01*
X62873Y615125D01*
X62456Y615659D01*
X62165Y615899D01*
X61748Y616059D01*
X61373Y616112D01*
Y614992D01*
G01X63456Y613859D02*
X63706Y613699D01*
X63831Y613512D01*
X63873Y613299D01*
X63790Y613032D01*
X63581Y612845D01*
X63331Y612792D01*
X63081Y612819D01*
X62873Y612925D01*
X62456Y613459D01*
X62165Y613699D01*
X61748Y613859D01*
X61373Y613912D01*
Y612792D01*
G01X66065Y609915D02*
X65905Y609665D01*
X65718Y609540D01*
X65505Y609498D01*
X65238Y609581D01*
X65051Y609790D01*
X64998Y610040D01*
X65025Y610290D01*
X65131Y610498D01*
X65665Y610915D01*
X65905Y611206D01*
X66065Y611623D01*
X66118Y611998D01*
X64998D01*
G01X63358Y609498D02*
X63571Y609581D01*
X63731Y609790D01*
X63838Y610040D01*
X63918Y610373D01*
X63945Y610748D01*
X63918Y611123D01*
X63838Y611456D01*
X63731Y611706D01*
X63571Y611915D01*
X63358Y611998D01*
X63145Y611915D01*
X62985Y611706D01*
X62878Y611456D01*
X62798Y611123D01*
X62771Y610748D01*
X62798Y610373D01*
X62878Y610040D01*
X62985Y609790D01*
X63145Y609581D01*
X63358Y609498D01*
G01X59231Y613209D02*
Y616350D01*
G01X58066Y613209D02*
X59231D01*
G01Y618361D02*
Y620261D01*
G01X55792Y634711D02*
X52592D01*
G01X55792Y640911D02*
Y634711D01*
G01X52592D02*
Y640911D01*
G01X59592Y634711D02*
Y640911D01*
G01X62792Y634711D02*
X59592D01*
G01X62792Y640911D02*
Y634711D01*
G01X65588Y623567D02*
X62388D01*
G01X65588Y629767D02*
Y623567D01*
G01X62388Y629767D02*
X65588D01*
G01X62388Y623567D02*
Y629767D01*
G01X56092Y634711D02*
Y640911D01*
G01X59292Y634711D02*
X56092D01*
G01X59292Y640911D02*
Y634711D01*
G01X63092D02*
Y640911D01*
G01X66292Y634711D02*
X63092D01*
G01X66292Y640911D02*
Y634711D01*
G01X55583Y630800D02*
Y633900D01*
X56503D01*
X56810Y633745D01*
X57040Y633383D01*
X57117Y632970D01*
X57040Y632557D01*
X56848Y632247D01*
X56503Y632092D01*
X55583D01*
G01X58607Y633900D02*
Y631678D01*
X58760Y631213D01*
X59067Y630903D01*
X59450Y630800D01*
X59833Y630903D01*
X60140Y631213D01*
X60293Y631678D01*
Y633900D01*
G01X62473Y630800D02*
X62550Y631472D01*
X62665Y632040D01*
X62818Y632557D01*
X63010Y633125D01*
X63317Y633900D01*
X61783D01*
G01X65650Y630800D02*
Y633900D01*
X65190Y633280D01*
G01Y630800D02*
X66110D01*
G01X59231Y625413D02*
X58058D01*
G01X59231Y622272D02*
Y625413D01*
G01X83448Y640707D02*
X67936D01*
G01X52592Y640911D02*
X55792D01*
G01X59592D02*
X62792D01*
G01X56092D02*
X59292D01*
G01X63092D02*
X66292D01*
G01X54124Y690073D02*
Y686873D01*
G01X60649Y819618D02*
Y825618D01*
X72649D01*
Y819618D01*
X60649D01*
G01X57749Y825908D02*
Y819708D01*
X54549D01*
Y825908D01*
X57749D01*
G01X56545Y827610D02*
X68553D01*
G01X65949D02*
X68553D01*
G01X56545Y828414D02*
Y827610D01*
X58849D01*
G01X54649Y844718D02*
X60849D01*
Y841518D01*
X54649D01*
Y844718D01*
G01X60849Y846118D02*
X54649D01*
Y849318D01*
X60849D01*
Y846118D01*
G01X73335Y841518D02*
X67135D01*
Y844718D01*
X73335D01*
Y841518D01*
G01X56545Y839618D02*
X68553D01*
G01X58649D02*
X56545D01*
Y838814D01*
G01X68553D02*
Y839618D01*
X66049D01*
G01X62776Y867145D02*
X70067D01*
G01X62776Y908445D02*
Y867145D01*
G01X92658Y908445D02*
X62776D01*
G01X64555Y968796D02*
X58555D01*
Y980796D01*
X64555D01*
Y968796D01*
G01X60909Y982676D02*
X54909D01*
Y994676D01*
X60909D01*
Y982676D01*
G01X71342Y982514D02*
X65342D01*
Y994514D01*
X71342D01*
Y982514D01*
G01X67374Y1007221D02*
Y1001021D01*
X64174D01*
Y1007221D01*
X67374D01*
G01X63379D02*
Y1001021D01*
X60179D01*
Y1007221D01*
X63379D01*
G01X59434D02*
Y1001021D01*
X56234D01*
Y1007221D01*
X59434D01*
G01X52701Y1021721D02*
Y1034311D01*
G01X53993Y1046129D02*
Y1037229D01*
G01X52701Y1048360D02*
Y1061021D01*
G01X62984Y1070056D02*
Y1073256D01*
G01X69184Y1070056D02*
X62984D01*
G01Y1073256D02*
X69184D01*
G01X62984Y1074056D02*
Y1077256D01*
G01X69184Y1074056D02*
X62984D01*
G01Y1066056D02*
Y1069256D01*
G01X69184Y1066056D02*
X62984D01*
G01Y1069256D02*
X69184D01*
G01X54824Y1074361D02*
Y1071161D01*
G01X58613Y1090572D02*
Y1088619D01*
G01X56660Y1090572D02*
X58613D01*
G01Y1080713D02*
Y1078760D01*
G01D02*
X56660D01*
G01X62984Y1077256D02*
X69184D01*
G01X62984Y1082056D02*
Y1085256D01*
G01X69184Y1082056D02*
X62984D01*
G01Y1085256D02*
X69184D01*
G01X62984Y1086056D02*
Y1089256D01*
G01X69184Y1086056D02*
X62984D01*
G01Y1089256D02*
X69184D01*
G01X62984Y1078056D02*
Y1081256D01*
G01X69184Y1078056D02*
X62984D01*
G01Y1081256D02*
X69184D01*
G01X62984Y1090056D02*
Y1093256D01*
G01X69184Y1090056D02*
X62984D01*
G01Y1093256D02*
X69184D01*
G01X56263Y1126523D02*
Y1123323D01*
G01X63349Y1186328D02*
Y1132392D01*
G01X67981Y1166331D02*
X64881D01*
Y1167251D01*
X65036Y1167558D01*
X65398Y1167788D01*
X65811Y1167865D01*
X66224Y1167788D01*
X66534Y1167596D01*
X66689Y1167251D01*
Y1166331D01*
G01X64881Y1169431D02*
X67981D01*
Y1170965D01*
G01Y1173298D02*
X64881D01*
X65501Y1172838D01*
G01X67981D02*
Y1173758D01*
G01Y1176398D02*
X67929Y1176666D01*
X67774Y1176973D01*
X67516Y1177165D01*
X67154Y1177241D01*
X66793Y1177165D01*
X66483Y1176935D01*
X66328Y1176590D01*
Y1176206D01*
X66224Y1175976D01*
X65966Y1175785D01*
X65604Y1175708D01*
X65243Y1175823D01*
X64984Y1176091D01*
X64881Y1176398D01*
X64984Y1176705D01*
X65243Y1176973D01*
X65604Y1177088D01*
X65966Y1177011D01*
X66224Y1176820D01*
X66328Y1176590D01*
Y1176206D01*
X66483Y1175861D01*
X66793Y1175631D01*
X67154Y1175555D01*
X67516Y1175631D01*
X67774Y1175823D01*
X67929Y1176130D01*
X67981Y1176398D01*
G01X56102Y1200345D02*
X59302D01*
G01X56102Y1194145D02*
Y1200345D01*
G01X59302Y1194145D02*
X56102D01*
G01X59302Y1200345D02*
Y1194145D01*
G01X59153Y1201135D02*
X55953D01*
G01X59153Y1207335D02*
Y1201135D01*
G01X55953D02*
Y1207335D01*
G01X59780Y1200871D02*
Y1207071D01*
G01X62980Y1200871D02*
X59780D01*
G01X62980Y1207071D02*
Y1200871D01*
G01X53524Y1193850D02*
Y1190650D01*
G01X52137Y1201505D02*
X55337D01*
G01X52137Y1195305D02*
Y1201505D01*
G01X55337Y1195305D02*
X52137D01*
G01X55337Y1201505D02*
Y1195305D01*
G01X57250Y1224988D02*
Y1218988D01*
G01X55953Y1207335D02*
X59153D01*
G01X59780Y1207071D02*
X62980D01*
G01X56685Y1208120D02*
Y1211320D01*
G01X62885Y1208120D02*
X56685D01*
G01X62885Y1211320D02*
Y1208120D01*
G01X56685Y1211320D02*
X62885D01*
G01Y1215320D02*
Y1212120D01*
G01X56685Y1215320D02*
X62885D01*
G01X56685Y1212120D02*
Y1215320D01*
G01X62885Y1212120D02*
X56685D01*
G01X54656Y1211464D02*
Y1205264D01*
G01X56011Y1215309D02*
Y1212109D01*
G01X57250Y1231888D02*
Y1225888D01*
G01Y1238788D02*
Y1232788D01*
G01X56341Y1242106D02*
X53241D01*
Y1243026D01*
X53396Y1243333D01*
X53758Y1243563D01*
X54171Y1243640D01*
X54584Y1243563D01*
X54894Y1243371D01*
X55049Y1243026D01*
Y1242106D01*
G01X53241Y1245206D02*
X56341D01*
Y1246740D01*
G01Y1249073D02*
X53241D01*
X53861Y1248613D01*
G01X56341D02*
Y1249533D01*
G01Y1252096D02*
X55669Y1252173D01*
X55101Y1252288D01*
X54584Y1252441D01*
X54016Y1252633D01*
X53241Y1252940D01*
Y1251406D01*
G01X55951Y1483816D02*
Y1479283D01*
X52751D01*
Y1484172D01*
G01X52739Y1487913D02*
Y1492572D01*
X55939D01*
Y1488059D01*
G01X65634Y1515502D02*
Y1513280D01*
X65787Y1512815D01*
X66094Y1512505D01*
X66477Y1512402D01*
X66860Y1512505D01*
X67167Y1512815D01*
X67320Y1513280D01*
Y1515502D01*
G01X70037Y1512402D02*
Y1515502D01*
X68619Y1513280D01*
X70535D01*
G01X73137Y1512402D02*
Y1515502D01*
X71719Y1513280D01*
X73635D01*
G01X75049Y1514985D02*
X75279Y1515295D01*
X75547Y1515450D01*
X75854Y1515502D01*
X76237Y1515399D01*
X76505Y1515140D01*
X76582Y1514830D01*
X76544Y1514520D01*
X76390Y1514262D01*
X75624Y1513745D01*
X75279Y1513384D01*
X75049Y1512867D01*
X74972Y1512402D01*
X76582D01*
G01X57992Y1505835D02*
Y1503728D01*
G01D02*
X55885D01*
G01X67003Y1542971D02*
X60803D01*
Y1546171D01*
X67003D01*
Y1542971D01*
G01X55885Y1539554D02*
X57992D01*
G01D02*
Y1537447D01*
G01X57714Y1554795D02*
Y1548595D01*
X54514D01*
Y1554795D01*
X57714D01*
G01X66347Y1554788D02*
Y1548588D01*
X63147D01*
Y1554788D01*
X66347D01*
G01X58413Y1548595D02*
Y1554795D01*
X61613D01*
Y1548595D01*
X58413D01*
G01X61922Y1594195D02*
X64144D01*
X64609Y1594348D01*
X64919Y1594655D01*
X65022Y1595038D01*
X64919Y1595421D01*
X64609Y1595728D01*
X64144Y1595881D01*
X61922D01*
G01X64402Y1597295D02*
X64764Y1597525D01*
X64970Y1597831D01*
X65022Y1598176D01*
X64970Y1598483D01*
X64712Y1598790D01*
X64402Y1598981D01*
X64092Y1599020D01*
X63730Y1598943D01*
X63472Y1598675D01*
X63369Y1598406D01*
Y1598061D01*
G01Y1598406D02*
X63214Y1598636D01*
X62955Y1598828D01*
X62645Y1598905D01*
X62335Y1598828D01*
X62077Y1598636D01*
X61922Y1598291D01*
X61974Y1597946D01*
X62180Y1597601D01*
G01X62439Y1600510D02*
X62129Y1600740D01*
X61974Y1601008D01*
X61922Y1601315D01*
X62025Y1601698D01*
X62284Y1601966D01*
X62594Y1602043D01*
X62904Y1602005D01*
X63162Y1601851D01*
X63679Y1601085D01*
X64040Y1600740D01*
X64557Y1600510D01*
X65022Y1600433D01*
Y1602043D01*
G01Y1604338D02*
X64970Y1604606D01*
X64815Y1604913D01*
X64557Y1605105D01*
X64195Y1605181D01*
X63834Y1605105D01*
X63524Y1604875D01*
X63369Y1604530D01*
Y1604146D01*
X63265Y1603916D01*
X63007Y1603725D01*
X62645Y1603648D01*
X62284Y1603763D01*
X62025Y1604031D01*
X61922Y1604338D01*
X62025Y1604645D01*
X62284Y1604913D01*
X62645Y1605028D01*
X63007Y1604951D01*
X63265Y1604760D01*
X63369Y1604530D01*
Y1604146D01*
X63524Y1603801D01*
X63834Y1603571D01*
X64195Y1603495D01*
X64557Y1603571D01*
X64815Y1603763D01*
X64970Y1604070D01*
X65022Y1604338D01*
G01X66346Y1594714D02*
X86032D01*
G01X66346Y1602445D02*
Y1594714D01*
G01X61490Y1610477D02*
Y1616677D01*
G01X64690Y1610477D02*
X61490D01*
G01X64690Y1616677D02*
Y1610477D01*
G01X72189Y1608288D02*
X66346Y1602445D01*
G01X61490Y1616677D02*
X64690D01*
G01X67891Y1626702D02*
X64691D01*
G01X67891Y1632902D02*
Y1626702D01*
G01X64691D02*
Y1632902D01*
G01X66346Y1614131D02*
X72189Y1608288D01*
G01X66346Y1621862D02*
Y1614131D01*
G01X86032Y1621862D02*
X66346D01*
G01X64691Y1632902D02*
X67891D01*
G01X56248Y1745941D02*
Y1748441D01*
G01Y1753441D02*
Y1758441D01*
G01Y1763441D02*
Y1765941D01*
G01Y1799441D02*
Y1804441D01*
G01Y1791941D02*
Y1794441D01*
G01X74680Y-94413D02*
X71580D01*
Y-93493D01*
X71735Y-93186D01*
X72097Y-92956D01*
X72510Y-92879D01*
X72923Y-92956D01*
X73233Y-93148D01*
X73388Y-93493D01*
Y-94413D01*
G01X74783Y-91236D02*
X71580Y-89856D01*
G01X74680Y-88328D02*
X71580D01*
X74680Y-86564D01*
X71580D01*
G01X74783Y-84346D02*
X74732Y-84423D01*
X74628D01*
X74577Y-84346D01*
X74628Y-84269D01*
X74732D01*
X74783Y-84346D01*
G01X73388D02*
X73337Y-84423D01*
X73233D01*
X73182Y-84346D01*
X73233Y-84269D01*
X73337D01*
X73388Y-84346D01*
G01X74680Y-82089D02*
X71580D01*
Y-81323D01*
X71735Y-81016D01*
X71942Y-80786D01*
X72252Y-80594D01*
X72613Y-80441D01*
X73130Y-80403D01*
X73647Y-80441D01*
X74008Y-80594D01*
X74318Y-80786D01*
X74525Y-81016D01*
X74680Y-81323D01*
Y-82089D01*
G01Y-79104D02*
X71580Y-78146D01*
X74680Y-77188D01*
G01X73595Y-77533D02*
Y-78759D01*
G01X71580Y-75046D02*
X71683Y-75353D01*
X71942Y-75583D01*
X72252Y-75736D01*
X72665Y-75851D01*
X73130Y-75889D01*
X73595Y-75851D01*
X74008Y-75736D01*
X74318Y-75583D01*
X74577Y-75353D01*
X74680Y-75046D01*
X74577Y-74739D01*
X74318Y-74509D01*
X74008Y-74356D01*
X73595Y-74241D01*
X73130Y-74203D01*
X72665Y-74241D01*
X72252Y-74356D01*
X71942Y-74509D01*
X71683Y-74739D01*
X71580Y-75046D01*
G01X74680Y-72674D02*
X71580D01*
Y-71218D01*
G01X73078Y-71754D02*
Y-72674D01*
G01X71580Y-68846D02*
X71683Y-69153D01*
X71942Y-69383D01*
X72252Y-69536D01*
X72665Y-69651D01*
X73130Y-69689D01*
X73595Y-69651D01*
X74008Y-69536D01*
X74318Y-69383D01*
X74577Y-69153D01*
X74680Y-68846D01*
X74577Y-68539D01*
X74318Y-68309D01*
X74008Y-68156D01*
X73595Y-68041D01*
X73130Y-68003D01*
X72665Y-68041D01*
X72252Y-68156D01*
X71942Y-68309D01*
X71683Y-68539D01*
X71580Y-68846D01*
G01Y-65746D02*
X74680D01*
G01X71580Y-66628D02*
Y-64864D01*
G01X74680Y-61879D02*
Y-63413D01*
X71580D01*
Y-61879D01*
G01X73078Y-62493D02*
Y-63413D01*
G01X73027Y-59239D02*
X72872Y-59086D01*
X72613Y-58971D01*
X72252Y-58894D01*
X71942Y-58971D01*
X71735Y-59124D01*
X71580Y-59393D01*
Y-60428D01*
X74680D01*
Y-59163D01*
X74473Y-58894D01*
X74163Y-58741D01*
X73802Y-58664D01*
X73440Y-58741D01*
X73130Y-58971D01*
X73027Y-59239D01*
Y-60428D01*
G01X71580Y-56906D02*
Y-55986D01*
G01Y-56446D02*
X74680D01*
G01Y-56906D02*
Y-55986D01*
G01Y-54074D02*
X71580D01*
Y-52618D01*
G01X73078Y-53154D02*
Y-54074D01*
G01X71580Y-50246D02*
X71683Y-50553D01*
X71942Y-50783D01*
X72252Y-50936D01*
X72665Y-51051D01*
X73130Y-51089D01*
X73595Y-51051D01*
X74008Y-50936D01*
X74318Y-50783D01*
X74577Y-50553D01*
X74680Y-50246D01*
X74577Y-49939D01*
X74318Y-49709D01*
X74008Y-49556D01*
X73595Y-49441D01*
X73130Y-49403D01*
X72665Y-49441D01*
X72252Y-49556D01*
X71942Y-49709D01*
X71683Y-49939D01*
X71580Y-50246D01*
G01X74981Y86929D02*
X71781D01*
G01X74981Y93129D02*
Y86929D01*
G01X71781Y93129D02*
X74981D01*
G01X71781Y86929D02*
Y93129D01*
G01X70981D02*
Y86929D01*
G01X68977Y97026D02*
Y103226D01*
G01X72177Y97026D02*
X68977D01*
G01X72177Y103226D02*
Y97026D01*
G01X83208Y98928D02*
Y105128D01*
G01X86408Y98928D02*
X83208D01*
G01X79060Y96673D02*
Y102873D01*
G01X82260Y96673D02*
X79060D01*
G01X82260Y102873D02*
Y96673D01*
G01X75060D02*
Y102873D01*
G01X78260Y96673D02*
X75060D01*
G01X78260Y102873D02*
Y96673D01*
G01X68977Y103226D02*
X72177D01*
G01X83208Y105128D02*
X86408D01*
G01X79060Y102873D02*
X82260D01*
G01X75060D02*
X78260D01*
G01X81043Y144690D02*
Y154138D01*
G01X91879Y144690D02*
X81043D01*
G01X83624Y139647D02*
Y142847D01*
G01X89824Y139647D02*
X83624D01*
G01Y142847D02*
X89824D01*
G01X76645Y139647D02*
Y142847D01*
G01X82845Y139647D02*
X76645D01*
G01X82845Y142847D02*
Y139647D01*
G01X76645Y142847D02*
X82845D01*
G01X72675Y145940D02*
Y149140D01*
G01X78875Y145940D02*
X72675D01*
G01X78875Y149140D02*
Y145940D01*
G01X72675Y149140D02*
X78875D01*
G01X70345Y164436D02*
Y195440D01*
G01X82051Y156808D02*
X81744Y156860D01*
X81476Y157066D01*
X81246Y157376D01*
X81093Y157738D01*
X81016Y158151D01*
Y158565D01*
X81093Y158978D01*
X81246Y159340D01*
X81476Y159650D01*
X81744Y159856D01*
X82051Y159908D01*
X82358Y159856D01*
X82626Y159650D01*
X82856Y159340D01*
X83009Y158978D01*
X83086Y158565D01*
Y158151D01*
X83009Y157738D01*
X82856Y157376D01*
X82626Y157066D01*
X82358Y156860D01*
X82051Y156808D01*
G01X82358Y157635D02*
X82818Y156808D01*
G01X85151D02*
Y159908D01*
X84691Y159288D01*
G01Y156808D02*
X85611D01*
G01X87408Y157428D02*
X87638Y157066D01*
X87944Y156860D01*
X88289Y156808D01*
X88596Y156860D01*
X88903Y157118D01*
X89094Y157428D01*
X89133Y157738D01*
X89056Y158100D01*
X88788Y158358D01*
X88519Y158461D01*
X88174D01*
G01X88519D02*
X88749Y158616D01*
X88941Y158875D01*
X89018Y159185D01*
X88941Y159495D01*
X88749Y159753D01*
X88404Y159908D01*
X88059Y159856D01*
X87714Y159650D01*
G01X91811Y156808D02*
Y159908D01*
X90393Y157686D01*
X92309D01*
G01X84461Y154138D02*
X86461Y152414D01*
G01X81043Y154138D02*
X84461D01*
G01X78875Y153140D02*
Y149940D01*
G01X72675Y153140D02*
X78875D01*
G01X72675Y149940D02*
Y153140D01*
G01X78875Y149940D02*
X72675D01*
G01X84039Y176944D02*
Y178897D01*
G01X85992Y176944D02*
X84039D01*
G01X79311Y171473D02*
X76111D01*
G01X79311Y177673D02*
Y171473D01*
G01X76111Y177673D02*
X79311D01*
G01X76111Y171473D02*
Y177673D01*
G01X82334Y170297D02*
Y167097D01*
G01X76134Y170297D02*
X82334D01*
G01X76134Y167097D02*
Y170297D01*
G01X82334Y167097D02*
X76134D01*
G01X75311Y171473D02*
X72111D01*
G01X75311Y177673D02*
Y171473D01*
G01X72111Y177673D02*
X75311D01*
G01X72111Y171473D02*
Y177673D01*
G01X84039Y188756D02*
X85992D01*
G01X84039Y186803D02*
Y188756D01*
G01X79538Y182730D02*
X76338D01*
G01X79538Y188930D02*
Y182730D01*
G01X76338Y188930D02*
X79538D01*
G01X76338Y182730D02*
Y188930D01*
G01X82529Y193541D02*
Y190341D01*
G01X76329Y193541D02*
X82529D01*
G01X76329Y190341D02*
Y193541D01*
G01X82529Y190341D02*
X76329D01*
G01X73658Y225035D02*
Y213035D01*
G01X82967Y200607D02*
Y203707D01*
X83887D01*
X84194Y203552D01*
X84424Y203190D01*
X84501Y202777D01*
X84424Y202364D01*
X84232Y202054D01*
X83887Y201899D01*
X82967D01*
G01X85991Y203707D02*
Y201485D01*
X86144Y201020D01*
X86451Y200710D01*
X86834Y200607D01*
X87217Y200710D01*
X87524Y201020D01*
X87677Y201485D01*
Y203707D01*
G01X89091Y201227D02*
X89321Y200865D01*
X89627Y200659D01*
X89972Y200607D01*
X90279Y200659D01*
X90586Y200917D01*
X90777Y201227D01*
X90816Y201537D01*
X90739Y201899D01*
X90471Y202157D01*
X90202Y202260D01*
X89857D01*
G01X90202D02*
X90432Y202415D01*
X90624Y202674D01*
X90701Y202984D01*
X90624Y203294D01*
X90432Y203552D01*
X90087Y203707D01*
X89742Y203655D01*
X89397Y203449D01*
G01X93034Y203707D02*
X92727Y203604D01*
X92497Y203345D01*
X92344Y203035D01*
X92229Y202622D01*
X92191Y202157D01*
X92229Y201692D01*
X92344Y201279D01*
X92497Y200969D01*
X92727Y200710D01*
X93034Y200607D01*
X93341Y200710D01*
X93571Y200969D01*
X93724Y201279D01*
X93839Y201692D01*
X93877Y202157D01*
X93839Y202622D01*
X93724Y203035D01*
X93571Y203345D01*
X93341Y203604D01*
X93034Y203707D01*
G01X96814Y220252D02*
Y208048D01*
X81510D01*
Y220252D01*
X96814D01*
G01X74498Y226621D02*
Y232621D01*
G01X86498Y226621D02*
X74498D01*
G01X78477Y215082D02*
X75277D01*
G01X78477Y221282D02*
Y215082D01*
G01X75277Y221282D02*
X78477D01*
G01X75277Y215082D02*
Y221282D01*
G01X78298Y225921D02*
X84498D01*
G01X78298Y222721D02*
Y225921D01*
G01X84498Y222721D02*
X78298D01*
G01X74498Y232621D02*
X86498D01*
G01X75166Y258010D02*
Y264210D01*
G01X78366Y258010D02*
X75166D01*
G01X78366Y264210D02*
Y258010D01*
G01X83166D02*
Y264210D01*
G01X86366Y258010D02*
X83166D01*
G01X82366D02*
X79166D01*
G01X82366Y264210D02*
Y258010D01*
G01X79166D02*
Y264210D01*
G01X73236Y283655D02*
Y271655D01*
G01X75166Y264210D02*
X78366D01*
G01X83166D02*
X86366D01*
G01X79166D02*
X82366D01*
G01X76125Y267653D02*
Y279427D01*
G01X85887Y267653D02*
X76125D01*
G01X77419Y283383D02*
X74219D01*
G01X77419Y289583D02*
Y283383D01*
G01X74219Y289583D02*
X77419D01*
G01X74219Y283383D02*
Y289583D01*
G01X81419Y283383D02*
X78219D01*
G01X81419Y289583D02*
Y283383D01*
G01X78219Y289583D02*
X81419D01*
G01X78219Y283383D02*
Y289583D01*
G01X82219Y283383D02*
Y289583D01*
X85419D01*
Y283383D01*
X82219D01*
G01X76125Y279427D02*
X85887D01*
G01X75643Y458419D02*
Y446419D01*
G01X69643D02*
Y458419D01*
G01X75643Y446419D02*
X69643D01*
G01Y458419D02*
X75643D01*
G01X83774Y471194D02*
Y473434D01*
G01X82149Y472221D02*
X85399D01*
G01X77626Y474835D02*
Y504394D01*
G01X89122Y474835D02*
X77626D01*
G01X75564Y493811D02*
Y481811D01*
G01X69564D02*
Y493811D01*
G01X75564Y481811D02*
X69564D01*
G01X68703Y480988D02*
Y474988D01*
G01X83674Y507934D02*
Y505508D01*
G01X77626Y504394D02*
X89122D01*
G01X69564Y493811D02*
X75564D01*
G01X73943Y516938D02*
Y519178D01*
G01X72318Y517965D02*
X75568D01*
G01X79291Y550138D02*
Y520579D01*
G01X84400Y526983D02*
X81300D01*
Y527903D01*
X81455Y528210D01*
X81817Y528440D01*
X82230Y528517D01*
X82643Y528440D01*
X82953Y528248D01*
X83108Y527903D01*
Y526983D01*
G01X84400Y530007D02*
X81300D01*
Y530773D01*
X81455Y531080D01*
X81662Y531310D01*
X81972Y531502D01*
X82333Y531655D01*
X82850Y531693D01*
X83367Y531655D01*
X83728Y531502D01*
X84038Y531310D01*
X84245Y531080D01*
X84400Y530773D01*
Y530007D01*
G01X83108Y533222D02*
X82747Y533490D01*
X82540Y533720D01*
X82437Y534027D01*
X82540Y534295D01*
X82747Y534487D01*
X83057Y534640D01*
X83418Y534678D01*
X83728Y534640D01*
X84038Y534487D01*
X84297Y534257D01*
X84400Y533988D01*
X84297Y533682D01*
X83987Y533413D01*
X83522Y533260D01*
X83005Y533222D01*
X82333Y533298D01*
X81972Y533413D01*
X81610Y533605D01*
X81352Y533873D01*
X81300Y534142D01*
X81403Y534410D01*
X81662Y534602D01*
G01X78676Y570014D02*
Y573214D01*
G01X84876Y570014D02*
X78676D01*
G01X81700Y584657D02*
X83922D01*
X84387Y584810D01*
X84697Y585117D01*
X84800Y585500D01*
X84697Y585883D01*
X84387Y586190D01*
X83922Y586343D01*
X81700D01*
G01X84800Y588523D02*
X84128Y588600D01*
X83560Y588715D01*
X83043Y588868D01*
X82475Y589060D01*
X81700Y589367D01*
Y587833D01*
G01X84438Y591048D02*
X84697Y591317D01*
X84800Y591623D01*
X84697Y591930D01*
X84387Y592198D01*
X83922Y592390D01*
X83457Y592467D01*
X82888D01*
X82423Y592390D01*
X82010Y592198D01*
X81803Y591968D01*
X81700Y591700D01*
X81803Y591393D01*
X82010Y591163D01*
X82320Y591010D01*
X82733Y590933D01*
X83095Y591010D01*
X83457Y591202D01*
X83663Y591432D01*
X83715Y591700D01*
X83612Y592007D01*
X83353Y592237D01*
X82888Y592467D01*
G01X79405Y581942D02*
X77452D01*
G01X79405Y583895D02*
Y581942D01*
G01X78676Y577214D02*
X84876D01*
G01X78676Y574014D02*
Y577214D01*
G01X84876Y574014D02*
X78676D01*
G01X73619Y577441D02*
Y574241D01*
G01X78676Y573214D02*
X84876D01*
G01X79405Y593754D02*
Y591801D01*
G01X77452Y593754D02*
X79405D01*
G01X85284Y598125D02*
X82084D01*
G01D02*
Y604325D01*
G01X81284Y598125D02*
X78084D01*
G01X81284Y604325D02*
Y598125D01*
G01X78084D02*
Y604325D01*
G01X73284Y598125D02*
X70084D01*
G01X73284Y604325D02*
Y598125D01*
G01X70084D02*
Y604325D01*
G01X77284Y598125D02*
X74084D01*
G01X77284Y604325D02*
Y598125D01*
G01X74084D02*
Y604325D01*
G01X69284D02*
Y598125D01*
G01X83448Y609615D02*
Y640707D01*
G01X82084Y604325D02*
X85284D01*
G01X78084D02*
X81284D01*
G01X70084D02*
X73284D01*
G01X74084D02*
X77284D01*
G01X81333Y650400D02*
Y653500D01*
X82253D01*
X82560Y653345D01*
X82790Y652983D01*
X82867Y652570D01*
X82790Y652157D01*
X82598Y651847D01*
X82253Y651692D01*
X81333D01*
G01X84433Y653500D02*
Y650400D01*
X85967D01*
G01X88300D02*
Y653500D01*
X87840Y652880D01*
G01Y650400D02*
X88760D01*
G01X80615Y659290D02*
X90615D01*
G01Y654690D02*
X80615D01*
G01Y659290D02*
Y654690D01*
G01X81025Y667104D02*
X93025D01*
G01X81025Y661104D02*
Y667104D01*
G01X93025Y661104D02*
X81025D01*
G01X76506Y664091D02*
X79706D01*
G01X76506Y657891D02*
Y664091D01*
G01X79706Y657891D02*
X76506D01*
G01X79706Y664091D02*
Y657891D01*
G01X75568Y660992D02*
X72368D01*
G01X75568Y667192D02*
Y660992D01*
G01X72368Y667192D02*
X75568D01*
G01X72368Y660992D02*
Y667192D01*
G01X69323Y664332D02*
Y658396D01*
G01X81407Y668639D02*
Y680909D01*
G01X73337Y668639D02*
X81407D01*
G01X73337Y680909D02*
Y668639D01*
G01X83014Y676507D02*
Y679707D01*
G01X89214Y676507D02*
X83014D01*
G01Y679707D02*
X89214D01*
G01X83014Y680507D02*
Y683707D01*
G01X89214Y680507D02*
X83014D01*
G01Y683707D02*
X89214D01*
G01X83414Y687707D02*
Y684507D01*
G01X77214D02*
Y687707D01*
G01X83414Y684507D02*
X77214D01*
G01X73310Y682912D02*
Y689112D01*
G01X76510Y682912D02*
X73310D01*
G01X76510Y689112D02*
Y682912D01*
G01X69323Y685168D02*
Y679232D01*
G01X84183Y670200D02*
Y673300D01*
X85103D01*
X85410Y673145D01*
X85640Y672783D01*
X85717Y672370D01*
X85640Y671957D01*
X85448Y671647D01*
X85103Y671492D01*
X84183D01*
G01X87207Y673300D02*
Y671078D01*
X87360Y670613D01*
X87667Y670303D01*
X88050Y670200D01*
X88433Y670303D01*
X88740Y670613D01*
X88893Y671078D01*
Y673300D01*
G01X91610Y670200D02*
Y673300D01*
X90192Y671078D01*
X92108D01*
G01X81407Y680909D02*
X73337D01*
G01X77214Y687707D02*
X83414D01*
G01X73310Y689112D02*
X76510D01*
G01X73449Y826618D02*
Y832818D01*
X76649D01*
Y826618D01*
X73449D01*
G01X68553Y827610D02*
Y828414D01*
G01X73449Y834032D02*
Y840232D01*
X76649D01*
Y834032D01*
X73449D01*
G01X79245Y839068D02*
Y836846D01*
X79398Y836381D01*
X79705Y836071D01*
X80088Y835968D01*
X80471Y836071D01*
X80778Y836381D01*
X80931Y836846D01*
Y839068D01*
G01X83648Y835968D02*
Y839068D01*
X82230Y836846D01*
X84146D01*
G01X85445Y836588D02*
X85675Y836226D01*
X85981Y836020D01*
X86326Y835968D01*
X86633Y836020D01*
X86940Y836278D01*
X87131Y836588D01*
X87170Y836898D01*
X87093Y837260D01*
X86825Y837518D01*
X86556Y837621D01*
X86211D01*
G01X86556D02*
X86786Y837776D01*
X86978Y838035D01*
X87055Y838345D01*
X86978Y838655D01*
X86786Y838913D01*
X86441Y839068D01*
X86096Y839016D01*
X85751Y838810D01*
G01X89388Y839068D02*
X89081Y838965D01*
X88851Y838706D01*
X88698Y838396D01*
X88583Y837983D01*
X88545Y837518D01*
X88583Y837053D01*
X88698Y836640D01*
X88851Y836330D01*
X89081Y836071D01*
X89388Y835968D01*
X89695Y836071D01*
X89925Y836330D01*
X90078Y836640D01*
X90193Y837053D01*
X90231Y837518D01*
X90193Y837983D01*
X90078Y838396D01*
X89925Y838706D01*
X89695Y838965D01*
X89388Y839068D01*
G01X127107Y857677D02*
X78032D01*
G01X105375D02*
X78032D01*
G01X71607Y856484D02*
Y854262D01*
X71760Y853797D01*
X72067Y853487D01*
X72450Y853384D01*
X72833Y853487D01*
X73140Y853797D01*
X73293Y854262D01*
Y856484D01*
G01X74707Y854004D02*
X74937Y853642D01*
X75243Y853436D01*
X75588Y853384D01*
X75895Y853436D01*
X76202Y853694D01*
X76393Y854004D01*
X76432Y854314D01*
X76355Y854676D01*
X76087Y854934D01*
X75818Y855037D01*
X75473D01*
G01X75818D02*
X76048Y855192D01*
X76240Y855451D01*
X76317Y855761D01*
X76240Y856071D01*
X76048Y856329D01*
X75703Y856484D01*
X75358Y856432D01*
X75013Y856226D01*
G01X78650Y853384D02*
Y856484D01*
X78190Y855864D01*
G01Y853384D02*
X79110D01*
G01X81673D02*
X81750Y854056D01*
X81865Y854624D01*
X82018Y855141D01*
X82210Y855709D01*
X82517Y856484D01*
X80983D01*
G01X70067Y867145D02*
X77717Y874795D01*
G01D02*
X85367Y867145D01*
G01X82804Y1007489D02*
Y1016937D01*
G01X93640Y1007489D02*
X82804D01*
G01X83099Y1006066D02*
X86299D01*
G01X83099Y999866D02*
Y1006066D01*
G01X86299Y999866D02*
X83099D01*
G01X84820Y1026397D02*
X84768Y1026090D01*
X84562Y1025822D01*
X84252Y1025592D01*
X83890Y1025439D01*
X83477Y1025362D01*
X83063D01*
X82650Y1025439D01*
X82288Y1025592D01*
X81978Y1025822D01*
X81772Y1026090D01*
X81720Y1026397D01*
X81772Y1026704D01*
X81978Y1026972D01*
X82288Y1027202D01*
X82650Y1027355D01*
X83063Y1027432D01*
X83477D01*
X83890Y1027355D01*
X84252Y1027202D01*
X84562Y1026972D01*
X84768Y1026704D01*
X84820Y1026397D01*
G01X83993Y1026704D02*
X84820Y1027164D01*
G01Y1029497D02*
X81720D01*
X82340Y1029037D01*
G01X84820D02*
Y1029957D01*
G01X82237Y1031869D02*
X81927Y1032099D01*
X81772Y1032367D01*
X81720Y1032674D01*
X81823Y1033057D01*
X82082Y1033325D01*
X82392Y1033402D01*
X82702Y1033364D01*
X82960Y1033210D01*
X83477Y1032444D01*
X83838Y1032099D01*
X84355Y1031869D01*
X84820Y1031792D01*
Y1033402D01*
G01X82804Y1016937D02*
X86222D01*
G01X82616Y1019448D02*
Y1022648D01*
G01X88816Y1019448D02*
X82616D01*
G01Y1022648D02*
X88816D01*
G01X69184Y1073256D02*
Y1070056D01*
G01Y1077256D02*
Y1074056D01*
G01Y1069256D02*
Y1066056D01*
G01Y1085256D02*
Y1082056D01*
G01Y1089256D02*
Y1086056D01*
G01Y1081256D02*
Y1078056D01*
G01Y1093256D02*
Y1090056D01*
G01X78238Y1168736D02*
Y1171836D01*
G01X79848D02*
Y1168736D01*
G01Y1170286D02*
X78238D01*
G01X82143Y1168736D02*
Y1171836D01*
X81683Y1171216D01*
G01Y1168736D02*
X82603D01*
G01X84400Y1169356D02*
X84630Y1168994D01*
X84936Y1168788D01*
X85281Y1168736D01*
X85588Y1168788D01*
X85895Y1169046D01*
X86086Y1169356D01*
X86125Y1169666D01*
X86048Y1170028D01*
X85780Y1170286D01*
X85511Y1170389D01*
X85166D01*
G01X85511D02*
X85741Y1170544D01*
X85933Y1170803D01*
X86010Y1171113D01*
X85933Y1171423D01*
X85741Y1171681D01*
X85396Y1171836D01*
X85051Y1171784D01*
X84706Y1171578D01*
G01X88343Y1168736D02*
X88611Y1168788D01*
X88918Y1168943D01*
X89110Y1169201D01*
X89186Y1169563D01*
X89110Y1169924D01*
X88880Y1170234D01*
X88535Y1170389D01*
X88151D01*
X87921Y1170493D01*
X87730Y1170751D01*
X87653Y1171113D01*
X87768Y1171474D01*
X88036Y1171733D01*
X88343Y1171836D01*
X88650Y1171733D01*
X88918Y1171474D01*
X89033Y1171113D01*
X88956Y1170751D01*
X88765Y1170493D01*
X88535Y1170389D01*
X88151D01*
X87806Y1170234D01*
X87576Y1169924D01*
X87500Y1169563D01*
X87576Y1169201D01*
X87768Y1168943D01*
X88075Y1168788D01*
X88343Y1168736D01*
G01X73261Y1200622D02*
Y1203722D01*
X74181D01*
X74488Y1203567D01*
X74718Y1203205D01*
X74795Y1202792D01*
X74718Y1202379D01*
X74526Y1202069D01*
X74181Y1201914D01*
X73261D01*
G01X76361Y1201242D02*
X76553Y1200932D01*
X76783Y1200725D01*
X77051Y1200622D01*
X77358Y1200725D01*
X77588Y1200932D01*
X77818Y1201242D01*
X77895Y1201655D01*
Y1203722D01*
G01X80228Y1200622D02*
Y1203722D01*
X79768Y1203102D01*
G01Y1200622D02*
X80688D01*
G01X83328Y1203722D02*
X83021Y1203619D01*
X82791Y1203360D01*
X82638Y1203050D01*
X82523Y1202637D01*
X82485Y1202172D01*
X82523Y1201707D01*
X82638Y1201294D01*
X82791Y1200984D01*
X83021Y1200725D01*
X83328Y1200622D01*
X83635Y1200725D01*
X83865Y1200984D01*
X84018Y1201294D01*
X84133Y1201707D01*
X84171Y1202172D01*
X84133Y1202637D01*
X84018Y1203050D01*
X83865Y1203360D01*
X83635Y1203619D01*
X83328Y1203722D01*
G01X73404Y1205065D02*
Y1208165D01*
X74324D01*
X74631Y1208010D01*
X74861Y1207648D01*
X74938Y1207235D01*
X74861Y1206822D01*
X74669Y1206512D01*
X74324Y1206357D01*
X73404D01*
G01X76504Y1205685D02*
X76696Y1205375D01*
X76926Y1205168D01*
X77194Y1205065D01*
X77501Y1205168D01*
X77731Y1205375D01*
X77961Y1205685D01*
X78038Y1206098D01*
Y1208165D01*
G01X79719Y1205427D02*
X79988Y1205168D01*
X80294Y1205065D01*
X80601Y1205168D01*
X80869Y1205478D01*
X81061Y1205943D01*
X81138Y1206408D01*
Y1206977D01*
X81061Y1207442D01*
X80869Y1207855D01*
X80639Y1208062D01*
X80371Y1208165D01*
X80064Y1208062D01*
X79834Y1207855D01*
X79681Y1207545D01*
X79604Y1207132D01*
X79681Y1206770D01*
X79873Y1206408D01*
X80103Y1206202D01*
X80371Y1206150D01*
X80678Y1206253D01*
X80908Y1206512D01*
X81138Y1206977D01*
G01X81980Y1439909D02*
Y1441776D01*
X84230D01*
X84980Y1441216D01*
X85480Y1440562D01*
X85730Y1439629D01*
X85480Y1438696D01*
X84980Y1438042D01*
X84230Y1437482D01*
X83355Y1437109D01*
X82355Y1436922D01*
X81480D01*
X80730Y1437109D01*
X79855Y1437482D01*
X79105Y1438042D01*
X78605Y1438602D01*
X78230Y1439349D01*
Y1440002D01*
X78480Y1440749D01*
X78980Y1441309D01*
G01X85730Y1444982D02*
X78230D01*
Y1447222D01*
X78605Y1447969D01*
X79480Y1448529D01*
X80480Y1448716D01*
X81480Y1448529D01*
X82230Y1448062D01*
X82605Y1447222D01*
Y1444982D01*
G01X78230Y1452296D02*
X83605D01*
X84730Y1452669D01*
X85480Y1453416D01*
X85730Y1454349D01*
X85480Y1455282D01*
X84730Y1456029D01*
X83605Y1456402D01*
X78230D01*
G01X88230Y1459049D02*
Y1464649D01*
G01X85730Y1467389D02*
X78230D01*
G01Y1471309D02*
X85730D01*
G01X81980D02*
Y1467389D01*
G01X72541Y1585165D02*
X69341D01*
G01X72541Y1591365D02*
Y1585165D01*
G01X69341Y1591365D02*
X72541D01*
G01X69341Y1585165D02*
Y1591365D01*
G01X75891Y1626702D02*
X72691D01*
G01X75891Y1632902D02*
Y1626702D01*
G01X72691D02*
Y1632902D01*
G01X79891Y1626702D02*
X76691D01*
G01X79891Y1632902D02*
Y1626702D01*
G01X76691D02*
Y1632902D01*
G01X83891Y1626702D02*
X80691D01*
G01X83891Y1632902D02*
Y1626702D01*
G01X80691D02*
Y1632902D01*
G01X71891Y1626702D02*
X68691D01*
G01X71891Y1632902D02*
Y1626702D01*
G01X68691D02*
Y1632902D01*
G01X72691D02*
X75891D01*
G01X76691D02*
X79891D01*
G01X80691D02*
X83891D01*
G01X68691D02*
X71891D01*
G01X86408Y105128D02*
Y98928D01*
G01X86002Y89533D02*
Y92633D01*
G01X87612D02*
Y89533D01*
G01Y91083D02*
X86002D01*
G01X89830Y89533D02*
X89907Y90205D01*
X90022Y90773D01*
X90175Y91290D01*
X90367Y91858D01*
X90674Y92633D01*
X89140D01*
G01X93007Y89533D02*
Y92633D01*
X92547Y92013D01*
G01Y89533D02*
X93467D01*
G01X101481Y116723D02*
X98381D01*
Y117643D01*
X98536Y117950D01*
X98898Y118180D01*
X99311Y118257D01*
X99724Y118180D01*
X100034Y117988D01*
X100189Y117643D01*
Y116723D01*
G01X98381Y119747D02*
X100603D01*
X101068Y119900D01*
X101378Y120207D01*
X101481Y120590D01*
X101378Y120973D01*
X101068Y121280D01*
X100603Y121433D01*
X98381D01*
G01X101481Y123690D02*
X101429Y123958D01*
X101274Y124265D01*
X101016Y124457D01*
X100654Y124533D01*
X100293Y124457D01*
X99983Y124227D01*
X99828Y123882D01*
Y123498D01*
X99724Y123268D01*
X99466Y123077D01*
X99104Y123000D01*
X98743Y123115D01*
X98484Y123383D01*
X98381Y123690D01*
X98484Y123997D01*
X98743Y124265D01*
X99104Y124380D01*
X99466Y124303D01*
X99724Y124112D01*
X99828Y123882D01*
Y123498D01*
X99983Y123153D01*
X100293Y122923D01*
X100654Y122847D01*
X101016Y122923D01*
X101274Y123115D01*
X101429Y123422D01*
X101481Y123690D01*
G01X98898Y126062D02*
X98588Y126292D01*
X98433Y126560D01*
X98381Y126867D01*
X98484Y127250D01*
X98743Y127518D01*
X99053Y127595D01*
X99363Y127557D01*
X99621Y127403D01*
X100138Y126637D01*
X100499Y126292D01*
X101016Y126062D01*
X101481Y125985D01*
Y127595D01*
G01X91879Y154138D02*
Y144690D01*
G01X89824Y142847D02*
Y139647D01*
G01X99486Y151368D02*
Y148168D01*
G01X93286D02*
Y151368D01*
G01X99486Y148168D02*
X93286D01*
G01Y144168D02*
Y147368D01*
G01X99486Y144168D02*
X93286D01*
G01X99486Y147368D02*
Y144168D01*
G01X93286Y147368D02*
X99486D01*
G01X100500Y134907D02*
X102722D01*
X103187Y135060D01*
X103497Y135367D01*
X103600Y135750D01*
X103497Y136133D01*
X103187Y136440D01*
X102722Y136593D01*
X100500D01*
G01X102980Y138007D02*
X103342Y138237D01*
X103548Y138543D01*
X103600Y138888D01*
X103548Y139195D01*
X103290Y139502D01*
X102980Y139693D01*
X102670Y139732D01*
X102308Y139655D01*
X102050Y139387D01*
X101947Y139118D01*
Y138773D01*
G01Y139118D02*
X101792Y139348D01*
X101533Y139540D01*
X101223Y139617D01*
X100913Y139540D01*
X100655Y139348D01*
X100500Y139003D01*
X100552Y138658D01*
X100758Y138313D01*
G01X103600Y141950D02*
X103548Y142218D01*
X103393Y142525D01*
X103135Y142717D01*
X102773Y142793D01*
X102412Y142717D01*
X102102Y142487D01*
X101947Y142142D01*
Y141758D01*
X101843Y141528D01*
X101585Y141337D01*
X101223Y141260D01*
X100862Y141375D01*
X100603Y141643D01*
X100500Y141950D01*
X100603Y142257D01*
X100862Y142525D01*
X101223Y142640D01*
X101585Y142563D01*
X101843Y142372D01*
X101947Y142142D01*
Y141758D01*
X102102Y141413D01*
X102412Y141183D01*
X102773Y141107D01*
X103135Y141183D01*
X103393Y141375D01*
X103548Y141682D01*
X103600Y141950D01*
G01X101017Y144322D02*
X100707Y144552D01*
X100552Y144820D01*
X100500Y145127D01*
X100603Y145510D01*
X100862Y145778D01*
X101172Y145855D01*
X101482Y145817D01*
X101740Y145663D01*
X102257Y144897D01*
X102618Y144552D01*
X103135Y144322D01*
X103600Y144245D01*
Y145855D01*
G01X88461Y154138D02*
X91879D01*
G01X86461Y152414D02*
X88461Y154138D01*
G01X93286Y151368D02*
X99486D01*
G01X85057Y175100D02*
Y172878D01*
X85210Y172413D01*
X85517Y172103D01*
X85900Y172000D01*
X86283Y172103D01*
X86590Y172413D01*
X86743Y172878D01*
Y175100D01*
G01X88157Y172465D02*
X88387Y172207D01*
X88655Y172052D01*
X89000Y172000D01*
X89345Y172103D01*
X89613Y172310D01*
X89805Y172672D01*
X89843Y173085D01*
X89767Y173498D01*
X89575Y173757D01*
X89307Y173963D01*
X89038Y174015D01*
X88770Y173963D01*
X88425Y173757D01*
X88540Y175100D01*
X89575D01*
G01X92100Y172000D02*
Y175100D01*
X91640Y174480D01*
G01Y172000D02*
X92560D01*
G01X95851Y178897D02*
Y176944D01*
G01D02*
X93898D01*
G01X100222Y171065D02*
Y174265D01*
G01X106422Y171065D02*
X100222D01*
G01Y174265D02*
X106422D01*
G01X100222Y179065D02*
Y182265D01*
G01X106422Y179065D02*
X100222D01*
G01Y175065D02*
Y178265D01*
G01X106422Y175065D02*
X100222D01*
G01Y178265D02*
X106422D01*
G01X100222Y167065D02*
Y170265D01*
G01X106422Y167065D02*
X100222D01*
G01Y170265D02*
X106422D01*
G01X95851Y188756D02*
Y186803D01*
G01X93898Y188756D02*
X95851D01*
G01X100222Y182265D02*
X106422D01*
G01X100222Y183065D02*
Y186265D01*
G01X106422Y183065D02*
X100222D01*
G01Y186265D02*
X106422D01*
G01X100222Y187065D02*
Y190265D01*
G01X106422Y187065D02*
X100222D01*
G01Y190265D02*
X106422D01*
G01X100222Y194265D02*
X106422D01*
G01X100222Y191065D02*
Y194265D01*
G01X106422Y191065D02*
X100222D01*
G01Y195065D02*
Y198265D01*
G01X106422Y195065D02*
X100222D01*
G01X100317Y202464D02*
X106517D01*
Y199264D01*
X100317D01*
Y202464D01*
G01X100222Y198265D02*
X106422D01*
G01X100317Y207264D02*
Y210464D01*
G01X106517Y207264D02*
X100317D01*
G01Y210464D02*
X106517D01*
G01X100317Y211264D02*
Y214464D01*
G01X106517Y211264D02*
X100317D01*
G01Y206464D02*
X106517D01*
G01X100317Y203264D02*
Y206464D01*
G01X106517Y203264D02*
X100317D01*
G01X86498Y232621D02*
Y226621D01*
G01X84498Y225921D02*
Y222721D01*
G01X100317Y215264D02*
Y218464D01*
G01X106517Y215264D02*
X100317D01*
G01Y218464D02*
X106517D01*
G01X100317Y220264D02*
Y223464D01*
G01X106517Y220264D02*
X100317D01*
G01Y223464D02*
X106517D01*
G01X100317Y214464D02*
X106517D01*
G01X100314Y227319D02*
X106514D01*
Y224119D01*
X100314D01*
Y227319D01*
G01X98033Y234813D02*
Y250325D01*
G01X86366Y264210D02*
Y258010D01*
G01X93077Y264635D02*
X108589D01*
G01X93077Y295727D02*
Y264635D01*
G01X91445Y273701D02*
X88245D01*
G01X91445Y279901D02*
Y273701D01*
G01X88245D02*
Y279901D01*
G01X85887Y279427D02*
Y267653D01*
G01X88245Y279901D02*
X91445D01*
G01X89967Y283093D02*
X86867D01*
Y284013D01*
X87022Y284320D01*
X87384Y284550D01*
X87797Y284627D01*
X88210Y284550D01*
X88520Y284358D01*
X88675Y284013D01*
Y283093D01*
G01X86867Y286117D02*
X89089D01*
X89554Y286270D01*
X89864Y286577D01*
X89967Y286960D01*
X89864Y287343D01*
X89554Y287650D01*
X89089Y287803D01*
X86867D01*
G01X89967Y289983D02*
X89295Y290060D01*
X88727Y290175D01*
X88210Y290328D01*
X87642Y290520D01*
X86867Y290827D01*
Y289293D01*
G01X88675Y292432D02*
X88314Y292700D01*
X88107Y292930D01*
X88004Y293237D01*
X88107Y293505D01*
X88314Y293697D01*
X88624Y293850D01*
X88985Y293888D01*
X89295Y293850D01*
X89605Y293697D01*
X89864Y293467D01*
X89967Y293198D01*
X89864Y292892D01*
X89554Y292623D01*
X89089Y292470D01*
X88572Y292432D01*
X87900Y292508D01*
X87539Y292623D01*
X87177Y292815D01*
X86919Y293083D01*
X86867Y293352D01*
X86970Y293620D01*
X87229Y293812D01*
G01X108589Y295727D02*
X93077D01*
G01X93600Y477383D02*
X90500D01*
Y478303D01*
X90655Y478610D01*
X91017Y478840D01*
X91430Y478917D01*
X91843Y478840D01*
X92153Y478648D01*
X92308Y478303D01*
Y477383D01*
G01X93600Y480407D02*
X90500D01*
Y481173D01*
X90655Y481480D01*
X90862Y481710D01*
X91172Y481902D01*
X91533Y482055D01*
X92050Y482093D01*
X92567Y482055D01*
X92928Y481902D01*
X93238Y481710D01*
X93445Y481480D01*
X93600Y481173D01*
Y480407D01*
G01X93135Y483507D02*
X93393Y483737D01*
X93548Y484005D01*
X93600Y484350D01*
X93497Y484695D01*
X93290Y484963D01*
X92928Y485155D01*
X92515Y485193D01*
X92102Y485117D01*
X91843Y484925D01*
X91637Y484657D01*
X91585Y484388D01*
X91637Y484120D01*
X91843Y483775D01*
X90500Y483890D01*
Y484925D01*
G01X91017Y486722D02*
X90707Y486952D01*
X90552Y487220D01*
X90500Y487527D01*
X90603Y487910D01*
X90862Y488178D01*
X91172Y488255D01*
X91482Y488217D01*
X91740Y488063D01*
X92257Y487297D01*
X92618Y486952D01*
X93135Y486722D01*
X93600Y486645D01*
Y488255D01*
G01X89122Y504394D02*
Y474835D01*
G01X91913Y553448D02*
Y568248D01*
G01X84876Y573214D02*
Y570014D01*
G01Y577214D02*
Y574014D01*
G01X86052Y580237D02*
X89252D01*
G01X86052Y574037D02*
Y580237D01*
G01X89252Y574037D02*
X86052D01*
G01X89252Y580237D02*
Y574037D01*
G01X85284Y604325D02*
Y598125D01*
G01X89284D02*
X86084D01*
G01X89284Y604325D02*
Y598125D01*
G01X86084D02*
Y604325D01*
G01X88000Y611583D02*
X84900D01*
Y612503D01*
X85055Y612810D01*
X85417Y613040D01*
X85830Y613117D01*
X86243Y613040D01*
X86553Y612848D01*
X86708Y612503D01*
Y611583D01*
G01X88000Y614607D02*
X84900D01*
Y615373D01*
X85055Y615680D01*
X85262Y615910D01*
X85572Y616102D01*
X85933Y616255D01*
X86450Y616293D01*
X86967Y616255D01*
X87328Y616102D01*
X87638Y615910D01*
X87845Y615680D01*
X88000Y615373D01*
Y614607D01*
G01Y618473D02*
X87328Y618550D01*
X86760Y618665D01*
X86243Y618818D01*
X85675Y619010D01*
X84900Y619317D01*
Y617783D01*
G01X86708Y620922D02*
X86347Y621190D01*
X86140Y621420D01*
X86037Y621727D01*
X86140Y621995D01*
X86347Y622187D01*
X86657Y622340D01*
X87018Y622378D01*
X87328Y622340D01*
X87638Y622187D01*
X87897Y621957D01*
X88000Y621688D01*
X87897Y621382D01*
X87587Y621113D01*
X87122Y620960D01*
X86605Y620922D01*
X85933Y620998D01*
X85572Y621113D01*
X85210Y621305D01*
X84952Y621573D01*
X84900Y621842D01*
X85003Y622110D01*
X85262Y622302D01*
G01X86084Y604325D02*
X89284D01*
G01X91856Y650725D02*
Y656925D01*
G01X95056Y650725D02*
X91856D01*
G01X95056Y656925D02*
Y650725D01*
G01X90615Y654790D02*
Y654690D01*
G01Y659290D02*
Y654690D01*
G01X93025Y667104D02*
Y661104D01*
G01X91856Y656925D02*
X95056D01*
G01X89214Y679707D02*
Y676507D01*
G01Y683707D02*
Y680507D01*
G01X96602Y853858D02*
X96794Y853548D01*
X97024Y853341D01*
X97292Y853238D01*
X97599Y853341D01*
X97829Y853548D01*
X98059Y853858D01*
X98136Y854271D01*
Y856338D01*
G01X99702Y853238D02*
Y856338D01*
X100622D01*
X100929Y856183D01*
X101159Y855821D01*
X101236Y855408D01*
X101159Y854995D01*
X100967Y854685D01*
X100622Y854530D01*
X99702D01*
G01X104336Y853238D02*
X102802D01*
Y856338D01*
X104336D01*
G01X103722Y854840D02*
X102802D01*
G01X105864Y853238D02*
X107474Y856338D01*
G01X105864D02*
X107474Y853238D01*
G01X109769Y856338D02*
X109462Y856235D01*
X109232Y855976D01*
X109079Y855666D01*
X108964Y855253D01*
X108926Y854788D01*
X108964Y854323D01*
X109079Y853910D01*
X109232Y853600D01*
X109462Y853341D01*
X109769Y853238D01*
X110076Y853341D01*
X110306Y853600D01*
X110459Y853910D01*
X110574Y854323D01*
X110612Y854788D01*
X110574Y855253D01*
X110459Y855666D01*
X110306Y855976D01*
X110076Y856235D01*
X109769Y856338D01*
G01X92658Y867145D02*
Y908445D01*
G01X85367Y867145D02*
X92658D01*
G01X99302Y967455D02*
X158357D01*
Y936060D01*
X99302D01*
Y967204D01*
G01X94236Y987631D02*
X97436D01*
G01X94236Y981431D02*
Y987631D01*
G01X97436Y981431D02*
X94236D01*
G01X97436Y987631D02*
Y981431D01*
G01X98236Y990431D02*
Y996631D01*
G01X101436Y990431D02*
X98236D01*
G01X94236D02*
Y996631D01*
G01X97436Y990431D02*
X94236D01*
G01X97436Y996631D02*
Y990431D01*
G01X98236Y987631D02*
X101436D01*
G01X98236Y981431D02*
Y987631D01*
G01X101436Y981431D02*
X98236D01*
G01X93640Y1016937D02*
Y1007489D01*
G01X88466Y996264D02*
Y999364D01*
X89232D01*
X89539Y999209D01*
X89769Y999002D01*
X89961Y998692D01*
X90114Y998331D01*
X90152Y997814D01*
X90114Y997297D01*
X89961Y996936D01*
X89769Y996626D01*
X89539Y996419D01*
X89232Y996264D01*
X88466D01*
G01X92409D02*
Y999364D01*
X91949Y998744D01*
G01Y996264D02*
X92869D01*
G01X87958Y1005249D02*
X95048D01*
G01X87958Y1001449D02*
Y1005249D01*
G01X95048Y1001449D02*
X87958D01*
G01X88458Y1005249D02*
X95648D01*
G01X88458Y1001449D02*
Y1005249D01*
G01X95648Y1001449D02*
X88458D01*
G01X96098Y1005249D02*
Y1001499D01*
G01X88958Y1005249D02*
X96098D01*
G01X88958Y1001449D02*
Y1005249D01*
G01X96048Y1001449D02*
X88958D01*
G01X98236Y996631D02*
X101436D01*
G01X94236D02*
X97436D01*
G01X96009Y1009297D02*
Y1015497D01*
G01X99209Y1009297D02*
X96009D01*
G01X99209Y1015497D02*
Y1009297D01*
G01X86299Y1006066D02*
Y999866D01*
G01X90222Y1016937D02*
X93640D01*
G01X88222Y1015213D02*
X90222Y1016937D01*
G01X86222D02*
X88222Y1015213D01*
G01X94671Y1025363D02*
Y1029963D01*
G01X104871Y1025363D02*
X94671D01*
G01X96009Y1015497D02*
X99209D01*
G01X89911Y1019577D02*
Y1022777D01*
G01X96111Y1019577D02*
X89911D01*
G01X96111Y1022777D02*
Y1019577D01*
G01X89911Y1022777D02*
X96111D01*
G01X92657Y1023702D02*
X89457D01*
G01X92657Y1029902D02*
Y1023702D01*
G01X89457D02*
Y1029902D01*
G01X88816Y1022648D02*
Y1019448D01*
G01X94671Y1029963D02*
X104871D01*
G01X89457Y1029902D02*
X92657D01*
G01X148227Y1066535D02*
G02X140089Y1087664I-31496J1D01*
G01X148227Y1263386D02*
G03X139265Y1241381I-31496J0D01*
G01X92041Y1295694D02*
Y1298794D01*
G01X93651D02*
Y1295694D01*
G01Y1297244D02*
X92041D01*
G01X95294Y1296056D02*
X95563Y1295797D01*
X95869Y1295694D01*
X96176Y1295797D01*
X96444Y1296107D01*
X96636Y1296572D01*
X96713Y1297037D01*
Y1297606D01*
X96636Y1298071D01*
X96444Y1298484D01*
X96214Y1298691D01*
X95946Y1298794D01*
X95639Y1298691D01*
X95409Y1298484D01*
X95256Y1298174D01*
X95179Y1297761D01*
X95256Y1297399D01*
X95448Y1297037D01*
X95678Y1296831D01*
X95946Y1296779D01*
X96253Y1296882D01*
X96483Y1297141D01*
X96713Y1297606D01*
G01X99046Y1295694D02*
Y1298794D01*
X98586Y1298174D01*
G01Y1295694D02*
X99506D01*
G01X93150Y1425158D02*
Y1689331D01*
G01X206142Y1425158D02*
X93150D01*
G01X86032Y1594714D02*
Y1621862D01*
G01X87891Y1626702D02*
X84691D01*
G01X87891Y1632902D02*
Y1626702D01*
G01X84691D02*
Y1632902D01*
G01D02*
X87891D01*
G01X93150Y1689331D02*
X206142D01*
G01X103062Y111951D02*
Y118151D01*
G01X106262Y111951D02*
X103062D01*
G01X106262Y118151D02*
Y111951D01*
G01X113982Y109424D02*
X117182D01*
G01X113982Y103224D02*
Y109424D01*
G01X117182Y103224D02*
X113982D01*
G01X109982Y109424D02*
X113182D01*
G01X109982Y103224D02*
Y109424D01*
G01X113182Y103224D02*
X109982D01*
G01X113182Y109424D02*
Y103224D01*
G01X108436Y111734D02*
Y123508D01*
G01X118198Y111734D02*
X108436D01*
G01X103062Y118151D02*
X106262D01*
G01X109207Y126223D02*
X106007D01*
G01X109207Y132423D02*
Y126223D01*
G01X106007Y132423D02*
X109207D01*
G01X106007Y126223D02*
Y132423D01*
G01X119207Y126223D02*
X116007D01*
G01Y132423D02*
X119207D01*
G01X116007Y126223D02*
Y132423D01*
G01X112007D02*
X115207D01*
G01X112007Y126223D02*
Y132423D01*
G01X115207Y126223D02*
X112007D01*
G01X115207Y132423D02*
Y126223D01*
G01X108436Y123508D02*
X118198D01*
G01X108396Y146229D02*
X105196D01*
G01X108396Y152429D02*
Y146229D01*
G01X105196D02*
Y152429D01*
G01X106886Y144395D02*
Y135095D01*
G01X117486Y144395D02*
X106886D01*
G01Y134995D02*
X117486D01*
G01X105196Y152429D02*
X108396D01*
G01X105196Y159540D02*
X108396D01*
G01X105196Y153340D02*
Y159540D01*
G01X108396Y153340D02*
X105196D01*
G01X108396Y159540D02*
Y153340D01*
G01X115109Y149950D02*
Y165304D01*
G01X127787Y149950D02*
X115109D01*
G01X115306Y165304D02*
X127787D01*
G01X112383Y179600D02*
Y182700D01*
X113303D01*
X113610Y182545D01*
X113840Y182183D01*
X113917Y181770D01*
X113840Y181357D01*
X113648Y181047D01*
X113303Y180892D01*
X112383D01*
G01X115407Y179600D02*
Y182700D01*
X116173D01*
X116480Y182545D01*
X116710Y182338D01*
X116902Y182028D01*
X117055Y181667D01*
X117093Y181150D01*
X117055Y180633D01*
X116902Y180272D01*
X116710Y179962D01*
X116480Y179755D01*
X116173Y179600D01*
X115407D01*
G01X118622Y180892D02*
X118890Y181253D01*
X119120Y181460D01*
X119427Y181563D01*
X119695Y181460D01*
X119887Y181253D01*
X120040Y180943D01*
X120078Y180582D01*
X120040Y180272D01*
X119887Y179962D01*
X119657Y179703D01*
X119388Y179600D01*
X119082Y179703D01*
X118813Y180013D01*
X118660Y180478D01*
X118622Y180995D01*
X118698Y181667D01*
X118813Y182028D01*
X119005Y182390D01*
X119273Y182648D01*
X119542Y182700D01*
X119810Y182597D01*
X120002Y182338D01*
G01X121722Y182183D02*
X121952Y182493D01*
X122220Y182648D01*
X122527Y182700D01*
X122910Y182597D01*
X123178Y182338D01*
X123255Y182028D01*
X123217Y181718D01*
X123063Y181460D01*
X122297Y180943D01*
X121952Y180582D01*
X121722Y180065D01*
X121645Y179600D01*
X123255D01*
G01X106422Y174265D02*
Y171065D01*
G01Y182265D02*
Y179065D01*
G01Y178265D02*
Y175065D01*
G01Y170265D02*
Y167065D01*
G01X107990Y189435D02*
X110230D01*
G01X109017Y191060D02*
Y187810D01*
G01X111631Y195583D02*
X141190D01*
G01X111631Y184087D02*
Y195583D01*
G01X141190Y184087D02*
X111631D01*
G01X106422Y186265D02*
Y183065D01*
G01Y190265D02*
Y187065D01*
G01Y194265D02*
Y191065D01*
G01Y198265D02*
Y195065D01*
G01X111784Y204506D02*
Y216506D01*
G01X117784Y204506D02*
X111784D01*
G01X106517Y210464D02*
Y207264D01*
G01Y214464D02*
Y211264D01*
G01Y206464D02*
Y203264D01*
G01X111784Y216506D02*
X117784D01*
G01X106517Y218464D02*
Y215264D01*
G01Y223464D02*
Y220264D01*
G01X114552Y243678D02*
X120752D01*
G01X114552Y240478D02*
Y243678D01*
G01X120752Y240478D02*
X114552D01*
G01X110582Y246771D02*
Y249971D01*
G01X116782Y246771D02*
X110582D01*
G01X116782Y249971D02*
Y246771D01*
G01X117560Y257844D02*
X117253Y257896D01*
X116985Y258102D01*
X116755Y258412D01*
X116602Y258774D01*
X116525Y259187D01*
Y259601D01*
X116602Y260014D01*
X116755Y260376D01*
X116985Y260686D01*
X117253Y260892D01*
X117560Y260944D01*
X117867Y260892D01*
X118135Y260686D01*
X118365Y260376D01*
X118518Y260014D01*
X118595Y259601D01*
Y259187D01*
X118518Y258774D01*
X118365Y258412D01*
X118135Y258102D01*
X117867Y257896D01*
X117560Y257844D01*
G01X117867Y258671D02*
X118327Y257844D01*
G01X120660D02*
Y260944D01*
X120200Y260324D01*
G01Y257844D02*
X121120D01*
G01X123032Y260427D02*
X123262Y260737D01*
X123530Y260892D01*
X123837Y260944D01*
X124220Y260841D01*
X124488Y260582D01*
X124565Y260272D01*
X124527Y259962D01*
X124373Y259704D01*
X123607Y259187D01*
X123262Y258826D01*
X123032Y258309D01*
X122955Y257844D01*
X124565D01*
G01X126860D02*
X127128Y257896D01*
X127435Y258051D01*
X127627Y258309D01*
X127703Y258671D01*
X127627Y259032D01*
X127397Y259342D01*
X127052Y259497D01*
X126668D01*
X126438Y259601D01*
X126247Y259859D01*
X126170Y260221D01*
X126285Y260582D01*
X126553Y260841D01*
X126860Y260944D01*
X127167Y260841D01*
X127435Y260582D01*
X127550Y260221D01*
X127473Y259859D01*
X127282Y259601D01*
X127052Y259497D01*
X126668D01*
X126323Y259342D01*
X126093Y259032D01*
X126017Y258671D01*
X126093Y258309D01*
X126285Y258051D01*
X126592Y257896D01*
X126860Y257844D01*
G01X110582Y249971D02*
X116782D01*
G01Y253971D02*
Y250771D01*
G01X110582Y253971D02*
X116782D01*
G01X110582Y250771D02*
Y253971D01*
G01X116782Y250771D02*
X110582D01*
G01X113000Y272383D02*
X109900D01*
Y273303D01*
X110055Y273610D01*
X110417Y273840D01*
X110830Y273917D01*
X111243Y273840D01*
X111553Y273648D01*
X111708Y273303D01*
Y272383D01*
G01X113000Y275407D02*
X109900D01*
Y276173D01*
X110055Y276480D01*
X110262Y276710D01*
X110572Y276902D01*
X110933Y277055D01*
X111450Y277093D01*
X111967Y277055D01*
X112328Y276902D01*
X112638Y276710D01*
X112845Y276480D01*
X113000Y276173D01*
Y275407D01*
G01Y279350D02*
X112948Y279618D01*
X112793Y279925D01*
X112535Y280117D01*
X112173Y280193D01*
X111812Y280117D01*
X111502Y279887D01*
X111347Y279542D01*
Y279158D01*
X111243Y278928D01*
X110985Y278737D01*
X110623Y278660D01*
X110262Y278775D01*
X110003Y279043D01*
X109900Y279350D01*
X110003Y279657D01*
X110262Y279925D01*
X110623Y280040D01*
X110985Y279963D01*
X111243Y279772D01*
X111347Y279542D01*
Y279158D01*
X111502Y278813D01*
X111812Y278583D01*
X112173Y278507D01*
X112535Y278583D01*
X112793Y278775D01*
X112948Y279082D01*
X113000Y279350D01*
G01Y282910D02*
X109900D01*
X112122Y281492D01*
Y283408D01*
G01X108589Y264635D02*
Y295727D01*
G01X105375Y857677D02*
Y917913D01*
G01X110032Y905545D02*
X109980Y905813D01*
X109825Y906120D01*
X109567Y906312D01*
X109205Y906388D01*
X108844Y906312D01*
X108534Y906082D01*
X108379Y905737D01*
Y905353D01*
X108275Y905123D01*
X108017Y904932D01*
X107655Y904855D01*
X107294Y904970D01*
X107035Y905238D01*
X106932Y905545D01*
X107035Y905852D01*
X107294Y906120D01*
X107655Y906235D01*
X108017Y906158D01*
X108275Y905967D01*
X108379Y905737D01*
Y905353D01*
X108534Y905008D01*
X108844Y904778D01*
X109205Y904702D01*
X109567Y904778D01*
X109825Y904970D01*
X109980Y905277D01*
X110032Y905545D01*
G01X107971Y948920D02*
Y952020D01*
X108891D01*
X109198Y951865D01*
X109428Y951503D01*
X109505Y951090D01*
X109428Y950677D01*
X109236Y950367D01*
X108891Y950212D01*
X107971D01*
G01X112681Y951762D02*
X112451Y951917D01*
X112183Y952020D01*
X111876D01*
X111531Y951865D01*
X111263Y951607D01*
X111071Y951297D01*
X110918Y950780D01*
X110880Y950315D01*
X110956Y949850D01*
X111071Y949540D01*
X111301Y949230D01*
X111570Y949023D01*
X111838Y948920D01*
X112106D01*
X112375Y949023D01*
X112605Y949178D01*
X112796Y949385D01*
G01X115245Y950573D02*
X115398Y950728D01*
X115513Y950987D01*
X115590Y951348D01*
X115513Y951658D01*
X115360Y951865D01*
X115091Y952020D01*
X114056D01*
Y948920D01*
X115321D01*
X115590Y949127D01*
X115743Y949437D01*
X115820Y949798D01*
X115743Y950160D01*
X115513Y950470D01*
X115245Y950573D01*
X114056D01*
G01X120180Y952020D02*
X121138Y948920D01*
X122096Y952020D01*
G01X125005Y948920D02*
X123471D01*
Y952020D01*
X125005D01*
G01X124391Y950522D02*
X123471D01*
G01X126456Y948920D02*
Y952020D01*
X128220Y948920D01*
Y952020D01*
G01X129595Y948920D02*
Y952020D01*
X130361D01*
X130668Y951865D01*
X130898Y951658D01*
X131090Y951348D01*
X131243Y950987D01*
X131281Y950470D01*
X131243Y949953D01*
X131090Y949592D01*
X130898Y949282D01*
X130668Y949075D01*
X130361Y948920D01*
X129595D01*
G01X133538D02*
X133231Y948972D01*
X132963Y949178D01*
X132733Y949488D01*
X132580Y949850D01*
X132503Y950263D01*
Y950677D01*
X132580Y951090D01*
X132733Y951452D01*
X132963Y951762D01*
X133231Y951968D01*
X133538Y952020D01*
X133845Y951968D01*
X134113Y951762D01*
X134343Y951452D01*
X134496Y951090D01*
X134573Y950677D01*
Y950263D01*
X134496Y949850D01*
X134343Y949488D01*
X134113Y949178D01*
X133845Y948972D01*
X133538Y948920D01*
G01X135871D02*
Y952020D01*
X136830D01*
X137136Y951865D01*
X137328Y951658D01*
X137405Y951245D01*
X137328Y950832D01*
X137098Y950573D01*
X136830Y950418D01*
X135871D01*
G01X136830D02*
X137405Y948920D01*
G01X142071Y952020D02*
Y948920D01*
X143605D01*
G01X145938D02*
X145631Y948972D01*
X145363Y949178D01*
X145133Y949488D01*
X144980Y949850D01*
X144903Y950263D01*
Y950677D01*
X144980Y951090D01*
X145133Y951452D01*
X145363Y951762D01*
X145631Y951968D01*
X145938Y952020D01*
X146245Y951968D01*
X146513Y951762D01*
X146743Y951452D01*
X146896Y951090D01*
X146973Y950677D01*
Y950263D01*
X146896Y949850D01*
X146743Y949488D01*
X146513Y949178D01*
X146245Y948972D01*
X145938Y948920D01*
G01X149268Y950470D02*
X150035D01*
Y949540D01*
X149805Y949230D01*
X149536Y949023D01*
X149153Y948920D01*
X148770Y949023D01*
X148501Y949230D01*
X148271Y949540D01*
X148118Y949902D01*
X148041Y950315D01*
Y950677D01*
X148118Y950987D01*
X148271Y951348D01*
X148501Y951658D01*
X148731Y951865D01*
X149038Y952020D01*
X149306D01*
X149613Y951917D01*
X149843Y951710D01*
G01X152138Y948920D02*
X151831Y948972D01*
X151563Y949178D01*
X151333Y949488D01*
X151180Y949850D01*
X151103Y950263D01*
Y950677D01*
X151180Y951090D01*
X151333Y951452D01*
X151563Y951762D01*
X151831Y951968D01*
X152138Y952020D01*
X152445Y951968D01*
X152713Y951762D01*
X152943Y951452D01*
X153096Y951090D01*
X153173Y950677D01*
Y950263D01*
X153096Y949850D01*
X152943Y949488D01*
X152713Y949178D01*
X152445Y948972D01*
X152138Y948920D01*
G01X101436Y996631D02*
Y990431D01*
G01Y987631D02*
Y981431D01*
G01X110236Y987631D02*
X113436D01*
G01X110236Y981431D02*
Y987631D01*
G01X113436Y981431D02*
X110236D01*
G01X113436Y987631D02*
Y981431D01*
G01X102236Y987631D02*
X105436D01*
G01X102236Y981431D02*
Y987631D01*
G01X105436Y981431D02*
X102236D01*
G01X105436Y987631D02*
Y981431D01*
G01X114236Y987631D02*
X117436D01*
G01X114236Y981431D02*
Y987631D01*
G01X117436Y981431D02*
X114236D01*
G01X106236Y987631D02*
X109436D01*
G01X106236Y981431D02*
Y987631D01*
G01X109436Y981431D02*
X106236D01*
G01X109436Y987631D02*
Y981431D01*
G01X110236Y990431D02*
Y996631D01*
G01X113436Y990431D02*
X110236D01*
G01X113436Y996631D02*
Y990431D01*
G01X102236D02*
Y996631D01*
G01X105436Y990431D02*
X102236D01*
G01X105436Y996631D02*
Y990431D01*
G01X114236D02*
Y996631D01*
G01X117436Y990431D02*
X114236D01*
G01X106236D02*
Y996631D01*
G01X109436Y990431D02*
X106236D01*
G01X109436Y996631D02*
Y990431D01*
G01X101164Y1003053D02*
Y1007653D01*
G01X111364Y1003053D02*
X101164D01*
G01X111364Y1007653D02*
Y1003053D01*
G01X101164Y1007653D02*
X111364D01*
G01X115370Y1009265D02*
Y1019465D01*
G01X119970Y1009265D02*
X115370D01*
G01X110236Y996631D02*
X113436D01*
G01X102236D02*
X105436D01*
G01X114236D02*
X117436D01*
G01X106236D02*
X109436D01*
G01X104871Y1029963D02*
Y1025363D01*
G01X107958Y1022862D02*
X112558D01*
G01X107958Y1012662D02*
Y1022862D01*
G01X112558Y1012662D02*
X107958D01*
G01X112558Y1022862D02*
Y1012662D01*
G01X100758Y1011603D02*
X107158D01*
G01X100758Y1024483D02*
X107158D01*
G01D02*
Y1011603D01*
G01X100758D02*
Y1024483D01*
G01X115370Y1019465D02*
X119970D01*
G01X115370Y1021865D02*
Y1032065D01*
G01X119970Y1021865D02*
X115370D01*
G01X106704Y1025761D02*
Y1028961D01*
G01X112904Y1025761D02*
X106704D01*
G01X112904Y1028961D02*
Y1025761D01*
G01X115370Y1032065D02*
X119970D01*
G01X106704Y1028961D02*
X112904D01*
G01X113333Y1105408D02*
X123533D01*
G01X113333Y1100808D02*
Y1105408D01*
G01X123533Y1100808D02*
X113333D01*
G01X125154Y1106208D02*
X112274D01*
G01Y1112608D02*
Y1106208D01*
G01X103724Y1102002D02*
Y1112202D01*
G01X108324Y1102002D02*
X103724D01*
G01X108324Y1112202D02*
Y1102002D01*
G01X113333Y1118008D02*
X123533D01*
G01X113333Y1113408D02*
Y1118008D01*
G01X123533Y1113408D02*
X113333D01*
G01X112274Y1112608D02*
X125154D01*
G01Y1118808D02*
X112274D01*
G01Y1125208D02*
Y1118808D01*
G01X103724Y1112202D02*
X108324D01*
G01X103724Y1114602D02*
Y1124802D01*
G01X108324Y1114602D02*
X103724D01*
G01X108324Y1124802D02*
Y1114602D01*
G01X113333Y1130608D02*
X123533D01*
G01X113333Y1126008D02*
Y1130608D01*
G01X123533Y1126008D02*
X113333D01*
G01Y1138608D02*
Y1143208D01*
G01X123533Y1138608D02*
X113333D01*
G01X112274Y1125208D02*
X125154D01*
G01X112274Y1137808D02*
X125154D01*
G01Y1131408D02*
X112274D01*
G01Y1137808D02*
Y1131408D01*
G01X103724Y1124802D02*
X108324D01*
G01X103724Y1139802D02*
Y1150002D01*
G01X108324Y1139802D02*
X103724D01*
G01X108324Y1150002D02*
Y1139802D01*
G01X103724Y1137402D02*
X108324D01*
G01X103724Y1127202D02*
Y1137402D01*
G01X108324Y1127202D02*
X103724D01*
G01X108324Y1137402D02*
Y1127202D01*
G01X113333Y1143208D02*
X123533D01*
G01X113333Y1155808D02*
X123533D01*
G01X113333Y1151208D02*
Y1155808D01*
G01X123533Y1151208D02*
X113333D01*
G01X112274Y1150408D02*
X125154D01*
G01Y1144008D02*
X112274D01*
G01Y1150408D02*
Y1144008D01*
G01X103724Y1150002D02*
X108324D01*
G01X103724Y1152402D02*
Y1162602D01*
G01X108324Y1152402D02*
X103724D01*
G01X108324Y1162602D02*
Y1152402D01*
G01X113333Y1168408D02*
X123533D01*
G01X113333Y1163808D02*
Y1168408D01*
G01X123533Y1163808D02*
X113333D01*
G01X112274Y1163008D02*
X125154D01*
G01Y1156608D02*
X112274D01*
G01Y1163008D02*
Y1156608D01*
G01X125154Y1169208D02*
X112274D01*
G01Y1175608D02*
Y1169208D01*
G01X103724Y1162602D02*
X108324D01*
G01X103724Y1165002D02*
Y1175202D01*
G01X108324Y1165002D02*
X103724D01*
G01X108324Y1175202D02*
Y1165002D01*
G01X113333Y1181008D02*
X123533D01*
G01X113333Y1176408D02*
Y1181008D01*
G01X123533Y1176408D02*
X113333D01*
G01X112274Y1175608D02*
X125154D01*
G01X112274Y1188208D02*
X125154D01*
G01Y1181808D02*
X112274D01*
G01Y1188208D02*
Y1181808D01*
G01X103724Y1187802D02*
X108324D01*
G01X103724Y1177602D02*
Y1187802D01*
G01X108324Y1177602D02*
X103724D01*
G01X108324Y1187802D02*
Y1177602D01*
G01X103724Y1175202D02*
X108324D01*
G01X112984Y1202278D02*
X117368Y1206662D01*
G01X115246Y1200016D02*
X112984Y1202278D01*
G01X119630Y1204400D02*
X115246Y1200016D01*
G01X112418Y1202844D02*
X110156Y1205106D01*
G01X116802Y1207228D02*
X112418Y1202844D01*
G01X110156Y1205106D02*
X114540Y1209490D01*
G01X109589Y1205673D02*
X107327Y1207935D01*
G01X113973Y1210057D02*
X109589Y1205673D01*
G01X111711Y1212319D02*
X113973Y1210057D01*
G01X107327Y1207935D02*
X111711Y1212319D01*
G01X114540Y1209490D02*
X116802Y1207228D01*
G01X108883Y1215147D02*
X111145Y1212885D01*
G01X104499Y1210763D02*
X108883Y1215147D01*
G01X106761Y1208501D02*
X104499Y1210763D01*
G01X111145Y1212885D02*
X106761Y1208501D01*
G01X103579Y1211683D02*
X101317Y1213945D01*
G01X107963Y1216067D02*
X103579Y1211683D01*
G01X105701Y1218329D02*
X107963Y1216067D01*
G01X101317Y1213945D02*
X105701Y1218329D01*
G01X108001Y1228126D02*
X111201D01*
G01X108001Y1221926D02*
Y1228126D01*
G01X111201Y1221926D02*
X108001D01*
G01X111201Y1228126D02*
Y1221926D01*
G01X104001Y1228126D02*
X107201D01*
G01X104001Y1221926D02*
Y1228126D01*
G01X107201Y1221926D02*
X104001D01*
G01X107201Y1228126D02*
Y1221926D01*
G01X115818Y1223377D02*
X120202Y1227761D01*
G01X118080Y1221115D02*
X115818Y1223377D01*
G01X115253Y1223943D02*
X112991Y1226205D01*
G01X119637Y1228327D02*
X115253Y1223943D01*
G01X112991Y1226205D02*
X117375Y1230589D01*
G01X104961Y1677520D02*
Y1436969D01*
G01D02*
X194331D01*
G01X104961Y1647993D02*
X194331D01*
G01Y1677520D02*
X104961D01*
G01X129860Y96067D02*
Y99267D01*
G01X136060Y96067D02*
X129860D01*
G01Y99267D02*
X136060D01*
G01X126599Y122172D02*
Y110172D01*
G01X120599D02*
Y122172D01*
G01X126599Y110172D02*
X120599D01*
G01X131885Y108095D02*
Y104895D01*
G01X125685Y108095D02*
X131885D01*
G01X125685Y104895D02*
Y108095D01*
G01X131885Y104895D02*
X125685D01*
G01X117982Y109424D02*
X121182D01*
G01X117982Y103224D02*
Y109424D01*
G01X121182Y103224D02*
X117982D01*
G01X121182Y109424D02*
Y103224D01*
G01X125676Y100895D02*
Y104095D01*
G01X131876Y100895D02*
X125676D01*
G01X131876Y104095D02*
Y100895D01*
G01X125676Y104095D02*
X131876D01*
G01X132733Y108086D02*
X135933D01*
G01X132733Y101886D02*
Y108086D01*
G01X135933Y101886D02*
X132733D01*
G01X117182Y109424D02*
Y103224D01*
G01X118198Y123508D02*
Y111734D01*
G01X120599Y122172D02*
X126599D01*
G01X119207Y132423D02*
Y126223D01*
G01X123261Y126228D02*
X120061D01*
G01X123261Y132428D02*
Y126228D01*
G01X120061Y132428D02*
X123261D01*
G01X120061Y126228D02*
Y132428D01*
G01X123440Y141337D02*
X120240D01*
G01X123440Y147537D02*
Y141337D01*
G01X120240Y147537D02*
X123440D01*
G01X120240Y141337D02*
Y147537D01*
G01X120105Y133238D02*
Y136438D01*
G01X126305Y133238D02*
X120105D01*
G01X126305Y136438D02*
Y133238D01*
G01X120105Y136438D02*
X126305D01*
G01X120105Y137238D02*
Y140438D01*
G01X126305Y137238D02*
X120105D01*
G01X126305Y140438D02*
Y137238D01*
G01X120105Y140438D02*
X126305D01*
G01X126651Y148437D02*
X129851D01*
G01X126651Y142237D02*
Y148437D01*
G01X129851Y142237D02*
X126651D01*
G01X129851Y148437D02*
Y142237D01*
G01X117486Y134995D02*
Y144395D01*
G01X129100Y152907D02*
X131322D01*
X131787Y153060D01*
X132097Y153367D01*
X132200Y153750D01*
X132097Y154133D01*
X131787Y154440D01*
X131322Y154593D01*
X129100D01*
G01X131580Y156007D02*
X131942Y156237D01*
X132148Y156543D01*
X132200Y156888D01*
X132148Y157195D01*
X131890Y157502D01*
X131580Y157693D01*
X131270Y157732D01*
X130908Y157655D01*
X130650Y157387D01*
X130547Y157118D01*
Y156773D01*
G01Y157118D02*
X130392Y157348D01*
X130133Y157540D01*
X129823Y157617D01*
X129513Y157540D01*
X129255Y157348D01*
X129100Y157003D01*
X129152Y156658D01*
X129358Y156313D01*
G01X130908Y159222D02*
X130547Y159490D01*
X130340Y159720D01*
X130237Y160027D01*
X130340Y160295D01*
X130547Y160487D01*
X130857Y160640D01*
X131218Y160678D01*
X131528Y160640D01*
X131838Y160487D01*
X132097Y160257D01*
X132200Y159988D01*
X132097Y159682D01*
X131787Y159413D01*
X131322Y159260D01*
X130805Y159222D01*
X130133Y159298D01*
X129772Y159413D01*
X129410Y159605D01*
X129152Y159873D01*
X129100Y160142D01*
X129203Y160410D01*
X129462Y160602D01*
G01X132200Y163510D02*
X129100D01*
X131322Y162092D01*
Y164008D01*
G01X127787Y165304D02*
Y149950D01*
G01X130607Y197645D02*
X118607D01*
G01X130607Y203645D02*
Y197645D01*
G01X118607D02*
Y203645D01*
G01D02*
X130607D01*
G01X117784Y216506D02*
Y204506D01*
G01X128560Y208464D02*
Y205264D01*
G01X122360Y208464D02*
X128560D01*
G01X122360Y205264D02*
Y208464D01*
G01X128560Y205264D02*
X122360D01*
G01X118584Y208306D02*
Y214506D01*
G01X121784Y208306D02*
X118584D01*
G01X121784Y214506D02*
Y208306D01*
G01X123390Y226801D02*
X135594D01*
Y211497D01*
X123390D01*
Y226801D01*
G01X118584Y214506D02*
X121784D01*
G01X118950Y245521D02*
Y254969D01*
G01X129786Y245521D02*
X118950D01*
G01X129786Y254969D02*
Y245521D01*
G01X122526Y231334D02*
X119326D01*
G01X122526Y237534D02*
Y231334D01*
G01X119326Y237534D02*
X122526D01*
G01X119326Y231334D02*
Y237534D01*
G01X128053Y231446D02*
X124853D01*
G01X128053Y237646D02*
Y231446D01*
G01X124853Y237646D02*
X128053D01*
G01X124853Y231446D02*
Y237646D01*
G01X120752Y243678D02*
Y240478D01*
G01X131928Y231434D02*
X128728D01*
G01X131928Y237634D02*
Y231434D01*
G01X128728Y237634D02*
X131928D01*
G01X128728Y231434D02*
Y237634D01*
G01X132963Y237659D02*
X136163D01*
G01X132963Y231459D02*
Y237659D01*
G01X136163Y231459D02*
X132963D01*
G01X131589Y240081D02*
Y243281D01*
G01X137789Y240081D02*
X131589D01*
G01Y243281D02*
X137789D01*
G01X127731Y243678D02*
Y240478D01*
G01X121531Y243678D02*
X127731D01*
G01X121531Y240478D02*
Y243678D01*
G01X127731Y240478D02*
X121531D01*
G01X126368Y254969D02*
X129786D01*
G01X124368Y253245D02*
X126368Y254969D01*
G01X122368D02*
X124368Y253245D01*
G01X118950Y254969D02*
X122368D01*
G01X131193Y252199D02*
X137393D01*
G01X131193Y248999D02*
Y252199D01*
G01X137393Y248999D02*
X131193D01*
G01X125635Y450181D02*
X128835D01*
G01X125635Y443981D02*
Y450181D01*
G01X128835Y443981D02*
X125635D01*
G01X128835Y450181D02*
Y443981D01*
G01Y450981D02*
X125635D01*
G01X128835Y457181D02*
Y450981D01*
G01X125635Y457181D02*
X128835D01*
G01X125635Y450981D02*
Y457181D01*
G01X130496Y447404D02*
Y462758D01*
G01X143174Y447404D02*
X130496D01*
G01X129607Y467300D02*
Y465078D01*
X129760Y464613D01*
X130067Y464303D01*
X130450Y464200D01*
X130833Y464303D01*
X131140Y464613D01*
X131293Y465078D01*
Y467300D01*
G01X132898Y464562D02*
X133167Y464303D01*
X133473Y464200D01*
X133780Y464303D01*
X134048Y464613D01*
X134240Y465078D01*
X134317Y465543D01*
Y466112D01*
X134240Y466577D01*
X134048Y466990D01*
X133818Y467197D01*
X133550Y467300D01*
X133243Y467197D01*
X133013Y466990D01*
X132860Y466680D01*
X132783Y466267D01*
X132860Y465905D01*
X133052Y465543D01*
X133282Y465337D01*
X133550Y465285D01*
X133857Y465388D01*
X134087Y465647D01*
X134317Y466112D01*
G01X130693Y462758D02*
X143174D01*
G01X127107Y917913D02*
Y857677D01*
G01X118236Y987631D02*
X121436D01*
G01X118236Y981431D02*
Y987631D01*
G01X121436Y981431D02*
X118236D01*
G01X121436Y987631D02*
Y981431D01*
G01X122236Y987631D02*
X125436D01*
G01X122236Y981431D02*
Y987631D01*
G01X125436Y981431D02*
X122236D01*
G01X125436Y987631D02*
Y981431D01*
G01X126236Y987631D02*
X129436D01*
G01X126236Y981431D02*
Y987631D01*
G01X129436Y981431D02*
X126236D01*
G01X129436Y987631D02*
Y981431D01*
G01X118236Y990431D02*
Y996631D01*
G01X121436Y990431D02*
X118236D01*
G01X121436Y996631D02*
Y990431D01*
G01X122236D02*
Y996631D01*
G01X125436Y990431D02*
X122236D01*
G01X125436Y996631D02*
Y990431D01*
G01X126236D02*
Y996631D01*
G01X129436Y990431D02*
X126236D01*
G01X129436Y996631D02*
Y990431D01*
G01X130236Y987631D02*
X133436D01*
G01X130236Y981431D02*
Y987631D01*
G01X133436Y981431D02*
X130236D01*
G01Y990431D02*
Y996631D01*
G01X133436Y990431D02*
X130236D01*
G01X117436Y987631D02*
Y981431D01*
G01Y996631D02*
Y990431D01*
G01X124979Y1008071D02*
Y1012671D01*
G01X135179Y1008071D02*
X124979D01*
G01X119970Y1019465D02*
Y1009265D01*
G01X118236Y996631D02*
X121436D01*
G01X122236D02*
X125436D01*
G01X126236D02*
X129436D01*
G01X130236D02*
X133436D01*
G01X124979Y1012671D02*
X135179D01*
G01X124979Y1025271D02*
X135179D01*
G01X124979Y1020671D02*
Y1025271D01*
G01X135179Y1020671D02*
X124979D01*
G01X123920Y1032471D02*
Y1026071D01*
G01X136800D02*
X123920D01*
G01Y1019871D02*
Y1013471D01*
G01X136800D02*
X123920D01*
G01Y1019871D02*
X136800D01*
G01X119970Y1032065D02*
Y1021865D01*
G01X123920Y1032471D02*
X136800D01*
G01X123533Y1105408D02*
Y1100808D01*
G01X125154Y1112608D02*
Y1106208D01*
G01X126004Y1107208D02*
X129204D01*
G01X126004Y1101008D02*
Y1107208D01*
G01X129204Y1101008D02*
X126004D01*
G01X129204Y1107208D02*
Y1101008D01*
G01X125954Y1108008D02*
Y1112608D01*
G01X136154Y1108008D02*
X125954D01*
G01Y1112608D02*
X136154D01*
G01X125954Y1120608D02*
Y1125208D01*
G01X136154Y1120608D02*
X125954D01*
G01X123533Y1118008D02*
Y1113408D01*
G01X125154Y1125208D02*
Y1118808D01*
G01X126004Y1119808D02*
X129204D01*
G01X126004Y1113608D02*
Y1119808D01*
G01X129204Y1113608D02*
X126004D01*
G01X129204Y1119808D02*
Y1113608D01*
G01X125954Y1125208D02*
X136154D01*
G01X125954Y1133208D02*
Y1137808D01*
G01X136154Y1133208D02*
X125954D01*
G01Y1137808D02*
X136154D01*
G01X123533Y1130608D02*
Y1126008D01*
G01Y1143208D02*
Y1138608D01*
G01X125154Y1137808D02*
Y1131408D01*
G01X126004Y1138808D02*
Y1145008D01*
G01X129204Y1138808D02*
X126004D01*
G01X129204Y1145008D02*
Y1138808D01*
G01X126004Y1132408D02*
X129204D01*
G01X126004Y1126208D02*
Y1132408D01*
G01X129204Y1126208D02*
X126004D01*
G01X129204Y1132408D02*
Y1126208D01*
G01X125954Y1145808D02*
Y1150408D01*
G01X136154Y1145808D02*
X125954D01*
G01Y1150408D02*
X136154D01*
G01X123533Y1155808D02*
Y1151208D01*
G01X125154Y1150408D02*
Y1144008D01*
G01X126004Y1145008D02*
X129204D01*
G01X126004Y1151408D02*
Y1157608D01*
G01X129204Y1151408D02*
X126004D01*
G01X129204Y1157608D02*
Y1151408D01*
G01X125954Y1158408D02*
Y1163008D01*
G01X136154Y1158408D02*
X125954D01*
G01Y1163008D02*
X136154D01*
G01X125954Y1171008D02*
Y1175608D01*
G01X136154Y1171008D02*
X125954D01*
G01X123533Y1168408D02*
Y1163808D01*
G01X125154Y1163008D02*
Y1156608D01*
G01Y1175608D02*
Y1169208D01*
G01X126004Y1157608D02*
X129204D01*
G01X126004Y1170208D02*
X129204D01*
G01X126004Y1164008D02*
Y1170208D01*
G01X129204Y1164008D02*
X126004D01*
G01X129204Y1170208D02*
Y1164008D01*
G01X125954Y1175608D02*
X136154D01*
G01X125954Y1183608D02*
Y1188208D01*
G01X136154Y1183608D02*
X125954D01*
G01Y1188208D02*
X136154D01*
G01X123533Y1181008D02*
Y1176408D01*
G01X125154Y1188208D02*
Y1181808D01*
G01X126004Y1182808D02*
X129204D01*
G01X126004Y1176608D02*
Y1182808D01*
G01X129204Y1176608D02*
X126004D01*
G01X129204Y1182808D02*
Y1176608D01*
G01X117368Y1206662D02*
X119630Y1204400D01*
G01X131516Y1216448D02*
X133778Y1214186D01*
G01X127132Y1212064D02*
X131516Y1216448D01*
G01X129394Y1209802D02*
X127132Y1212064D01*
G01X133778Y1214186D02*
X129394Y1209802D01*
G01X123737Y1215459D02*
X121475Y1217721D01*
G01X128121Y1219843D02*
X123737Y1215459D01*
G01X125859Y1222105D02*
X128121Y1219843D01*
G01X121475Y1217721D02*
X125859Y1222105D01*
G01X128687Y1219276D02*
X130949Y1217014D01*
G01X124303Y1214892D02*
X128687Y1219276D01*
G01X126565Y1212630D02*
X124303Y1214892D01*
G01X130949Y1217014D02*
X126565Y1212630D01*
G01X118645Y1220549D02*
X123029Y1224933D01*
G01X120907Y1218287D02*
X118645Y1220549D01*
G01X125291Y1222671D02*
X120907Y1218287D01*
G01X122464Y1225499D02*
X118080Y1221115D01*
G01X132223Y1206974D02*
X129961Y1209236D01*
G01X136607Y1211358D02*
X132223Y1206974D01*
G01X129961Y1209236D02*
X134345Y1213620D01*
G01X123029Y1224933D02*
X125291Y1222671D01*
G01X120202Y1227761D02*
X122464Y1225499D01*
G01X117375Y1230589D02*
X119637Y1228327D01*
G01X141003Y57756D02*
Y111606D01*
G01X141299Y58150D02*
Y111606D01*
G01X138980Y58733D02*
X139290Y58925D01*
X139497Y59155D01*
X139600Y59423D01*
X139497Y59730D01*
X139290Y59960D01*
X138980Y60190D01*
X138567Y60267D01*
X136500D01*
G01X138980Y61757D02*
X139342Y61987D01*
X139548Y62293D01*
X139600Y62638D01*
X139548Y62945D01*
X139290Y63252D01*
X138980Y63443D01*
X138670Y63482D01*
X138308Y63405D01*
X138050Y63137D01*
X137947Y62868D01*
Y62523D01*
G01Y62868D02*
X137792Y63098D01*
X137533Y63290D01*
X137223Y63367D01*
X136913Y63290D01*
X136655Y63098D01*
X136500Y62753D01*
X136552Y62408D01*
X136758Y62063D01*
G01X139600Y65700D02*
X136500D01*
X137120Y65240D01*
G01X139600D02*
Y66160D01*
G01X147384Y57756D02*
X141003D01*
G01X146979Y58150D02*
X141299D01*
G01X136060Y99267D02*
Y96067D01*
G01X141299Y118848D02*
Y114048D01*
G01X141003Y118848D02*
Y114048D01*
G01X135933Y108086D02*
Y101886D01*
G01X141299Y132607D02*
Y128340D01*
G01X141003Y132607D02*
Y128340D01*
G01Y125781D02*
Y121219D01*
G01X141299Y125781D02*
Y121219D01*
G01Y152756D02*
Y135341D01*
G01X141003Y153150D02*
Y135341D01*
G01Y153150D02*
X147384D01*
G01X141299Y152756D02*
X146979D01*
G01X144730Y189535D02*
X142304D01*
G01X141190Y195583D02*
Y184087D01*
G01X143324Y213965D02*
X140224D01*
Y214885D01*
X140379Y215192D01*
X140741Y215422D01*
X141154Y215499D01*
X141567Y215422D01*
X141877Y215230D01*
X142032Y214885D01*
Y213965D01*
G01X140224Y216989D02*
X142446D01*
X142911Y217142D01*
X143221Y217449D01*
X143324Y217832D01*
X143221Y218215D01*
X142911Y218522D01*
X142446Y218675D01*
X140224D01*
G01X142859Y220089D02*
X143117Y220319D01*
X143272Y220587D01*
X143324Y220932D01*
X143221Y221277D01*
X143014Y221545D01*
X142652Y221737D01*
X142239Y221775D01*
X141826Y221699D01*
X141567Y221507D01*
X141361Y221239D01*
X141309Y220970D01*
X141361Y220702D01*
X141567Y220357D01*
X140224Y220472D01*
Y221507D01*
G01X142032Y223304D02*
X141671Y223572D01*
X141464Y223802D01*
X141361Y224109D01*
X141464Y224377D01*
X141671Y224569D01*
X141981Y224722D01*
X142342Y224760D01*
X142652Y224722D01*
X142962Y224569D01*
X143221Y224339D01*
X143324Y224070D01*
X143221Y223764D01*
X142911Y223495D01*
X142446Y223342D01*
X141929Y223304D01*
X141257Y223380D01*
X140896Y223495D01*
X140534Y223687D01*
X140276Y223955D01*
X140224Y224224D01*
X140327Y224492D01*
X140586Y224684D01*
G01X140163Y231459D02*
X136963D01*
G01X140163Y237659D02*
Y231459D01*
G01X136963Y237659D02*
X140163D01*
G01X136963Y231459D02*
Y237659D01*
G01X136163D02*
Y231459D01*
G01X137789Y243281D02*
Y240081D01*
G01X137393Y252199D02*
Y248999D01*
G01X148000Y450700D02*
X144800D01*
G01X148000Y456900D02*
Y450700D01*
G01X144800Y456900D02*
X148000D01*
G01X144800Y450700D02*
Y456900D01*
G01X143174Y462758D02*
Y447404D01*
G01X137371Y537291D02*
Y543491D01*
G01X140571Y537291D02*
X137371D01*
G01X140571Y543491D02*
Y537291D01*
G01X141361Y537250D02*
Y543450D01*
G01X144561Y537250D02*
X141361D01*
G01X144561Y543450D02*
Y537250D01*
G01X137371Y543491D02*
X140571D01*
G01X141361Y543450D02*
X144561D01*
G01X148788Y556155D02*
Y552955D01*
G01X142588D02*
Y556155D01*
G01X148788Y552955D02*
X142588D01*
G01Y556155D02*
X148788D01*
G01Y560155D02*
Y556955D01*
G01X142588Y560155D02*
X148788D01*
G01X142588Y556955D02*
Y560155D01*
G01X148788Y556955D02*
X142588D01*
G01X148788Y564155D02*
Y560955D01*
G01X142588Y564155D02*
X148788D01*
G01X142588Y560955D02*
Y564155D01*
G01X148788Y560955D02*
X142588D01*
G01X142882Y576556D02*
Y588556D01*
G01X148882Y576556D02*
X142882D01*
G01X148882Y588556D02*
Y576556D01*
G01X142882Y588556D02*
X148882D01*
G01X148868Y597188D02*
X155068D01*
G01X148868Y593988D02*
Y597188D01*
G01X155068Y593988D02*
X148868D01*
G01Y593188D02*
X155068D01*
G01X148868Y589988D02*
Y593188D01*
G01X155068Y589988D02*
X148868D01*
G01X148900Y602000D02*
Y605200D01*
G01X155100Y602000D02*
X148900D01*
G01X148868Y601188D02*
X155068D01*
G01X148868Y597988D02*
Y601188D01*
G01X155068Y597988D02*
X148868D01*
G01X148900Y605200D02*
X155100D01*
G01X148900Y613200D02*
X155100D01*
G01X148900Y610000D02*
Y613200D01*
G01X155100Y610000D02*
X148900D01*
G01Y618000D02*
Y621200D01*
G01X155100Y618000D02*
X148900D01*
G01X148868Y609188D02*
X155068D01*
G01X148868Y605988D02*
Y609188D01*
G01X155068Y605988D02*
X148868D01*
G01X148900Y617200D02*
X155100D01*
G01X148900Y614000D02*
Y617200D01*
G01X155100Y614000D02*
X148900D01*
G01Y621200D02*
X155100D01*
G01X148900Y636369D02*
Y639569D01*
G01X155100Y636369D02*
X148900D01*
G01Y629821D02*
Y633021D01*
G01X155100Y629821D02*
X148900D01*
G01Y633021D02*
X155100D01*
G01X148900Y625200D02*
X155100D01*
G01X148900Y622000D02*
Y625200D01*
G01X155100Y622000D02*
X148900D01*
G01Y629200D02*
X155100D01*
G01X148900Y626000D02*
Y629200D01*
G01X155100Y626000D02*
X148900D01*
G01Y639569D02*
X155100D01*
G01X148900Y643574D02*
X155100D01*
G01X148900Y640374D02*
Y643574D01*
G01X155100Y640374D02*
X148900D01*
G01X142236Y987631D02*
X145436D01*
G01X142236Y981431D02*
Y987631D01*
G01X145436Y981431D02*
X142236D01*
G01X145436Y987631D02*
Y981431D01*
G01X146236Y987631D02*
X149436D01*
G01X146236Y981431D02*
Y987631D01*
G01X149436Y981431D02*
X146236D01*
G01X138236Y987631D02*
X141436D01*
G01X138236Y981431D02*
Y987631D01*
G01X141436Y981431D02*
X138236D01*
G01X141436Y987631D02*
Y981431D01*
G01X142236Y990431D02*
Y996631D01*
G01X145436Y990431D02*
X142236D01*
G01X145436Y996631D02*
Y990431D01*
G01X146236D02*
Y996631D01*
G01X149436Y990431D02*
X146236D01*
G01X138236D02*
Y996631D01*
G01X141436Y990431D02*
X138236D01*
G01X141436Y996631D02*
Y990431D01*
G01X133436Y987631D02*
Y981431D01*
G01X134236Y987631D02*
X137436D01*
G01X134236Y981431D02*
Y987631D01*
G01X137436Y981431D02*
X134236D01*
G01X137436Y987631D02*
Y981431D01*
G01X133436Y996631D02*
Y990431D01*
G01X134236D02*
Y996631D01*
G01X137436Y990431D02*
X134236D01*
G01X137436Y996631D02*
Y990431D01*
G01X135179Y1012671D02*
Y1008071D01*
G01X142236Y996631D02*
X145436D01*
G01X146236D02*
X149436D01*
G01X138236D02*
X141436D01*
G01X137650Y1008271D02*
Y1014471D01*
G01X140850Y1008271D02*
X137650D01*
G01X140850Y1014471D02*
Y1008271D01*
G01X134236Y996631D02*
X137436D01*
G01X137600Y1015271D02*
Y1019871D01*
G01X147800Y1015271D02*
X137600D01*
G01X147800Y1019871D02*
Y1015271D01*
G01X137600Y1019871D02*
X147800D01*
G01X135179Y1025271D02*
Y1020671D01*
G01X136800Y1032471D02*
Y1026071D01*
G01Y1019871D02*
Y1013471D01*
G01X137650Y1014471D02*
X140850D01*
G01X137650Y1020871D02*
Y1027071D01*
G01X140850Y1020871D02*
X137650D01*
G01X140850Y1027071D02*
Y1020871D01*
G01X137600Y1027871D02*
Y1032471D01*
G01X147800Y1027871D02*
X137600D01*
G01X147800Y1032471D02*
Y1027871D01*
G01X137600Y1032471D02*
X147800D01*
G01X137650Y1027071D02*
X140850D01*
G01X133984Y1035337D02*
Y1038437D01*
G01X135594D02*
Y1035337D01*
G01Y1036887D02*
X133984D01*
G01X137237Y1035699D02*
X137506Y1035440D01*
X137812Y1035337D01*
X138119Y1035440D01*
X138387Y1035750D01*
X138579Y1036215D01*
X138656Y1036680D01*
Y1037249D01*
X138579Y1037714D01*
X138387Y1038127D01*
X138157Y1038334D01*
X137889Y1038437D01*
X137582Y1038334D01*
X137352Y1038127D01*
X137199Y1037817D01*
X137122Y1037404D01*
X137199Y1037042D01*
X137391Y1036680D01*
X137621Y1036474D01*
X137889Y1036422D01*
X138196Y1036525D01*
X138426Y1036784D01*
X138656Y1037249D01*
G01X141449Y1035337D02*
Y1038437D01*
X140031Y1036215D01*
X141947D01*
G01X141338Y1071456D02*
Y1089133D01*
G01X150039Y1071456D02*
X141338D01*
G01X148132Y1068976D02*
G02X148227Y1066535I-31401J-2444D01*
G01X141338Y1258464D02*
Y1089133D01*
G01X136154Y1112608D02*
Y1108008D01*
G01Y1125208D02*
Y1120608D01*
G01Y1137808D02*
Y1133208D01*
G01Y1150408D02*
Y1145808D01*
G01Y1163008D02*
Y1158408D01*
G01Y1175608D02*
Y1171008D01*
G01Y1188208D02*
Y1183608D01*
G01X134345Y1213620D02*
X136607Y1211358D01*
G01X328346Y1258464D02*
X141338D01*
G01X165511Y58150D02*
Y104520D01*
G01X165807Y57756D02*
X159426D01*
G01X165511Y58150D02*
X159831D01*
G01X165511Y111507D02*
Y107060D01*
G01Y118680D02*
Y114087D01*
G01Y132859D02*
Y128325D01*
G01Y125844D02*
Y121329D01*
G01Y152756D02*
Y135490D01*
G01X154457Y156615D02*
X155204Y155990D01*
X156044Y155615D01*
X156790D01*
X157537Y155990D01*
X158097Y156615D01*
X158377Y157490D01*
X158190Y158365D01*
X157724Y159115D01*
X156884Y159615D01*
X155764Y159865D01*
X155110Y160365D01*
X154830Y161240D01*
X155017Y162115D01*
X155484Y162740D01*
X156137Y163115D01*
X156790D01*
X157444Y162865D01*
X158004Y162240D01*
G01X161957Y156615D02*
X162704Y155990D01*
X163544Y155615D01*
X164290D01*
X165037Y155990D01*
X165597Y156615D01*
X165877Y157490D01*
X165690Y158365D01*
X165224Y159115D01*
X164384Y159615D01*
X163264Y159865D01*
X162610Y160365D01*
X162330Y161240D01*
X162517Y162115D01*
X162984Y162740D01*
X163637Y163115D01*
X164290D01*
X164944Y162865D01*
X165504Y162240D01*
G01X169364Y155615D02*
Y163115D01*
X171230D01*
X171977Y162740D01*
X172537Y162240D01*
X173004Y161490D01*
X173377Y160615D01*
X173470Y159365D01*
X173377Y158115D01*
X173004Y157240D01*
X172537Y156490D01*
X171977Y155990D01*
X171230Y155615D01*
X169364D01*
G01X178917D02*
Y163115D01*
X177797Y161615D01*
G01Y155615D02*
X180037D01*
G01X157907Y164436D02*
X172707D01*
G01X157907Y195440D02*
Y164436D01*
G01X159426Y153150D02*
X165807D01*
G01X159831Y152756D02*
X165511D01*
G01X172707Y195440D02*
X157907D01*
G01X161910Y199912D02*
Y202338D01*
G01X154800Y212783D02*
X151700D01*
Y213703D01*
X151855Y214010D01*
X152217Y214240D01*
X152630Y214317D01*
X153043Y214240D01*
X153353Y214048D01*
X153508Y213703D01*
Y212783D01*
G01X154800Y215807D02*
X151700D01*
Y216573D01*
X151855Y216880D01*
X152062Y217110D01*
X152372Y217302D01*
X152733Y217455D01*
X153250Y217493D01*
X153767Y217455D01*
X154128Y217302D01*
X154438Y217110D01*
X154645Y216880D01*
X154800Y216573D01*
Y215807D01*
G01X152217Y219022D02*
X151907Y219252D01*
X151752Y219520D01*
X151700Y219827D01*
X151803Y220210D01*
X152062Y220478D01*
X152372Y220555D01*
X152682Y220517D01*
X152940Y220363D01*
X153457Y219597D01*
X153818Y219252D01*
X154335Y219022D01*
X154800Y218945D01*
Y220555D01*
G01X153508Y222122D02*
X153147Y222390D01*
X152940Y222620D01*
X152837Y222927D01*
X152940Y223195D01*
X153147Y223387D01*
X153457Y223540D01*
X153818Y223578D01*
X154128Y223540D01*
X154438Y223387D01*
X154697Y223157D01*
X154800Y222888D01*
X154697Y222582D01*
X154387Y222313D01*
X153922Y222160D01*
X153405Y222122D01*
X152733Y222198D01*
X152372Y222313D01*
X152010Y222505D01*
X151752Y222773D01*
X151700Y223042D01*
X151803Y223310D01*
X152062Y223502D01*
G01X167958Y203452D02*
X156462D01*
G01D02*
Y233011D01*
G01X161810Y236652D02*
Y234412D01*
G01X163435Y235625D02*
X160185D01*
G01X156462Y233011D02*
X167958D01*
G01X161679Y259204D02*
Y261630D01*
G01X167727Y262744D02*
X156231D01*
G01D02*
Y292303D01*
G01X155000Y264183D02*
X151900D01*
Y265103D01*
X152055Y265410D01*
X152417Y265640D01*
X152830Y265717D01*
X153243Y265640D01*
X153553Y265448D01*
X153708Y265103D01*
Y264183D01*
G01X155000Y267207D02*
X151900D01*
Y267973D01*
X152055Y268280D01*
X152262Y268510D01*
X152572Y268702D01*
X152933Y268855D01*
X153450Y268893D01*
X153967Y268855D01*
X154328Y268702D01*
X154638Y268510D01*
X154845Y268280D01*
X155000Y267973D01*
Y267207D01*
G01Y271150D02*
X154948Y271418D01*
X154793Y271725D01*
X154535Y271917D01*
X154173Y271993D01*
X153812Y271917D01*
X153502Y271687D01*
X153347Y271342D01*
Y270958D01*
X153243Y270728D01*
X152985Y270537D01*
X152623Y270460D01*
X152262Y270575D01*
X152003Y270843D01*
X151900Y271150D01*
X152003Y271457D01*
X152262Y271725D01*
X152623Y271840D01*
X152985Y271763D01*
X153243Y271572D01*
X153347Y271342D01*
Y270958D01*
X153502Y270613D01*
X153812Y270383D01*
X154173Y270307D01*
X154535Y270383D01*
X154793Y270575D01*
X154948Y270882D01*
X155000Y271150D01*
G01Y274173D02*
X154328Y274250D01*
X153760Y274365D01*
X153243Y274518D01*
X152675Y274710D01*
X151900Y275017D01*
Y273483D01*
G01X161895Y297771D02*
Y295531D01*
G01X163520Y296744D02*
X160270D01*
G01X156231Y292303D02*
X167727D01*
G01X166180Y366583D02*
X166490Y366775D01*
X166697Y367005D01*
X166800Y367273D01*
X166697Y367580D01*
X166490Y367810D01*
X166180Y368040D01*
X165767Y368117D01*
X163700D01*
G01X164217Y369722D02*
X163907Y369952D01*
X163752Y370220D01*
X163700Y370527D01*
X163803Y370910D01*
X164062Y371178D01*
X164372Y371255D01*
X164682Y371217D01*
X164940Y371063D01*
X165457Y370297D01*
X165818Y369952D01*
X166335Y369722D01*
X166800Y369645D01*
Y371255D01*
G01X163700Y373550D02*
X163803Y373243D01*
X164062Y373013D01*
X164372Y372860D01*
X164785Y372745D01*
X165250Y372707D01*
X165715Y372745D01*
X166128Y372860D01*
X166438Y373013D01*
X166697Y373243D01*
X166800Y373550D01*
X166697Y373857D01*
X166438Y374087D01*
X166128Y374240D01*
X165715Y374355D01*
X165250Y374393D01*
X164785Y374355D01*
X164372Y374240D01*
X164062Y374087D01*
X163803Y373857D01*
X163700Y373550D01*
G01X149500Y377000D02*
Y380200D01*
G01X155700Y377000D02*
X149500D01*
G01X155700Y380200D02*
Y377000D01*
G01X149500Y380200D02*
X155700D01*
G01Y384200D02*
Y381000D01*
G01X149500Y384200D02*
X155700D01*
G01X149500Y381000D02*
Y384200D01*
G01X155700Y381000D02*
X149500D01*
G01Y458000D02*
Y461200D01*
G01X155700Y458000D02*
X149500D01*
G01X155700Y461200D02*
Y458000D01*
G01X149500Y461200D02*
X155700D01*
G01Y465200D02*
Y462000D01*
G01X149500Y465200D02*
X155700D01*
G01X149500Y462000D02*
Y465200D01*
G01X155700Y462000D02*
X149500D01*
G01X149588Y552955D02*
Y556155D01*
G01X155788Y552955D02*
X149588D01*
G01X155788Y556155D02*
Y552955D01*
G01X149620Y560967D02*
Y564167D01*
G01X155820Y560967D02*
X149620D01*
G01X155820Y564167D02*
Y560967D01*
G01X149620Y564167D02*
X155820D01*
G01X149588Y556155D02*
X155788D01*
G01X149588Y556955D02*
Y560155D01*
G01X155788Y556955D02*
X149588D01*
G01X155788Y560155D02*
Y556955D01*
G01X149588Y560155D02*
X155788D01*
G01X149882Y576556D02*
Y588556D01*
G01X155882Y576556D02*
X149882D01*
G01X155882Y588556D02*
Y576556D01*
G01X149882Y588556D02*
X155882D01*
G01X155068Y597188D02*
Y593988D01*
G01Y593188D02*
Y589988D01*
G01X155100Y605200D02*
Y602000D01*
G01X155068Y601188D02*
Y597988D01*
G01X155100Y613200D02*
Y610000D01*
G01Y621200D02*
Y618000D01*
G01X155068Y609188D02*
Y605988D01*
G01X155100Y617200D02*
Y614000D01*
G01Y639569D02*
Y636369D01*
G01Y633021D02*
Y629821D01*
G01Y625200D02*
Y622000D01*
G01Y629200D02*
Y626000D01*
G01Y643574D02*
Y640374D01*
G01X158236Y987631D02*
X161436D01*
G01X158236Y981431D02*
Y987631D01*
G01X161436Y981431D02*
X158236D01*
G01X161436Y987631D02*
Y981431D01*
G01X158236Y990431D02*
Y996631D01*
G01X161436Y990431D02*
X158236D01*
G01X161436Y996631D02*
Y990431D01*
G01X154236D02*
Y996631D01*
G01X157436Y990431D02*
X154236D01*
G01X157436Y996631D02*
Y990431D01*
G01X149436Y987631D02*
Y981431D01*
G01Y996631D02*
Y990431D01*
G01X150236Y987631D02*
X153436D01*
G01X150236Y981431D02*
Y987631D01*
G01X153436Y981431D02*
X150236D01*
G01X153436Y987631D02*
Y981431D01*
G01X150236Y990431D02*
Y996631D01*
G01X153436Y990431D02*
X150236D01*
G01X153436Y996631D02*
Y990431D01*
G01X158236Y996631D02*
X161436D01*
G01X154236D02*
X157436D01*
G01X150236D02*
X153436D01*
G01X328346Y1071456D02*
X150039D01*
G01X165807Y57756D02*
Y104520D01*
G01X181732Y78540D02*
Y81740D01*
G01X187932Y78540D02*
X181732D01*
G01Y81740D02*
X187932D01*
G01X181732Y74540D02*
Y77740D01*
G01X187932Y74540D02*
X181732D01*
G01Y77740D02*
X187932D01*
G01X181732Y82540D02*
Y85740D01*
G01X187932Y82540D02*
X181732D01*
G01Y85740D02*
X187932D01*
G01X171339Y97026D02*
Y103226D01*
G01X174539Y97026D02*
X171339D01*
G01X174539Y103226D02*
Y97026D01*
G01X177343Y86929D02*
X174143D01*
G01X177343Y93129D02*
Y86929D01*
G01X174143Y93129D02*
X177343D01*
G01X174143Y86929D02*
Y93129D01*
G01X173343Y86929D02*
X170143D01*
G01X173343Y93129D02*
Y86929D01*
G01X170143Y93129D02*
X173343D01*
G01X170143Y86929D02*
Y93129D01*
G01X181343Y86929D02*
X178143D01*
G01X181343Y93129D02*
Y86929D01*
G01X178143Y93129D02*
X181343D01*
G01X178143Y86929D02*
Y93129D01*
G01X181422Y96673D02*
Y102873D01*
G01X184622Y96673D02*
X181422D01*
G01X177422D02*
Y102873D01*
G01X180622Y96673D02*
X177422D01*
G01X180622Y102873D02*
Y96673D01*
G01X165807Y111507D02*
Y107060D01*
G01Y118680D02*
Y114087D01*
G01X171339Y103226D02*
X174539D01*
G01X181422Y102873D02*
X184622D01*
G01X177422D02*
X180622D01*
G01X165807Y132859D02*
Y128325D01*
G01Y125844D02*
Y121329D01*
G01Y153150D02*
Y135490D01*
G01X179007Y139647D02*
Y142847D01*
G01X185207Y139647D02*
X179007D01*
G01Y142847D02*
X185207D01*
G01X175037Y145940D02*
Y149140D01*
G01X181237Y145940D02*
X175037D01*
G01X181237Y149140D02*
Y145940D01*
G01X175037Y149140D02*
X181237D01*
G01X172707Y164436D02*
Y195440D01*
G01X181237Y153140D02*
Y149940D01*
G01X175037Y153140D02*
X181237D01*
G01X175037Y149940D02*
Y153140D01*
G01X181237Y149940D02*
X175037D01*
G01X181673Y171473D02*
X178473D01*
G01X181673Y177673D02*
Y171473D01*
G01X178473Y177673D02*
X181673D01*
G01X178473Y171473D02*
Y177673D01*
G01X177673Y171473D02*
X174473D01*
G01X177673Y177673D02*
Y171473D01*
G01X174473Y177673D02*
X177673D01*
G01X174473Y171473D02*
Y177673D01*
G01X178496Y170297D02*
X184696D01*
G01X178496Y167097D02*
Y170297D01*
G01X184696Y167097D02*
X178496D01*
G01X181900Y182730D02*
X178700D01*
G01Y188930D02*
X181900D01*
G01X178700Y182730D02*
Y188930D01*
G01X178691Y193541D02*
X184891D01*
G01X178691Y190341D02*
Y193541D01*
G01X184891Y190341D02*
X178691D01*
G01X170020Y213035D02*
Y225035D01*
G01X176020Y213035D02*
X170020D01*
G01X176020Y225035D02*
Y213035D01*
G01X167958Y233011D02*
Y203452D01*
G01X170020Y225035D02*
X176020D01*
G01X176860Y226621D02*
Y232621D01*
G01X188860Y226621D02*
X176860D01*
G01X180839Y215082D02*
X177639D01*
G01X180839Y221282D02*
Y215082D01*
G01X177639Y221282D02*
X180839D01*
G01X177639Y215082D02*
Y221282D01*
G01X180660Y225921D02*
X186860D01*
G01X180660Y222721D02*
Y225921D01*
G01X186860Y222721D02*
X180660D01*
G01X176860Y232621D02*
X188860D01*
G01X169303Y250325D02*
Y234813D01*
G01D02*
X200395D01*
G01X167727Y292303D02*
Y262744D01*
G01X169583Y251600D02*
Y254700D01*
X170503D01*
X170810Y254545D01*
X171040Y254183D01*
X171117Y253770D01*
X171040Y253357D01*
X170848Y253047D01*
X170503Y252892D01*
X169583D01*
G01X172607Y251600D02*
Y254700D01*
X173373D01*
X173680Y254545D01*
X173910Y254338D01*
X174102Y254028D01*
X174255Y253667D01*
X174293Y253150D01*
X174255Y252633D01*
X174102Y252272D01*
X173910Y251962D01*
X173680Y251755D01*
X173373Y251600D01*
X172607D01*
G01X175822Y254183D02*
X176052Y254493D01*
X176320Y254648D01*
X176627Y254700D01*
X177010Y254597D01*
X177278Y254338D01*
X177355Y254028D01*
X177317Y253718D01*
X177163Y253460D01*
X176397Y252943D01*
X176052Y252582D01*
X175822Y252065D01*
X175745Y251600D01*
X177355D01*
G01X178807Y252065D02*
X179037Y251807D01*
X179305Y251652D01*
X179650Y251600D01*
X179995Y251703D01*
X180263Y251910D01*
X180455Y252272D01*
X180493Y252685D01*
X180417Y253098D01*
X180225Y253357D01*
X179957Y253563D01*
X179688Y253615D01*
X179420Y253563D01*
X179075Y253357D01*
X179190Y254700D01*
X180225D01*
G01X200395Y250325D02*
X169303D01*
G01X177528Y258010D02*
Y264210D01*
G01X180728Y258010D02*
X177528D01*
G01X180728Y264210D02*
Y258010D01*
G01X184728D02*
X181528D01*
G01D02*
Y264210D01*
G01X169598Y271655D02*
Y283655D01*
G01X175598Y271655D02*
X169598D01*
G01X175598Y283655D02*
Y271655D01*
G01X177528Y264210D02*
X180728D01*
G01X181528D02*
X184728D01*
G01X178487Y267653D02*
Y279427D01*
G01X188249Y267653D02*
X178487D01*
G01X169598Y283655D02*
X175598D01*
G01X179781Y283383D02*
X176581D01*
G01X179781Y289583D02*
Y283383D01*
G01X176581Y289583D02*
X179781D01*
G01X176581Y283383D02*
Y289583D01*
G01X183781Y283383D02*
X180581D01*
G01Y289583D02*
X183781D01*
G01X180581Y283383D02*
Y289583D01*
G01X178487Y279427D02*
X188249D01*
G01X194301Y334492D02*
G03I-9450J0D01*
G01X179087Y346690D02*
Y349790D01*
G01X180697D02*
Y346690D01*
G01Y348240D02*
X179087D01*
G01X182992Y346690D02*
Y349790D01*
X182532Y349170D01*
G01Y346690D02*
X183452D01*
G01X186552D02*
Y349790D01*
X185134Y347568D01*
X187050D01*
G01X188464Y349273D02*
X188694Y349583D01*
X188962Y349738D01*
X189269Y349790D01*
X189652Y349687D01*
X189920Y349428D01*
X189997Y349118D01*
X189959Y348808D01*
X189805Y348550D01*
X189039Y348033D01*
X188694Y347672D01*
X188464Y347155D01*
X188387Y346690D01*
X189997D01*
G01X168553Y366063D02*
Y391454D01*
G01Y366063D02*
X184099D01*
G01X168553Y412551D02*
Y408103D01*
G01Y405519D02*
Y401173D01*
G01Y398425D02*
Y393935D01*
G01Y426935D02*
Y422271D01*
G01Y419749D02*
Y415258D01*
G01Y441124D02*
Y436377D01*
G01Y433999D02*
Y429252D01*
G01Y469861D02*
Y443616D01*
G01Y477037D02*
Y472208D01*
G01Y491216D02*
Y486417D01*
G01Y484131D02*
Y479384D01*
G01Y513965D02*
Y493456D01*
G01Y521120D02*
Y516446D01*
G01Y639449D02*
Y537657D01*
G01Y535125D02*
Y530551D01*
G01Y528234D02*
Y523436D01*
G01X181906Y647253D02*
X166306D01*
X181906Y656223D01*
X166306D01*
G01Y667298D02*
Y671978D01*
G01Y669638D02*
X181906D01*
G01Y667298D02*
Y671978D01*
G01X167606Y691828D02*
X166826Y690658D01*
X166306Y689293D01*
Y687733D01*
X167086Y685978D01*
X168386Y684613D01*
X169946Y683638D01*
X172546Y682858D01*
X174886Y682663D01*
X177226Y683053D01*
X178786Y683638D01*
X180346Y684808D01*
X181386Y686173D01*
X181906Y687538D01*
Y688903D01*
X181386Y690268D01*
X180606Y691438D01*
X179566Y692413D01*
G01X166306Y705438D02*
X166826Y703878D01*
X168126Y702708D01*
X169686Y701928D01*
X171766Y701343D01*
X174106Y701148D01*
X176446Y701343D01*
X178526Y701928D01*
X180086Y702708D01*
X181386Y703878D01*
X181906Y705438D01*
X181386Y706998D01*
X180086Y708168D01*
X178526Y708948D01*
X176446Y709533D01*
X174106Y709728D01*
X171766Y709533D01*
X169686Y708948D01*
X168126Y708168D01*
X166826Y706998D01*
X166306Y705438D01*
G01X184029Y639449D02*
X168553D01*
G01X196798Y-509769D02*
X197598Y-510435D01*
X198498Y-510835D01*
X199298D01*
X200098Y-510435D01*
X200698Y-509769D01*
X200998Y-508835D01*
X200798Y-507902D01*
X200298Y-507102D01*
X199398Y-506568D01*
X198198Y-506302D01*
X197498Y-505768D01*
X197198Y-504835D01*
X197398Y-503902D01*
X197898Y-503235D01*
X198598Y-502835D01*
X199298D01*
X199998Y-503102D01*
X200598Y-503768D01*
G01X205698Y-502835D02*
X208098D01*
G01X206898D02*
Y-510835D01*
G01X205698D02*
X208098D01*
G01X212898Y-502835D02*
Y-510835D01*
X216898D01*
G01X220698D02*
Y-502835D01*
G01X224498D02*
X220698Y-507769D01*
G01X225098Y-510835D02*
X222398Y-505502D01*
G01X229598Y-508168D02*
X232198D01*
G01X238898Y-502835D02*
Y-510835D01*
G01X236598Y-502835D02*
X241198D01*
G01X246898Y-510835D02*
X246098Y-510702D01*
X245398Y-510168D01*
X244798Y-509368D01*
X244398Y-508435D01*
X244198Y-507368D01*
Y-506302D01*
X244398Y-505235D01*
X244798Y-504302D01*
X245398Y-503502D01*
X246098Y-502968D01*
X246898Y-502835D01*
X247698Y-502968D01*
X248398Y-503502D01*
X248998Y-504302D01*
X249398Y-505235D01*
X249598Y-506302D01*
Y-507368D01*
X249398Y-508435D01*
X248998Y-509368D01*
X248398Y-510168D01*
X247698Y-510702D01*
X246898Y-510835D01*
G01X252898D02*
Y-502835D01*
X255298D01*
X256098Y-503235D01*
X256698Y-504168D01*
X256898Y-505235D01*
X256698Y-506302D01*
X256198Y-507102D01*
X255298Y-507502D01*
X252898D01*
G01X185398Y-477835D02*
Y-485835D01*
X189398D01*
G01X197198D02*
Y-480502D01*
G01Y-481435D02*
X196798Y-480902D01*
X196198Y-480635D01*
X195498Y-480502D01*
X194798Y-480768D01*
X194198Y-481302D01*
X193798Y-482102D01*
X193598Y-483168D01*
X193798Y-484235D01*
X194198Y-485035D01*
X194798Y-485568D01*
X195498Y-485835D01*
X196198Y-485702D01*
X196798Y-485302D01*
X197198Y-484769D01*
G01X201298Y-488235D02*
X201898Y-488502D01*
X202698Y-488235D01*
X203198Y-487702D01*
X203598Y-487035D01*
X204198Y-484902D01*
X205498Y-480502D01*
G01X202298D02*
X204198Y-484902D01*
G01X209898Y-482235D02*
X213098D01*
X212798Y-481302D01*
X212298Y-480768D01*
X211598Y-480502D01*
X210898Y-480635D01*
X210298Y-481035D01*
X209898Y-481968D01*
X209698Y-482769D01*
Y-483568D01*
X209898Y-484368D01*
X210398Y-485168D01*
X210998Y-485702D01*
X211698Y-485835D01*
X212398Y-485568D01*
X213098Y-484769D01*
G01X217998Y-485835D02*
Y-480502D01*
G01Y-481568D02*
X218498Y-481035D01*
X218998Y-480635D01*
X219698Y-480502D01*
X220198Y-480635D01*
X220798Y-481035D01*
G01X192398Y66981D02*
Y70181D01*
G01X198598Y66981D02*
X192398D01*
G01X187932Y81740D02*
Y78540D01*
G01Y77740D02*
Y74540D01*
G01Y85740D02*
Y82540D01*
G01X192398Y70181D02*
X198598D01*
G01X192443Y74987D02*
Y78187D01*
G01X198643Y74987D02*
X192443D01*
G01Y78187D02*
X198643D01*
G01X192443Y70987D02*
Y74187D01*
G01X198643Y70987D02*
X192443D01*
G01Y74187D02*
X198643D01*
G01X192398Y82181D02*
X198598D01*
G01X192398Y78981D02*
Y82181D01*
G01X198598Y78981D02*
X192398D01*
G01X185352Y86929D02*
X182152D01*
G01X185352Y93129D02*
Y86929D01*
G01X182152Y93129D02*
X185352D01*
G01X182152Y86929D02*
Y93129D01*
G01X184622Y102873D02*
Y96673D01*
G01X186926Y95950D02*
Y102150D01*
G01X190126Y95950D02*
X186926D01*
G01X190126Y102150D02*
Y95950D01*
G01X191590Y95913D02*
Y111267D01*
G01X204071Y95913D02*
X191590D01*
G01X186926Y102150D02*
X190126D01*
G01X197941Y116088D02*
X204141D01*
G01X197941Y112888D02*
Y116088D01*
G01X204141Y112888D02*
X197941D01*
G01X186926Y109762D02*
X190126D01*
G01X186926Y103562D02*
Y109762D01*
G01X190126Y103562D02*
X186926D01*
G01X190126Y109762D02*
Y103562D01*
G01X191590Y111267D02*
X204268D01*
G01X183405Y144690D02*
Y154138D01*
G01X194241Y144690D02*
X183405D01*
G01X194241Y154138D02*
Y144690D01*
G01X185207Y142847D02*
Y139647D01*
G01X195648Y144168D02*
Y147368D01*
G01X201848Y144168D02*
X195648D01*
G01Y147368D02*
X201848D01*
G01X185986Y139647D02*
Y142847D01*
G01X192186Y139647D02*
X185986D01*
G01X192186Y142847D02*
Y139647D01*
G01X185986Y142847D02*
X192186D01*
G01X195648Y148168D02*
Y151368D01*
G01X201848Y148168D02*
X195648D01*
G01X185304Y157866D02*
X184997Y157918D01*
X184729Y158124D01*
X184499Y158434D01*
X184346Y158796D01*
X184269Y159209D01*
Y159623D01*
X184346Y160036D01*
X184499Y160398D01*
X184729Y160708D01*
X184997Y160914D01*
X185304Y160966D01*
X185611Y160914D01*
X185879Y160708D01*
X186109Y160398D01*
X186262Y160036D01*
X186339Y159623D01*
Y159209D01*
X186262Y158796D01*
X186109Y158434D01*
X185879Y158124D01*
X185611Y157918D01*
X185304Y157866D01*
G01X185611Y158693D02*
X186071Y157866D01*
G01X188404D02*
Y160966D01*
X187944Y160346D01*
G01Y157866D02*
X188864D01*
G01X190661Y158486D02*
X190891Y158124D01*
X191197Y157918D01*
X191542Y157866D01*
X191849Y157918D01*
X192156Y158176D01*
X192347Y158486D01*
X192386Y158796D01*
X192309Y159158D01*
X192041Y159416D01*
X191772Y159519D01*
X191427D01*
G01X191772D02*
X192002Y159674D01*
X192194Y159933D01*
X192271Y160243D01*
X192194Y160553D01*
X192002Y160811D01*
X191657Y160966D01*
X191312Y160914D01*
X190967Y160708D01*
G01X193761Y158331D02*
X193991Y158073D01*
X194259Y157918D01*
X194604Y157866D01*
X194949Y157969D01*
X195217Y158176D01*
X195409Y158538D01*
X195447Y158951D01*
X195371Y159364D01*
X195179Y159623D01*
X194911Y159829D01*
X194642Y159881D01*
X194374Y159829D01*
X194029Y159623D01*
X194144Y160966D01*
X195179D01*
G01X190823Y154138D02*
X194241D01*
G01X188823Y152414D02*
X190823Y154138D01*
G01X186823D02*
X188823Y152414D01*
G01X183405Y154138D02*
X186823D01*
G01X195648Y151368D02*
X201848D01*
G01X187857Y175100D02*
Y172878D01*
X188010Y172413D01*
X188317Y172103D01*
X188700Y172000D01*
X189083Y172103D01*
X189390Y172413D01*
X189543Y172878D01*
Y175100D01*
G01X190957Y172465D02*
X191187Y172207D01*
X191455Y172052D01*
X191800Y172000D01*
X192145Y172103D01*
X192413Y172310D01*
X192605Y172672D01*
X192643Y173085D01*
X192567Y173498D01*
X192375Y173757D01*
X192107Y173963D01*
X191838Y174015D01*
X191570Y173963D01*
X191225Y173757D01*
X191340Y175100D01*
X192375D01*
G01X195360Y172000D02*
Y175100D01*
X193942Y172878D01*
X195858D01*
G01X186401Y176944D02*
Y178897D01*
G01X188354Y176944D02*
X186401D01*
G01X198213D02*
X196260D01*
G01X184696Y170297D02*
Y167097D01*
G01X186401Y188756D02*
X188354D01*
G01X186401Y186803D02*
Y188756D01*
G01X196260D02*
X198213D01*
G01X181900Y188930D02*
Y182730D01*
G01X184891Y193541D02*
Y190341D01*
G01X185184Y200607D02*
Y203707D01*
X186104D01*
X186411Y203552D01*
X186641Y203190D01*
X186718Y202777D01*
X186641Y202364D01*
X186449Y202054D01*
X186104Y201899D01*
X185184D01*
G01X188208Y203707D02*
Y201485D01*
X188361Y201020D01*
X188668Y200710D01*
X189051Y200607D01*
X189434Y200710D01*
X189741Y201020D01*
X189894Y201485D01*
Y203707D01*
G01X191308Y201227D02*
X191538Y200865D01*
X191844Y200659D01*
X192189Y200607D01*
X192496Y200659D01*
X192803Y200917D01*
X192994Y201227D01*
X193033Y201537D01*
X192956Y201899D01*
X192688Y202157D01*
X192419Y202260D01*
X192074D01*
G01X192419D02*
X192649Y202415D01*
X192841Y202674D01*
X192918Y202984D01*
X192841Y203294D01*
X192649Y203552D01*
X192304Y203707D01*
X191959Y203655D01*
X191614Y203449D01*
G01X194523Y203190D02*
X194753Y203500D01*
X195021Y203655D01*
X195328Y203707D01*
X195711Y203604D01*
X195979Y203345D01*
X196056Y203035D01*
X196018Y202725D01*
X195864Y202467D01*
X195098Y201950D01*
X194753Y201589D01*
X194523Y201072D01*
X194446Y200607D01*
X196056D01*
G01X199176Y220252D02*
Y208048D01*
X183872D01*
Y220252D01*
X199176D01*
G01X188860Y232621D02*
Y226621D01*
G01X186860Y225921D02*
Y222721D01*
G01X185528Y258010D02*
Y264210D01*
G01X188728Y258010D02*
X185528D01*
G01X188728Y264210D02*
Y258010D01*
G01X184728Y264210D02*
Y258010D01*
G01X193522Y255997D02*
X190422D01*
Y256917D01*
X190577Y257224D01*
X190939Y257454D01*
X191352Y257531D01*
X191765Y257454D01*
X192075Y257262D01*
X192230Y256917D01*
Y255997D01*
G01X190422Y259021D02*
X192644D01*
X193109Y259174D01*
X193419Y259481D01*
X193522Y259864D01*
X193419Y260247D01*
X193109Y260554D01*
X192644Y260707D01*
X190422D01*
G01X193522Y262887D02*
X192850Y262964D01*
X192282Y263079D01*
X191765Y263232D01*
X191197Y263424D01*
X190422Y263731D01*
Y262197D01*
G01X193057Y265221D02*
X193315Y265451D01*
X193470Y265719D01*
X193522Y266064D01*
X193419Y266409D01*
X193212Y266677D01*
X192850Y266869D01*
X192437Y266907D01*
X192024Y266831D01*
X191765Y266639D01*
X191559Y266371D01*
X191507Y266102D01*
X191559Y265834D01*
X191765Y265489D01*
X190422Y265604D01*
Y266639D01*
G01X195439Y264635D02*
X210951D01*
G01X195439Y295727D02*
Y264635D01*
G01X185528Y264210D02*
X188728D01*
G01X193807Y273701D02*
X190607D01*
G01X193807Y279901D02*
Y273701D01*
G01X190607D02*
Y279901D01*
G01X188249Y279427D02*
Y267653D01*
G01X190607Y279901D02*
X193807D01*
G01X183781Y289583D02*
Y283383D01*
G01X184581D02*
Y289583D01*
X187781D01*
Y283383D01*
X184581D01*
G01X210951Y295727D02*
X195439D01*
G01X196549Y366063D02*
X204045D01*
G01X191408Y655807D02*
X190628Y654637D01*
X190108Y653272D01*
Y651712D01*
X190888Y649957D01*
X192188Y648592D01*
X193748Y647617D01*
X196348Y646837D01*
X198688Y646642D01*
X201028Y647032D01*
X202588Y647617D01*
X204148Y648787D01*
X205188Y650152D01*
X205708Y651517D01*
Y652882D01*
X205188Y654247D01*
X204408Y655417D01*
X203368Y656392D01*
G01X197388Y670977D02*
X196608Y671757D01*
X195308Y672342D01*
X193488Y672732D01*
X191928Y672342D01*
X190888Y671562D01*
X190108Y670197D01*
Y664932D01*
X205708D01*
Y671367D01*
X204668Y672732D01*
X203108Y673512D01*
X201288Y673902D01*
X199468Y673512D01*
X197908Y672342D01*
X197388Y670977D01*
Y664932D01*
G01X190108Y683417D02*
X205708D01*
Y691217D01*
G01X210908Y699367D02*
Y711067D01*
G01X190108Y723117D02*
X205708D01*
G01X190108Y718632D02*
Y727602D01*
G01X205708Y741017D02*
X205448Y739457D01*
X204408Y738092D01*
X202848Y736922D01*
X201028Y736142D01*
X198948Y735752D01*
X196868D01*
X194788Y736142D01*
X192968Y736922D01*
X191408Y738092D01*
X190368Y739457D01*
X190108Y741017D01*
X190368Y742577D01*
X191408Y743942D01*
X192968Y745112D01*
X194788Y745892D01*
X196868Y746282D01*
X198948D01*
X201028Y745892D01*
X202848Y745112D01*
X204408Y743942D01*
X205448Y742577D01*
X205708Y741017D01*
G01Y755017D02*
X190108D01*
Y759697D01*
X190888Y761257D01*
X192708Y762427D01*
X194788Y762817D01*
X196868Y762427D01*
X198428Y761452D01*
X199208Y759697D01*
Y755017D01*
G01X204045Y639449D02*
X196599D01*
G01X194331Y1436969D02*
Y1677520D01*
G01X204648Y1451484D02*
X197148D01*
Y1453724D01*
X197523Y1454471D01*
X198398Y1455031D01*
X199398Y1455218D01*
X200398Y1455031D01*
X201148Y1454564D01*
X201523Y1453724D01*
Y1451484D01*
G01X204648Y1458984D02*
X197148D01*
Y1461318D01*
X197523Y1462064D01*
X198023Y1462531D01*
X199023Y1462718D01*
X200023Y1462531D01*
X200648Y1461971D01*
X201023Y1461318D01*
Y1458984D01*
G01Y1461318D02*
X204648Y1462718D01*
G01Y1470218D02*
Y1466484D01*
X197148D01*
Y1470218D01*
G01X200773Y1468724D02*
Y1466484D01*
G01X203648Y1473891D02*
X204273Y1474638D01*
X204648Y1475478D01*
Y1476224D01*
X204273Y1476971D01*
X203648Y1477531D01*
X202773Y1477811D01*
X201898Y1477624D01*
X201148Y1477158D01*
X200648Y1476318D01*
X200398Y1475198D01*
X199898Y1474544D01*
X199023Y1474264D01*
X198148Y1474451D01*
X197523Y1474918D01*
X197148Y1475571D01*
Y1476224D01*
X197398Y1476878D01*
X198023Y1477438D01*
G01X203648Y1481391D02*
X204273Y1482138D01*
X204648Y1482978D01*
Y1483724D01*
X204273Y1484471D01*
X203648Y1485031D01*
X202773Y1485311D01*
X201898Y1485124D01*
X201148Y1484658D01*
X200648Y1483818D01*
X200398Y1482698D01*
X199898Y1482044D01*
X199023Y1481764D01*
X198148Y1481951D01*
X197523Y1482418D01*
X197148Y1483071D01*
Y1483724D01*
X197398Y1484378D01*
X198023Y1484938D01*
G01X202148Y1489638D02*
Y1492064D01*
G01X204648Y1496578D02*
X197148D01*
Y1500124D01*
G01X200773Y1498818D02*
Y1496578D01*
G01X197148Y1504731D02*
Y1506971D01*
G01Y1505851D02*
X204648D01*
G01Y1504731D02*
Y1506971D01*
G01X197148Y1513351D02*
X204648D01*
G01X197148Y1511204D02*
Y1515498D01*
G01X211398Y-535835D02*
Y-532235D01*
X209398Y-527835D01*
G01X213398D02*
X211398Y-532235D01*
G01X217698Y-530502D02*
Y-534235D01*
X218098Y-535168D01*
X218698Y-535702D01*
X219398Y-535835D01*
X220098Y-535702D01*
X220698Y-535168D01*
X221098Y-534235D01*
G01Y-535835D02*
Y-530502D01*
G01X225698Y-535835D02*
Y-530502D01*
G01Y-531835D02*
X226098Y-531168D01*
X226698Y-530635D01*
X227498Y-530502D01*
X228198Y-530635D01*
X228798Y-531168D01*
X229098Y-532102D01*
Y-535835D01*
G01X237198D02*
Y-530502D01*
G01Y-531435D02*
X236798Y-530902D01*
X236198Y-530635D01*
X235498Y-530502D01*
X234798Y-530768D01*
X234198Y-531302D01*
X233798Y-532102D01*
X233598Y-533168D01*
X233798Y-534235D01*
X234198Y-535035D01*
X234798Y-535568D01*
X235498Y-535835D01*
X236198Y-535702D01*
X236798Y-535302D01*
X237198Y-534769D01*
G01X213230Y67523D02*
X201026D01*
G01X213230Y79047D02*
Y67523D01*
G01X201026D02*
Y70183D01*
G01X207923Y59613D02*
Y56413D01*
G01X201723Y59613D02*
X207923D01*
G01X201723Y56413D02*
Y59613D01*
G01X207923Y56413D02*
X201723D01*
G01X198598Y70181D02*
Y66981D01*
G01X201026Y79047D02*
X213230D01*
G01X201026Y76285D02*
Y79047D01*
G01X204128Y73285D02*
X201026Y76285D01*
G01Y70183D02*
X204128Y73285D01*
G01X198643Y78187D02*
Y74987D01*
G01Y74187D02*
Y70987D01*
G01X198598Y82181D02*
Y78981D01*
G01X199433Y93476D02*
X202633D01*
G01X199433Y87276D02*
Y93476D01*
G01X202633Y87276D02*
X199433D01*
G01X202633Y93476D02*
Y87276D01*
G01X212082Y87204D02*
X208882D01*
G01X212082Y93404D02*
Y87204D01*
G01X208882Y93404D02*
X212082D01*
G01X208882Y87204D02*
Y93404D01*
G01X215989Y87299D02*
X212789D01*
G01Y93499D02*
X215989D01*
G01X212789Y87299D02*
Y93499D01*
G01X208133Y87276D02*
X204933D01*
G01X208133Y93476D02*
Y87276D01*
G01X204933Y93476D02*
X208133D01*
G01X204933Y87276D02*
Y93476D01*
G01X205500Y97907D02*
X207722D01*
X208187Y98060D01*
X208497Y98367D01*
X208600Y98750D01*
X208497Y99133D01*
X208187Y99440D01*
X207722Y99593D01*
X205500D01*
G01X207980Y101007D02*
X208342Y101237D01*
X208548Y101543D01*
X208600Y101888D01*
X208548Y102195D01*
X208290Y102502D01*
X207980Y102693D01*
X207670Y102732D01*
X207308Y102655D01*
X207050Y102387D01*
X206947Y102118D01*
Y101773D01*
G01Y102118D02*
X206792Y102348D01*
X206533Y102540D01*
X206223Y102617D01*
X205913Y102540D01*
X205655Y102348D01*
X205500Y102003D01*
X205552Y101658D01*
X205758Y101313D01*
G01X208238Y104298D02*
X208497Y104567D01*
X208600Y104873D01*
X208497Y105180D01*
X208187Y105448D01*
X207722Y105640D01*
X207257Y105717D01*
X206688D01*
X206223Y105640D01*
X205810Y105448D01*
X205603Y105218D01*
X205500Y104950D01*
X205603Y104643D01*
X205810Y104413D01*
X206120Y104260D01*
X206533Y104183D01*
X206895Y104260D01*
X207257Y104452D01*
X207463Y104682D01*
X207515Y104950D01*
X207412Y105257D01*
X207153Y105487D01*
X206688Y105717D01*
G01X208238Y107398D02*
X208497Y107667D01*
X208600Y107973D01*
X208497Y108280D01*
X208187Y108548D01*
X207722Y108740D01*
X207257Y108817D01*
X206688D01*
X206223Y108740D01*
X205810Y108548D01*
X205603Y108318D01*
X205500Y108050D01*
X205603Y107743D01*
X205810Y107513D01*
X206120Y107360D01*
X206533Y107283D01*
X206895Y107360D01*
X207257Y107552D01*
X207463Y107782D01*
X207515Y108050D01*
X207412Y108357D01*
X207153Y108587D01*
X206688Y108817D01*
G01X204268Y111267D02*
Y95913D01*
G01X205424Y111951D02*
Y118151D01*
G01X208624Y111951D02*
X205424D01*
G01X208624Y118151D02*
Y111951D01*
G01X204141Y116088D02*
Y112888D01*
G01X212344Y109424D02*
X215544D01*
G01X212344Y103224D02*
Y109424D01*
G01X215544Y103224D02*
X212344D01*
G01X210798Y111734D02*
Y123508D01*
G01X220560Y111734D02*
X210798D01*
G01X205424Y118151D02*
X208624D01*
G01X213569Y126223D02*
X210369D01*
G01X213569Y132423D02*
Y126223D01*
G01X210369Y132423D02*
X213569D01*
G01X210369Y126223D02*
Y132423D01*
G01X203665Y119112D02*
X200565D01*
Y120032D01*
X200720Y120339D01*
X201082Y120569D01*
X201495Y120646D01*
X201908Y120569D01*
X202218Y120377D01*
X202373Y120032D01*
Y119112D01*
G01X200565Y122136D02*
X202787D01*
X203252Y122289D01*
X203562Y122596D01*
X203665Y122979D01*
X203562Y123362D01*
X203252Y123669D01*
X202787Y123822D01*
X200565D01*
G01X203665Y126079D02*
X203613Y126347D01*
X203458Y126654D01*
X203200Y126846D01*
X202838Y126922D01*
X202477Y126846D01*
X202167Y126616D01*
X202012Y126271D01*
Y125887D01*
X201908Y125657D01*
X201650Y125466D01*
X201288Y125389D01*
X200927Y125504D01*
X200668Y125772D01*
X200565Y126079D01*
X200668Y126386D01*
X200927Y126654D01*
X201288Y126769D01*
X201650Y126692D01*
X201908Y126501D01*
X202012Y126271D01*
Y125887D01*
X202167Y125542D01*
X202477Y125312D01*
X202838Y125236D01*
X203200Y125312D01*
X203458Y125504D01*
X203613Y125811D01*
X203665Y126079D01*
G01X203045Y128336D02*
X203407Y128566D01*
X203613Y128872D01*
X203665Y129217D01*
X203613Y129524D01*
X203355Y129831D01*
X203045Y130022D01*
X202735Y130061D01*
X202373Y129984D01*
X202115Y129716D01*
X202012Y129447D01*
Y129102D01*
G01Y129447D02*
X201857Y129677D01*
X201598Y129869D01*
X201288Y129946D01*
X200978Y129869D01*
X200720Y129677D01*
X200565Y129332D01*
X200617Y128987D01*
X200823Y128642D01*
G01X210798Y123508D02*
X220560D01*
G01X202515Y133146D02*
X204737D01*
X205202Y133299D01*
X205512Y133606D01*
X205615Y133989D01*
X205512Y134372D01*
X205202Y134679D01*
X204737Y134832D01*
X202515D01*
G01X204995Y136246D02*
X205357Y136476D01*
X205563Y136782D01*
X205615Y137127D01*
X205563Y137434D01*
X205305Y137741D01*
X204995Y137932D01*
X204685Y137971D01*
X204323Y137894D01*
X204065Y137626D01*
X203962Y137357D01*
Y137012D01*
G01Y137357D02*
X203807Y137587D01*
X203548Y137779D01*
X203238Y137856D01*
X202928Y137779D01*
X202670Y137587D01*
X202515Y137242D01*
X202567Y136897D01*
X202773Y136552D01*
G01X205615Y140189D02*
X205563Y140457D01*
X205408Y140764D01*
X205150Y140956D01*
X204788Y141032D01*
X204427Y140956D01*
X204117Y140726D01*
X203962Y140381D01*
Y139997D01*
X203858Y139767D01*
X203600Y139576D01*
X203238Y139499D01*
X202877Y139614D01*
X202618Y139882D01*
X202515Y140189D01*
X202618Y140496D01*
X202877Y140764D01*
X203238Y140879D01*
X203600Y140802D01*
X203858Y140611D01*
X203962Y140381D01*
Y139997D01*
X204117Y139652D01*
X204427Y139422D01*
X204788Y139346D01*
X205150Y139422D01*
X205408Y139614D01*
X205563Y139921D01*
X205615Y140189D01*
G01X205150Y142446D02*
X205408Y142676D01*
X205563Y142944D01*
X205615Y143289D01*
X205512Y143634D01*
X205305Y143902D01*
X204943Y144094D01*
X204530Y144132D01*
X204117Y144056D01*
X203858Y143864D01*
X203652Y143596D01*
X203600Y143327D01*
X203652Y143059D01*
X203858Y142714D01*
X202515Y142829D01*
Y143864D01*
G01X201848Y147368D02*
Y144168D01*
G01Y151368D02*
Y148168D01*
G01X210758Y146229D02*
X207558D01*
G01X210758Y152429D02*
Y146229D01*
G01X207558D02*
Y152429D01*
G01X209248Y144395D02*
Y135095D01*
G01X219848Y144395D02*
X209248D01*
G01Y134995D02*
X219848D01*
G01X207558Y159540D02*
X210758D01*
G01X207558Y153340D02*
Y159540D01*
G01X210758Y153340D02*
X207558D01*
G01X210758Y159540D02*
Y153340D01*
G01X207558Y152429D02*
X210758D01*
G01X198213Y178897D02*
Y176944D01*
G01X202584Y171065D02*
Y174265D01*
G01X208784Y171065D02*
X202584D01*
G01X208784Y174265D02*
Y171065D01*
G01X202584Y174265D02*
X208784D01*
G01X202584Y179065D02*
Y182265D01*
G01X208784Y179065D02*
X202584D01*
G01X208784Y182265D02*
Y179065D01*
G01X202584Y175065D02*
Y178265D01*
G01X208784Y175065D02*
X202584D01*
G01X208784Y178265D02*
Y175065D01*
G01X202584Y178265D02*
X208784D01*
G01X202584Y167065D02*
Y170265D01*
G01X208784Y167065D02*
X202584D01*
G01X208784Y170265D02*
Y167065D01*
G01X202584Y170265D02*
X208784D01*
G01X198213Y188756D02*
Y186803D01*
G01X210352Y189435D02*
X212592D01*
G01X211379Y191060D02*
Y187810D01*
G01X213993Y195583D02*
X243552D01*
G01X213993Y184087D02*
Y195583D01*
G01X243552Y184087D02*
X213993D01*
G01X202584Y182265D02*
X208784D01*
G01X202584Y183065D02*
Y186265D01*
G01X208784Y183065D02*
X202584D01*
G01X208784Y186265D02*
Y183065D01*
G01X202584Y186265D02*
X208784D01*
G01Y198265D02*
Y195065D01*
G01X202584D02*
Y198265D01*
G01X208784Y195065D02*
X202584D01*
G01Y187065D02*
Y190265D01*
G01X208784Y187065D02*
X202584D01*
G01X208784Y190265D02*
Y187065D01*
G01X202584Y190265D02*
X208784D01*
G01Y194265D02*
Y191065D01*
G01X202584Y194265D02*
X208784D01*
G01X202584Y191065D02*
Y194265D01*
G01X208784Y191065D02*
X202584D01*
G01X214146Y204506D02*
Y216506D01*
G01X220146Y204506D02*
X214146D01*
G01X202584Y198265D02*
X208784D01*
G01X202679Y207264D02*
Y210464D01*
G01X208879Y207264D02*
X202679D01*
G01X208879Y210464D02*
Y207264D01*
G01X202679Y210464D02*
X208879D01*
G01Y206464D02*
Y203264D01*
G01X202679Y206464D02*
X208879D01*
G01X202679Y203264D02*
Y206464D01*
G01X208879Y203264D02*
X202679D01*
G01Y214464D02*
X208879D01*
Y211264D01*
X202679D01*
Y214464D01*
G01Y202464D02*
X208879D01*
Y199264D01*
X202679D01*
Y202464D01*
G01X214146Y216506D02*
X220146D01*
G01X202679Y215264D02*
Y218464D01*
G01X208879Y215264D02*
X202679D01*
G01X208879Y218464D02*
Y215264D01*
G01X202679Y218464D02*
X208879D01*
G01X202679Y220264D02*
Y223464D01*
G01X208879Y220264D02*
X202679D01*
G01X208879Y223464D02*
Y220264D01*
G01X202679Y223464D02*
X208879D01*
G01X202676Y227319D02*
X208876D01*
Y224119D01*
X202676D01*
Y227319D01*
G01X200395Y234813D02*
Y250325D01*
G01X212944Y246771D02*
Y249971D01*
G01X219144Y246771D02*
X212944D01*
G01Y249971D02*
X219144D01*
G01X212944Y253971D02*
X219144D01*
G01X212944Y250771D02*
Y253971D01*
G01X219144Y250771D02*
X212944D01*
G01X215600Y265183D02*
X212500D01*
Y266103D01*
X212655Y266410D01*
X213017Y266640D01*
X213430Y266717D01*
X213843Y266640D01*
X214153Y266448D01*
X214308Y266103D01*
Y265183D01*
G01X215600Y268207D02*
X212500D01*
Y268973D01*
X212655Y269280D01*
X212862Y269510D01*
X213172Y269702D01*
X213533Y269855D01*
X214050Y269893D01*
X214567Y269855D01*
X214928Y269702D01*
X215238Y269510D01*
X215445Y269280D01*
X215600Y268973D01*
Y268207D01*
G01Y272150D02*
X215548Y272418D01*
X215393Y272725D01*
X215135Y272917D01*
X214773Y272993D01*
X214412Y272917D01*
X214102Y272687D01*
X213947Y272342D01*
Y271958D01*
X213843Y271728D01*
X213585Y271537D01*
X213223Y271460D01*
X212862Y271575D01*
X212603Y271843D01*
X212500Y272150D01*
X212603Y272457D01*
X212862Y272725D01*
X213223Y272840D01*
X213585Y272763D01*
X213843Y272572D01*
X213947Y272342D01*
Y271958D01*
X214102Y271613D01*
X214412Y271383D01*
X214773Y271307D01*
X215135Y271383D01*
X215393Y271575D01*
X215548Y271882D01*
X215600Y272150D01*
G01Y275250D02*
X215548Y275518D01*
X215393Y275825D01*
X215135Y276017D01*
X214773Y276093D01*
X214412Y276017D01*
X214102Y275787D01*
X213947Y275442D01*
Y275058D01*
X213843Y274828D01*
X213585Y274637D01*
X213223Y274560D01*
X212862Y274675D01*
X212603Y274943D01*
X212500Y275250D01*
X212603Y275557D01*
X212862Y275825D01*
X213223Y275940D01*
X213585Y275863D01*
X213843Y275672D01*
X213947Y275442D01*
Y275058D01*
X214102Y274713D01*
X214412Y274483D01*
X214773Y274407D01*
X215135Y274483D01*
X215393Y274675D01*
X215548Y274982D01*
X215600Y275250D01*
G01X210951Y264635D02*
Y295727D01*
G01X204045Y366063D02*
Y391496D01*
G01Y393802D02*
Y398671D01*
G01Y401039D02*
Y405714D01*
G01Y408102D02*
Y412746D01*
G01Y415104D02*
Y419739D01*
G01Y422281D02*
Y426977D01*
G01Y429376D02*
Y433999D01*
G01Y436398D02*
Y441124D01*
G01Y451956D02*
Y443420D01*
G01Y459056D02*
Y469892D01*
G01Y472291D02*
Y476944D01*
G01Y479302D02*
Y484110D01*
G01Y486417D02*
Y491184D01*
G01Y493480D02*
Y514036D01*
G01Y516322D02*
Y521079D01*
G01Y523437D02*
Y528152D01*
G01Y580396D02*
Y537656D01*
G01Y530592D02*
Y535257D01*
G01Y587506D02*
Y639449D01*
G01X206142Y1689331D02*
Y1425158D01*
G01X215791Y1427533D02*
X212591D01*
Y1433733D01*
G01Y1424383D02*
Y1430583D01*
X215791D01*
G01X214970Y1613485D02*
X215770Y1613985D01*
X216303Y1614585D01*
X216570Y1615285D01*
X216303Y1616085D01*
X215770Y1616685D01*
X214970Y1617285D01*
X213903Y1617485D01*
X208570D01*
G01X214970Y1621285D02*
X215903Y1621885D01*
X216437Y1622685D01*
X216570Y1623585D01*
X216437Y1624385D01*
X215770Y1625185D01*
X214970Y1625685D01*
X214170Y1625785D01*
X213237Y1625585D01*
X212570Y1624885D01*
X212303Y1624185D01*
Y1623285D01*
G01Y1624185D02*
X211903Y1624785D01*
X211237Y1625285D01*
X210437Y1625485D01*
X209637Y1625285D01*
X208970Y1624785D01*
X208570Y1623885D01*
X208703Y1622985D01*
X209237Y1622085D01*
G01X214900Y67907D02*
X217122D01*
X217587Y68060D01*
X217897Y68367D01*
X218000Y68750D01*
X217897Y69133D01*
X217587Y69440D01*
X217122Y69593D01*
X214900D01*
G01X218000Y71850D02*
X214900D01*
X215520Y71390D01*
G01X218000D02*
Y72310D01*
G01X215417Y74222D02*
X215107Y74452D01*
X214952Y74720D01*
X214900Y75027D01*
X215003Y75410D01*
X215262Y75678D01*
X215572Y75755D01*
X215882Y75717D01*
X216140Y75563D01*
X216657Y74797D01*
X217018Y74452D01*
X217535Y74222D01*
X218000Y74145D01*
Y75755D01*
G01Y77973D02*
X217328Y78050D01*
X216760Y78165D01*
X216243Y78318D01*
X215675Y78510D01*
X214900Y78817D01*
Y77283D01*
G01X215989Y93499D02*
Y87299D01*
G01X228961Y122172D02*
Y110172D01*
G01X222961D02*
Y122172D01*
G01X228961Y110172D02*
X222961D01*
G01X220344Y109424D02*
X223544D01*
G01X220344Y103224D02*
Y109424D01*
G01X223544Y103224D02*
X220344D01*
G01X223544Y109424D02*
Y103224D01*
G01X228038Y108095D02*
X234238D01*
G01X228038Y104895D02*
Y108095D01*
G01X234238Y104895D02*
X228038D01*
G01Y100895D02*
Y104095D01*
G01X234238Y100895D02*
X228038D01*
G01Y104095D02*
X234238D01*
G01X216344Y109424D02*
X219544D01*
G01X216344Y103224D02*
Y109424D01*
G01X219544Y103224D02*
X216344D01*
G01X219544Y109424D02*
Y103224D01*
G01X215544Y109424D02*
Y103224D01*
G01X220560Y123508D02*
Y111734D01*
G01X222961Y122172D02*
X228961D01*
G01X221569Y126223D02*
X218369D01*
G01X221569Y132423D02*
Y126223D01*
G01X218369Y132423D02*
X221569D01*
G01X218369Y126223D02*
Y132423D01*
G01X225623Y126228D02*
X222423D01*
G01X225623Y132428D02*
Y126228D01*
G01X222423Y132428D02*
X225623D01*
G01X222423Y126228D02*
Y132428D01*
G01X214369Y132423D02*
X217569D01*
G01X214369Y126223D02*
Y132423D01*
G01X217569Y126223D02*
X214369D01*
G01X217569Y132423D02*
Y126223D01*
G01X225802Y141337D02*
X222602D01*
G01X225802Y147537D02*
Y141337D01*
G01X222602Y147537D02*
X225802D01*
G01X222602Y141337D02*
Y147537D01*
G01X222467Y133238D02*
Y136438D01*
G01X228667Y133238D02*
X222467D01*
G01X228667Y136438D02*
Y133238D01*
G01X222467Y136438D02*
X228667D01*
G01X229013Y148437D02*
X232213D01*
G01X229013Y142237D02*
Y148437D01*
G01X232213Y142237D02*
X229013D01*
G01X222467Y137238D02*
Y140438D01*
G01X228667Y137238D02*
X222467D01*
G01X228667Y140438D02*
Y137238D01*
G01X222467Y140438D02*
X228667D01*
G01X219848Y134995D02*
Y144395D01*
G01X217471Y149950D02*
Y165304D01*
G01X230149Y149950D02*
X217471D01*
G01X230149Y165304D02*
Y149950D01*
G01X217668Y165304D02*
X230149D01*
G01X215183Y179600D02*
Y182700D01*
X216103D01*
X216410Y182545D01*
X216640Y182183D01*
X216717Y181770D01*
X216640Y181357D01*
X216448Y181047D01*
X216103Y180892D01*
X215183D01*
G01X218207Y179600D02*
Y182700D01*
X218973D01*
X219280Y182545D01*
X219510Y182338D01*
X219702Y182028D01*
X219855Y181667D01*
X219893Y181150D01*
X219855Y180633D01*
X219702Y180272D01*
X219510Y179962D01*
X219280Y179755D01*
X218973Y179600D01*
X218207D01*
G01X221422Y180892D02*
X221690Y181253D01*
X221920Y181460D01*
X222227Y181563D01*
X222495Y181460D01*
X222687Y181253D01*
X222840Y180943D01*
X222878Y180582D01*
X222840Y180272D01*
X222687Y179962D01*
X222457Y179703D01*
X222188Y179600D01*
X221882Y179703D01*
X221613Y180013D01*
X221460Y180478D01*
X221422Y180995D01*
X221498Y181667D01*
X221613Y182028D01*
X221805Y182390D01*
X222073Y182648D01*
X222342Y182700D01*
X222610Y182597D01*
X222802Y182338D01*
G01X224407Y180065D02*
X224637Y179807D01*
X224905Y179652D01*
X225250Y179600D01*
X225595Y179703D01*
X225863Y179910D01*
X226055Y180272D01*
X226093Y180685D01*
X226017Y181098D01*
X225825Y181357D01*
X225557Y181563D01*
X225288Y181615D01*
X225020Y181563D01*
X224675Y181357D01*
X224790Y182700D01*
X225825D01*
G01X232969Y197645D02*
X220969D01*
G01D02*
Y203645D01*
G01X220146Y216506D02*
Y204506D01*
G01X220969Y203645D02*
X232969D01*
G01X224722Y208464D02*
X230922D01*
G01X224722Y205264D02*
Y208464D01*
G01X230922Y205264D02*
X224722D01*
G01X220946Y208306D02*
Y214506D01*
G01X224146Y208306D02*
X220946D01*
G01X224146Y214506D02*
Y208306D01*
G01X225752Y226801D02*
X237956D01*
Y211497D01*
X225752D01*
Y226801D01*
G01X220946Y214506D02*
X224146D01*
G01X221312Y245521D02*
Y254969D01*
G01X232148Y245521D02*
X221312D01*
G01X224888Y231334D02*
X221688D01*
G01X224888Y237534D02*
Y231334D01*
G01X221688Y237534D02*
X224888D01*
G01X221688Y231334D02*
Y237534D01*
G01X230415Y231446D02*
X227215D01*
G01X230415Y237646D02*
Y231446D01*
G01X227215Y237646D02*
X230415D01*
G01X227215Y231446D02*
Y237646D01*
G01X219144Y249971D02*
Y246771D01*
G01X223114Y243678D02*
Y240478D01*
G01X216914Y243678D02*
X223114D01*
G01X216914Y240478D02*
Y243678D01*
G01X223114Y240478D02*
X216914D01*
G01X230093Y243678D02*
Y240478D01*
G01X223893Y243678D02*
X230093D01*
G01X223893Y240478D02*
Y243678D01*
G01X230093Y240478D02*
X223893D01*
G01X221550Y256200D02*
X221243Y256252D01*
X220975Y256458D01*
X220745Y256768D01*
X220592Y257130D01*
X220515Y257543D01*
Y257957D01*
X220592Y258370D01*
X220745Y258732D01*
X220975Y259042D01*
X221243Y259248D01*
X221550Y259300D01*
X221857Y259248D01*
X222125Y259042D01*
X222355Y258732D01*
X222508Y258370D01*
X222585Y257957D01*
Y257543D01*
X222508Y257130D01*
X222355Y256768D01*
X222125Y256458D01*
X221857Y256252D01*
X221550Y256200D01*
G01X221857Y257027D02*
X222317Y256200D01*
G01X224650D02*
Y259300D01*
X224190Y258680D01*
G01Y256200D02*
X225110D01*
G01X227022Y258783D02*
X227252Y259093D01*
X227520Y259248D01*
X227827Y259300D01*
X228210Y259197D01*
X228478Y258938D01*
X228555Y258628D01*
X228517Y258318D01*
X228363Y258060D01*
X227597Y257543D01*
X227252Y257182D01*
X227022Y256665D01*
X226945Y256200D01*
X228555D01*
G01X230198Y256562D02*
X230467Y256303D01*
X230773Y256200D01*
X231080Y256303D01*
X231348Y256613D01*
X231540Y257078D01*
X231617Y257543D01*
Y258112D01*
X231540Y258577D01*
X231348Y258990D01*
X231118Y259197D01*
X230850Y259300D01*
X230543Y259197D01*
X230313Y258990D01*
X230160Y258680D01*
X230083Y258267D01*
X230160Y257905D01*
X230352Y257543D01*
X230582Y257337D01*
X230850Y257285D01*
X231157Y257388D01*
X231387Y257647D01*
X231617Y258112D01*
G01X228730Y254969D02*
X232148D01*
G01X226730Y253245D02*
X228730Y254969D01*
G01X224730D02*
X226730Y253245D01*
G01X221312Y254969D02*
X224730D01*
G01X219144Y253971D02*
Y250771D01*
G01X229164Y386318D02*
X235364D01*
G01X229164Y383118D02*
Y386318D01*
G01X235364Y383118D02*
X229164D01*
G01Y382318D02*
X235364D01*
G01X229164Y379118D02*
Y382318D01*
G01X235364Y379118D02*
X229164D01*
G01Y391118D02*
Y394318D01*
G01X235364Y391118D02*
X229164D01*
G01Y387118D02*
Y390318D01*
G01X235364Y387118D02*
X229164D01*
G01Y390318D02*
X235364D01*
G01X229164Y394318D02*
X235364D01*
G01X229164Y398318D02*
X235364D01*
G01X229164Y395118D02*
Y398318D01*
G01X235364Y395118D02*
X229164D01*
G01Y402318D02*
X235364D01*
G01X229164Y399118D02*
Y402318D01*
G01X235364Y399118D02*
X229164D01*
G01Y406318D02*
X235364D01*
G01X229164Y403118D02*
Y406318D01*
G01X235364Y403118D02*
X229164D01*
G01Y407118D02*
Y410318D01*
G01X235364Y407118D02*
X229164D01*
G01Y410318D02*
X235364D01*
G01X229164Y414318D02*
X235364D01*
G01X229164Y411118D02*
Y414318D01*
G01X235364Y411118D02*
X229164D01*
G01X222900Y460400D02*
Y457200D01*
G01X216700D02*
Y460400D01*
G01X222900Y457200D02*
X216700D01*
G01Y460400D02*
X222900D01*
G01X216700Y461200D02*
Y464400D01*
G01X222900Y461200D02*
X216700D01*
G01X222900Y464400D02*
Y461200D01*
G01X216700Y464400D02*
X222900D01*
G01X225500Y555300D02*
X231700D01*
G01X225500Y552100D02*
Y555300D01*
G01X231700Y552100D02*
X225500D01*
G01X216900Y548200D02*
Y551400D01*
G01X223100Y548200D02*
X216900D01*
G01X223100Y551400D02*
Y548200D01*
G01X216900Y551400D02*
X223100D01*
G01Y547400D02*
Y544200D01*
G01X216900Y547400D02*
X223100D01*
G01X216900Y544200D02*
Y547400D01*
G01X223100Y544200D02*
X216900D01*
G01X225500Y548100D02*
Y551300D01*
G01X231700Y548100D02*
X225500D01*
G01Y551300D02*
X231700D01*
G01X225500Y559300D02*
X231700D01*
G01X225500Y556100D02*
Y559300D01*
G01X231700Y556100D02*
X225500D01*
G01X216900Y561200D02*
Y564400D01*
G01X223100Y561200D02*
X216900D01*
G01X223100Y564400D02*
Y561200D01*
G01X216900Y564400D02*
X223100D01*
G01X216900Y557200D02*
Y560400D01*
G01X223100Y557200D02*
X216900D01*
G01X223100Y560400D02*
Y557200D01*
G01X216900Y560400D02*
X223100D01*
G01X219539Y610364D02*
X216339D01*
G01X219539Y616564D02*
Y610364D01*
G01X216339Y616564D02*
X219539D01*
G01X216339Y610364D02*
Y616564D01*
G01X223409Y610376D02*
X220209D01*
G01X223409Y616576D02*
Y610376D01*
G01X220209Y616576D02*
X223409D01*
G01X220209Y610376D02*
Y616576D01*
G01X217300Y619800D02*
Y623000D01*
G01X223500Y619800D02*
X217300D01*
G01X223500Y623000D02*
Y619800D01*
G01X217300Y623000D02*
X223500D01*
G01X217300Y623800D02*
Y627000D01*
G01X223500Y623800D02*
X217300D01*
G01X223500Y627000D02*
Y623800D01*
G01X217300Y627000D02*
X223500D01*
G01X237314Y823850D02*
Y821900D01*
X227314D01*
G01D02*
Y833850D01*
G01Y839950D02*
Y851900D01*
X237314D01*
Y849950D01*
G01X227097Y854087D02*
X227289Y853777D01*
X227519Y853570D01*
X227787Y853467D01*
X228094Y853570D01*
X228324Y853777D01*
X228554Y854087D01*
X228631Y854500D01*
Y856567D01*
G01X230887Y853467D02*
X230964Y854139D01*
X231079Y854707D01*
X231232Y855224D01*
X231424Y855792D01*
X231731Y856567D01*
X230197D01*
G01X234064Y853467D02*
Y856567D01*
X233604Y855947D01*
G01Y853467D02*
X234524D01*
G01X237314Y891150D02*
Y889200D01*
X227314D01*
G01D02*
Y901150D01*
G01Y907250D02*
Y919200D01*
X237314D01*
Y917250D01*
G01X226953Y920881D02*
X227145Y920571D01*
X227375Y920364D01*
X227643Y920261D01*
X227950Y920364D01*
X228180Y920571D01*
X228410Y920881D01*
X228487Y921294D01*
Y923361D01*
G01X230743Y920261D02*
X230820Y920933D01*
X230935Y921501D01*
X231088Y922018D01*
X231280Y922586D01*
X231587Y923361D01*
X230053D01*
G01X233192Y922844D02*
X233422Y923154D01*
X233690Y923309D01*
X233997Y923361D01*
X234380Y923258D01*
X234648Y922999D01*
X234725Y922689D01*
X234687Y922379D01*
X234533Y922121D01*
X233767Y921604D01*
X233422Y921243D01*
X233192Y920726D01*
X233115Y920261D01*
X234725D01*
G01X222613Y1021333D02*
Y1029333D01*
X225013D01*
X225813Y1028933D01*
X226413Y1028000D01*
X226613Y1026933D01*
X226413Y1025866D01*
X225913Y1025066D01*
X225013Y1024666D01*
X222613D01*
G01X234613Y1021333D02*
X230613D01*
Y1029333D01*
X234613D01*
G01X233013Y1025466D02*
X230613D01*
G01X238513Y1021333D02*
X242713Y1029333D01*
G01X238513D02*
X242713Y1021333D01*
G01X248613Y1029333D02*
X247813Y1029066D01*
X247213Y1028400D01*
X246813Y1027600D01*
X246513Y1026533D01*
X246413Y1025333D01*
X246513Y1024133D01*
X246813Y1023066D01*
X247213Y1022266D01*
X247813Y1021600D01*
X248613Y1021333D01*
X249413Y1021600D01*
X250013Y1022266D01*
X250413Y1023066D01*
X250713Y1024133D01*
X250813Y1025333D01*
X250713Y1026533D01*
X250413Y1027600D01*
X250013Y1028400D01*
X249413Y1029066D01*
X248613Y1029333D01*
G01X215791Y1433733D02*
Y1430797D01*
G01X223143Y1433636D02*
Y1427436D01*
X219943D01*
G01Y1430424D02*
Y1433636D01*
G01Y1424286D02*
Y1427535D01*
G01Y1430486D02*
X223143D01*
Y1424286D01*
G01X215791Y1427653D02*
Y1424383D01*
G01X232144Y1472922D02*
X225944D01*
Y1476122D01*
X232144D01*
Y1472922D01*
G01X219484Y1478380D02*
Y1484580D01*
X222684D01*
Y1478380D01*
X219484D01*
G01X225943Y1480042D02*
X232143D01*
G01X225943Y1476842D02*
Y1480042D01*
G01X232143Y1476842D02*
X225943D01*
G01Y1480842D02*
Y1484042D01*
G01X232143Y1480842D02*
X225943D01*
G01X225937Y1495961D02*
X232137D01*
Y1492761D01*
X225937D01*
Y1495961D01*
G01X225943Y1484042D02*
X232143D01*
G01X225943Y1488042D02*
X232143D01*
G01X225943Y1484842D02*
Y1488042D01*
G01X232143Y1484842D02*
X225943D01*
G01Y1488842D02*
Y1492042D01*
G01X232143Y1488842D02*
X225943D01*
G01Y1492042D02*
X232143D01*
G01X227943Y1512042D02*
X234143D01*
G01X227943Y1508842D02*
Y1512042D01*
G01X234143Y1508842D02*
X227943D01*
G01X227948Y1512978D02*
Y1516178D01*
G01X234148Y1512978D02*
X227948D01*
G01X218415Y1517242D02*
X224615D01*
Y1514042D01*
X218415D01*
Y1517242D01*
G01X218115Y1524142D02*
X224315D01*
Y1520942D01*
X218115D01*
Y1524142D01*
G01X227948Y1516178D02*
X234148D01*
G01X227948Y1520178D02*
X234148D01*
G01X227948Y1516978D02*
Y1520178D01*
G01X234148Y1516978D02*
X227948D01*
G01Y1524978D02*
Y1528178D01*
G01X234148Y1524978D02*
X227948D01*
G01Y1528178D02*
X234148D01*
G01X227948Y1520978D02*
Y1524178D01*
G01X234148Y1520978D02*
X227948D01*
G01Y1524178D02*
X234148D01*
G01X231542Y1550985D02*
Y1544785D01*
X228342D01*
Y1550985D01*
X231542D01*
G01X223542Y1538985D02*
Y1532785D01*
X220342D01*
Y1538985D01*
X223542D01*
G01X231353Y1532615D02*
X228153D01*
G01Y1538815D02*
X231353D01*
G01X228153Y1532615D02*
Y1538815D01*
G01X224153D02*
X227353D01*
G01X224153Y1532615D02*
Y1538815D01*
G01X227353Y1532615D02*
X224153D01*
G01X227353Y1538815D02*
Y1532615D01*
G01X221555Y1564843D02*
X249311D01*
G01X221555Y1690040D02*
Y1564843D01*
G01X249311Y1647992D02*
X221555D01*
G01X249311Y1690040D02*
X221555D01*
G01X243365Y57756D02*
Y111785D01*
G01X243661Y58150D02*
Y111785D01*
G01X236911Y58512D02*
X237221Y58704D01*
X237428Y58934D01*
X237531Y59202D01*
X237428Y59509D01*
X237221Y59739D01*
X236911Y59969D01*
X236498Y60046D01*
X234431D01*
G01X236911Y61536D02*
X237273Y61766D01*
X237479Y62072D01*
X237531Y62417D01*
X237479Y62724D01*
X237221Y63031D01*
X236911Y63222D01*
X236601Y63261D01*
X236239Y63184D01*
X235981Y62916D01*
X235878Y62647D01*
Y62302D01*
G01Y62647D02*
X235723Y62877D01*
X235464Y63069D01*
X235154Y63146D01*
X234844Y63069D01*
X234586Y62877D01*
X234431Y62532D01*
X234483Y62187D01*
X234689Y61842D01*
G01X234948Y64751D02*
X234638Y64981D01*
X234483Y65249D01*
X234431Y65556D01*
X234534Y65939D01*
X234793Y66207D01*
X235103Y66284D01*
X235413Y66246D01*
X235671Y66092D01*
X236188Y65326D01*
X236549Y64981D01*
X237066Y64751D01*
X237531Y64674D01*
Y66284D01*
G01X249746Y57756D02*
X243365D01*
G01X249341Y58150D02*
X243661D01*
G01X232222Y96067D02*
Y99267D01*
G01X238422Y96067D02*
X232222D01*
G01X238422Y99267D02*
Y96067D01*
G01X232222Y99267D02*
X238422D01*
G01X243661Y118848D02*
Y114048D01*
G01X243365Y118848D02*
Y114048D01*
G01X234238Y108095D02*
Y104895D01*
G01Y104095D02*
Y100895D01*
G01X235095Y108086D02*
X238295D01*
G01X235095Y101886D02*
Y108086D01*
G01X238295Y101886D02*
X235095D01*
G01X238295Y108086D02*
Y101886D01*
G01X243661Y132607D02*
Y128340D01*
G01X243365Y132607D02*
Y128340D01*
G01Y125781D02*
Y121219D01*
G01X243661Y125781D02*
Y121219D01*
G01Y152756D02*
Y135411D01*
G01X243365Y153150D02*
Y135411D01*
G01X232213Y148437D02*
Y142237D01*
G01X231500Y152507D02*
X233722D01*
X234187Y152660D01*
X234497Y152967D01*
X234600Y153350D01*
X234497Y153733D01*
X234187Y154040D01*
X233722Y154193D01*
X231500D01*
G01X233980Y155607D02*
X234342Y155837D01*
X234548Y156143D01*
X234600Y156488D01*
X234548Y156795D01*
X234290Y157102D01*
X233980Y157293D01*
X233670Y157332D01*
X233308Y157255D01*
X233050Y156987D01*
X232947Y156718D01*
Y156373D01*
G01Y156718D02*
X232792Y156948D01*
X232533Y157140D01*
X232223Y157217D01*
X231913Y157140D01*
X231655Y156948D01*
X231500Y156603D01*
X231552Y156258D01*
X231758Y155913D01*
G01X233308Y158822D02*
X232947Y159090D01*
X232740Y159320D01*
X232637Y159627D01*
X232740Y159895D01*
X232947Y160087D01*
X233257Y160240D01*
X233618Y160278D01*
X233928Y160240D01*
X234238Y160087D01*
X234497Y159857D01*
X234600Y159588D01*
X234497Y159282D01*
X234187Y159013D01*
X233722Y158860D01*
X233205Y158822D01*
X232533Y158898D01*
X232172Y159013D01*
X231810Y159205D01*
X231552Y159473D01*
X231500Y159742D01*
X231603Y160010D01*
X231862Y160202D01*
G01X234135Y161807D02*
X234393Y162037D01*
X234548Y162305D01*
X234600Y162650D01*
X234497Y162995D01*
X234290Y163263D01*
X233928Y163455D01*
X233515Y163493D01*
X233102Y163417D01*
X232843Y163225D01*
X232637Y162957D01*
X232585Y162688D01*
X232637Y162420D01*
X232843Y162075D01*
X231500Y162190D01*
Y163225D01*
G01X243365Y153150D02*
X249746D01*
G01X243661Y152756D02*
X249341D01*
G01X247092Y189535D02*
X244666D01*
G01X243552Y195583D02*
Y184087D01*
G01X232969Y203645D02*
Y197645D01*
G01X230922Y208464D02*
Y205264D01*
G01X245108Y215121D02*
X242008D01*
Y216041D01*
X242163Y216348D01*
X242525Y216578D01*
X242938Y216655D01*
X243351Y216578D01*
X243661Y216386D01*
X243816Y216041D01*
Y215121D01*
G01X242008Y218145D02*
X244230D01*
X244695Y218298D01*
X245005Y218605D01*
X245108Y218988D01*
X245005Y219371D01*
X244695Y219678D01*
X244230Y219831D01*
X242008D01*
G01X244643Y221245D02*
X244901Y221475D01*
X245056Y221743D01*
X245108Y222088D01*
X245005Y222433D01*
X244798Y222701D01*
X244436Y222893D01*
X244023Y222931D01*
X243610Y222855D01*
X243351Y222663D01*
X243145Y222395D01*
X243093Y222126D01*
X243145Y221858D01*
X243351Y221513D01*
X242008Y221628D01*
Y222663D01*
G01X244746Y224536D02*
X245005Y224805D01*
X245108Y225111D01*
X245005Y225418D01*
X244695Y225686D01*
X244230Y225878D01*
X243765Y225955D01*
X243196D01*
X242731Y225878D01*
X242318Y225686D01*
X242111Y225456D01*
X242008Y225188D01*
X242111Y224881D01*
X242318Y224651D01*
X242628Y224498D01*
X243041Y224421D01*
X243403Y224498D01*
X243765Y224690D01*
X243971Y224920D01*
X244023Y225188D01*
X243920Y225495D01*
X243661Y225725D01*
X243196Y225955D01*
G01X232148Y254969D02*
Y245521D01*
G01X242525Y231459D02*
X239325D01*
G01X242525Y237659D02*
Y231459D01*
G01X239325Y237659D02*
X242525D01*
G01X239325Y231459D02*
Y237659D01*
G01X234290Y231434D02*
X231090D01*
G01X234290Y237634D02*
Y231434D01*
G01X231090Y237634D02*
X234290D01*
G01X231090Y231434D02*
Y237634D01*
G01X235325Y237659D02*
X238525D01*
G01X235325Y231459D02*
Y237659D01*
G01X238525Y231459D02*
X235325D01*
G01X238525Y237659D02*
Y231459D01*
G01X233951Y240081D02*
Y243281D01*
G01X240151Y240081D02*
X233951D01*
G01X240151Y243281D02*
Y240081D01*
G01X233951Y243281D02*
X240151D01*
G01X239755Y252199D02*
Y248999D01*
G01X233555Y252199D02*
X239755D01*
G01X233555Y248999D02*
Y252199D01*
G01X239755Y248999D02*
X233555D01*
G01X235364Y386318D02*
Y383118D01*
G01Y382318D02*
Y379118D01*
G01Y394318D02*
Y391118D01*
G01Y390318D02*
Y387118D01*
G01Y398318D02*
Y395118D01*
G01Y402318D02*
Y399118D01*
G01Y406318D02*
Y403118D01*
G01Y410318D02*
Y407118D01*
G01Y414318D02*
Y411118D01*
G01X246785Y544312D02*
X252985D01*
G01X246785Y541112D02*
Y544312D01*
G01X252985Y541112D02*
X246785D01*
G01Y545112D02*
Y548312D01*
G01X252985Y545112D02*
X246785D01*
G01Y548312D02*
X252985D01*
G01X231700Y555300D02*
Y552100D01*
G01Y551300D02*
Y548100D01*
G01Y559300D02*
Y556100D01*
G01X244878Y619263D02*
X241678D01*
G01X244878Y625463D02*
Y619263D01*
G01X241678D02*
Y625463D01*
G01X248878Y619263D02*
X245678D01*
G01D02*
Y625463D01*
G01X241307Y635329D02*
X243031Y637329D01*
G01X241307Y631911D02*
Y635329D01*
G01X250755Y631911D02*
X241307D01*
G01X241678Y625463D02*
X244878D01*
G01X245678D02*
X248878D01*
G01X241307Y639329D02*
Y642747D01*
G01X243031Y637329D02*
X241307Y639329D01*
G01Y642747D02*
X250755D01*
G01X240502Y649146D02*
Y655346D01*
G01X243702Y649146D02*
X240502D01*
G01X243702Y655346D02*
Y649146D01*
G01X244502D02*
Y655346D01*
G01X247702Y649146D02*
X244502D01*
G01X240502Y655346D02*
X243702D01*
G01X244502D02*
X247702D01*
G01X234755Y659600D02*
X236977D01*
X237442Y659753D01*
X237752Y660060D01*
X237855Y660443D01*
X237752Y660826D01*
X237442Y661133D01*
X236977Y661286D01*
X234755D01*
G01X237855Y663543D02*
X234755D01*
X235375Y663083D01*
G01X237855D02*
Y664003D01*
G01X235272Y665915D02*
X234962Y666145D01*
X234807Y666413D01*
X234755Y666720D01*
X234858Y667103D01*
X235117Y667371D01*
X235427Y667448D01*
X235737Y667410D01*
X235995Y667256D01*
X236512Y666490D01*
X236873Y666145D01*
X237390Y665915D01*
X237855Y665838D01*
Y667448D01*
G01X240083Y658013D02*
Y673013D01*
G01X253083Y658013D02*
X240083D01*
G01X246525Y677432D02*
Y674232D01*
G01X240325Y677432D02*
X246525D01*
G01X240325Y674232D02*
Y677432D01*
G01X246525Y674232D02*
X240325D01*
G01X240083Y673013D02*
X253083D01*
G01X250986Y814700D02*
X244786D01*
Y817900D01*
X250986D01*
Y814700D01*
G01X248527Y826057D02*
X248889Y826287D01*
X249095Y826593D01*
X249147Y826938D01*
X249095Y827245D01*
X248837Y827552D01*
X248527Y827743D01*
X248217Y827782D01*
X247855Y827705D01*
X247597Y827437D01*
X247494Y827168D01*
Y826823D01*
G01Y827168D02*
X247339Y827398D01*
X247080Y827590D01*
X246770Y827667D01*
X246460Y827590D01*
X246202Y827398D01*
X246047Y827053D01*
X246099Y826708D01*
X246305Y826363D01*
G01X237314Y843850D02*
Y829950D01*
G01X249986Y835200D02*
X243786D01*
Y838400D01*
X249986D01*
Y835200D01*
G01X248527Y893357D02*
X248889Y893587D01*
X249095Y893893D01*
X249147Y894238D01*
X249095Y894545D01*
X248837Y894852D01*
X248527Y895043D01*
X248217Y895082D01*
X247855Y895005D01*
X247597Y894737D01*
X247494Y894468D01*
Y894123D01*
G01Y894468D02*
X247339Y894698D01*
X247080Y894890D01*
X246770Y894967D01*
X246460Y894890D01*
X246202Y894698D01*
X246047Y894353D01*
X246099Y894008D01*
X246305Y893663D01*
G01X237314Y911150D02*
Y897250D01*
G01X234898Y1474040D02*
Y1480240D01*
X238098D01*
Y1474040D01*
X234898D01*
G01X232143Y1480042D02*
Y1476842D01*
G01Y1484042D02*
Y1480842D01*
G01Y1488042D02*
Y1484842D01*
G01Y1492042D02*
Y1488842D01*
G01X250985Y1504458D02*
X244785D01*
Y1507658D01*
X250985D01*
Y1504458D01*
G01X234143Y1512042D02*
Y1508842D01*
G01X234148Y1516178D02*
Y1512978D01*
G01X244966Y1512569D02*
Y1515769D01*
G01X251166Y1512569D02*
X244966D01*
G01Y1508542D02*
Y1511742D01*
G01X251166Y1508542D02*
X244966D01*
G01Y1511742D02*
X251166D01*
G01X242442Y1531985D02*
Y1525785D01*
X239242D01*
Y1531985D01*
X242442D01*
G01X249642D02*
Y1525785D01*
X246442D01*
Y1531985D01*
X249642D01*
G01X234148Y1520178D02*
Y1516978D01*
G01Y1528178D02*
Y1524978D01*
G01Y1524178D02*
Y1520978D01*
G01X244966Y1515769D02*
X251166D01*
G01X239542Y1550985D02*
Y1544785D01*
X236342D01*
Y1550985D01*
X239542D01*
G01X246542D02*
Y1544785D01*
X243342D01*
Y1550985D01*
X246542D01*
G01X235542D02*
Y1544785D01*
X232342D01*
Y1550985D01*
X235542D01*
G01X232153Y1538815D02*
X235353D01*
G01X232153Y1532615D02*
Y1538815D01*
G01X235353Y1532615D02*
X232153D01*
G01X235353Y1538815D02*
Y1532615D01*
G01X239353D02*
X236153D01*
G01X239353Y1538815D02*
Y1532615D01*
G01X236153Y1538815D02*
X239353D01*
G01X236153Y1532615D02*
Y1538815D01*
G01X231353D02*
Y1532615D01*
G01X231379Y1560185D02*
X231571Y1559875D01*
X231801Y1559668D01*
X232069Y1559565D01*
X232376Y1559668D01*
X232606Y1559875D01*
X232836Y1560185D01*
X232913Y1560598D01*
Y1562665D01*
G01X234518Y1560857D02*
X234786Y1561218D01*
X235016Y1561425D01*
X235323Y1561528D01*
X235591Y1561425D01*
X235783Y1561218D01*
X235936Y1560908D01*
X235974Y1560547D01*
X235936Y1560237D01*
X235783Y1559927D01*
X235553Y1559668D01*
X235284Y1559565D01*
X234978Y1559668D01*
X234709Y1559978D01*
X234556Y1560443D01*
X234518Y1560960D01*
X234594Y1561632D01*
X234709Y1561993D01*
X234901Y1562355D01*
X235169Y1562613D01*
X235438Y1562665D01*
X235706Y1562562D01*
X235898Y1562303D01*
G01X237503Y1560185D02*
X237733Y1559823D01*
X238039Y1559617D01*
X238384Y1559565D01*
X238691Y1559617D01*
X238998Y1559875D01*
X239189Y1560185D01*
X239228Y1560495D01*
X239151Y1560857D01*
X238883Y1561115D01*
X238614Y1561218D01*
X238269D01*
G01X238614D02*
X238844Y1561373D01*
X239036Y1561632D01*
X239113Y1561942D01*
X239036Y1562252D01*
X238844Y1562510D01*
X238499Y1562665D01*
X238154Y1562613D01*
X237809Y1562407D01*
G01X268169Y57756D02*
X261788D01*
G01X267873Y58150D02*
X262193D01*
G01X254819Y156615D02*
X255566Y155990D01*
X256406Y155615D01*
X257152D01*
X257899Y155990D01*
X258459Y156615D01*
X258739Y157490D01*
X258552Y158365D01*
X258086Y159115D01*
X257246Y159615D01*
X256126Y159865D01*
X255472Y160365D01*
X255192Y161240D01*
X255379Y162115D01*
X255846Y162740D01*
X256499Y163115D01*
X257152D01*
X257806Y162865D01*
X258366Y162240D01*
G01X262319Y156615D02*
X263066Y155990D01*
X263906Y155615D01*
X264652D01*
X265399Y155990D01*
X265959Y156615D01*
X266239Y157490D01*
X266052Y158365D01*
X265586Y159115D01*
X264746Y159615D01*
X263626Y159865D01*
X262972Y160365D01*
X262692Y161240D01*
X262879Y162115D01*
X263346Y162740D01*
X263999Y163115D01*
X264652D01*
X265306Y162865D01*
X265866Y162240D01*
G01X269726Y155615D02*
Y163115D01*
X271592D01*
X272339Y162740D01*
X272899Y162240D01*
X273366Y161490D01*
X273739Y160615D01*
X273832Y159365D01*
X273739Y158115D01*
X273366Y157240D01*
X272899Y156490D01*
X272339Y155990D01*
X271592Y155615D01*
X269726D01*
G01X277506Y161865D02*
X278066Y162615D01*
X278719Y162990D01*
X279466Y163115D01*
X280399Y162865D01*
X281052Y162240D01*
X281239Y161490D01*
X281146Y160740D01*
X280772Y160115D01*
X278906Y158865D01*
X278066Y157990D01*
X277506Y156740D01*
X277319Y155615D01*
X281239D01*
G01X260269Y164436D02*
X275069D01*
G01X260269Y195440D02*
Y164436D01*
G01X261788Y153150D02*
X268169D01*
G01X262193Y152756D02*
X267873D01*
G01X275069Y195440D02*
X260269D01*
G01X264272Y199912D02*
Y202338D01*
G01X257400Y204383D02*
X254300D01*
Y205303D01*
X254455Y205610D01*
X254817Y205840D01*
X255230Y205917D01*
X255643Y205840D01*
X255953Y205648D01*
X256108Y205303D01*
Y204383D01*
G01X257400Y207407D02*
X254300D01*
Y208173D01*
X254455Y208480D01*
X254662Y208710D01*
X254972Y208902D01*
X255333Y209055D01*
X255850Y209093D01*
X256367Y209055D01*
X256728Y208902D01*
X257038Y208710D01*
X257245Y208480D01*
X257400Y208173D01*
Y207407D01*
G01X256780Y210507D02*
X257142Y210737D01*
X257348Y211043D01*
X257400Y211388D01*
X257348Y211695D01*
X257090Y212002D01*
X256780Y212193D01*
X256470Y212232D01*
X256108Y212155D01*
X255850Y211887D01*
X255747Y211618D01*
Y211273D01*
G01Y211618D02*
X255592Y211848D01*
X255333Y212040D01*
X255023Y212117D01*
X254713Y212040D01*
X254455Y211848D01*
X254300Y211503D01*
X254352Y211158D01*
X254558Y210813D01*
G01X254300Y214450D02*
X254403Y214143D01*
X254662Y213913D01*
X254972Y213760D01*
X255385Y213645D01*
X255850Y213607D01*
X256315Y213645D01*
X256728Y213760D01*
X257038Y213913D01*
X257297Y214143D01*
X257400Y214450D01*
X257297Y214757D01*
X257038Y214987D01*
X256728Y215140D01*
X256315Y215255D01*
X255850Y215293D01*
X255385Y215255D01*
X254972Y215140D01*
X254662Y214987D01*
X254403Y214757D01*
X254300Y214450D01*
G01X270320Y203452D02*
X258824D01*
G01D02*
Y233011D01*
G01X264172Y236652D02*
Y234412D01*
G01X265797Y235625D02*
X262547D01*
G01X258824Y233011D02*
X270320D01*
G01X264041Y259204D02*
Y261630D01*
G01X257400Y263383D02*
X254300D01*
Y264303D01*
X254455Y264610D01*
X254817Y264840D01*
X255230Y264917D01*
X255643Y264840D01*
X255953Y264648D01*
X256108Y264303D01*
Y263383D01*
G01X257400Y266407D02*
X254300D01*
Y267173D01*
X254455Y267480D01*
X254662Y267710D01*
X254972Y267902D01*
X255333Y268055D01*
X255850Y268093D01*
X256367Y268055D01*
X256728Y267902D01*
X257038Y267710D01*
X257245Y267480D01*
X257400Y267173D01*
Y266407D01*
G01X257038Y269698D02*
X257297Y269967D01*
X257400Y270273D01*
X257297Y270580D01*
X256987Y270848D01*
X256522Y271040D01*
X256057Y271117D01*
X255488D01*
X255023Y271040D01*
X254610Y270848D01*
X254403Y270618D01*
X254300Y270350D01*
X254403Y270043D01*
X254610Y269813D01*
X254920Y269660D01*
X255333Y269583D01*
X255695Y269660D01*
X256057Y269852D01*
X256263Y270082D01*
X256315Y270350D01*
X256212Y270657D01*
X255953Y270887D01*
X255488Y271117D01*
G01X254300Y273450D02*
X254403Y273143D01*
X254662Y272913D01*
X254972Y272760D01*
X255385Y272645D01*
X255850Y272607D01*
X256315Y272645D01*
X256728Y272760D01*
X257038Y272913D01*
X257297Y273143D01*
X257400Y273450D01*
X257297Y273757D01*
X257038Y273987D01*
X256728Y274140D01*
X256315Y274255D01*
X255850Y274293D01*
X255385Y274255D01*
X254972Y274140D01*
X254662Y273987D01*
X254403Y273757D01*
X254300Y273450D01*
G01X270089Y262744D02*
X258593D01*
G01D02*
Y292303D01*
G01X262594Y297816D02*
Y295576D01*
G01X264219Y296789D02*
X260969D01*
G01X258593Y292303D02*
X270089D01*
G01X263380Y366183D02*
X263690Y366375D01*
X263897Y366605D01*
X264000Y366873D01*
X263897Y367180D01*
X263690Y367410D01*
X263380Y367640D01*
X262967Y367717D01*
X260900D01*
G01X261417Y369322D02*
X261107Y369552D01*
X260952Y369820D01*
X260900Y370127D01*
X261003Y370510D01*
X261262Y370778D01*
X261572Y370855D01*
X261882Y370817D01*
X262140Y370663D01*
X262657Y369897D01*
X263018Y369552D01*
X263535Y369322D01*
X264000Y369245D01*
Y370855D01*
G01Y373150D02*
X260900D01*
X261520Y372690D01*
G01X264000D02*
Y373610D01*
G01X253800Y460459D02*
Y457259D01*
G01X247600D02*
Y460459D01*
G01X253800Y457259D02*
X247600D01*
G01X253800Y455473D02*
Y452273D01*
G01X247600Y455473D02*
X253800D01*
G01X247600Y452273D02*
Y455473D01*
G01X253800Y452273D02*
X247600D01*
G01Y444273D02*
Y447473D01*
G01X253800Y444273D02*
X247600D01*
G01X253800Y447473D02*
Y444273D01*
G01X247600Y447473D02*
X253800D01*
G01X247600Y448273D02*
Y451473D01*
G01X253800Y448273D02*
X247600D01*
G01X253800Y451473D02*
Y448273D01*
G01X247600Y451473D02*
X253800D01*
G01X247600Y460459D02*
X253800D01*
G01X247600Y461259D02*
Y464459D01*
G01X253800Y461259D02*
X247600D01*
G01X253800Y464459D02*
Y461259D01*
G01X247600Y464459D02*
X253800D01*
G01X252985Y544312D02*
Y541112D01*
G01Y548312D02*
Y545112D01*
G01X248878Y625463D02*
Y619263D01*
G01X252878D02*
X249678D01*
G01X252878Y625463D02*
Y619263D01*
G01X249678D02*
Y625463D01*
G01X255400Y631950D02*
X255348Y631643D01*
X255142Y631375D01*
X254832Y631145D01*
X254470Y630992D01*
X254057Y630915D01*
X253643D01*
X253230Y630992D01*
X252868Y631145D01*
X252558Y631375D01*
X252352Y631643D01*
X252300Y631950D01*
X252352Y632257D01*
X252558Y632525D01*
X252868Y632755D01*
X253230Y632908D01*
X253643Y632985D01*
X254057D01*
X254470Y632908D01*
X254832Y632755D01*
X255142Y632525D01*
X255348Y632257D01*
X255400Y631950D01*
G01X254573Y632257D02*
X255400Y632717D01*
G01Y635050D02*
X252300D01*
X252920Y634590D01*
G01X255400D02*
Y635510D01*
G01Y638150D02*
X252300D01*
X252920Y637690D01*
G01X255400D02*
Y638610D01*
G01X255038Y640598D02*
X255297Y640867D01*
X255400Y641173D01*
X255297Y641480D01*
X254987Y641748D01*
X254522Y641940D01*
X254057Y642017D01*
X253488D01*
X253023Y641940D01*
X252610Y641748D01*
X252403Y641518D01*
X252300Y641250D01*
X252403Y640943D01*
X252610Y640713D01*
X252920Y640560D01*
X253333Y640483D01*
X253695Y640560D01*
X254057Y640752D01*
X254263Y640982D01*
X254315Y641250D01*
X254212Y641557D01*
X253953Y641787D01*
X253488Y642017D01*
G01X250755Y642747D02*
Y631911D01*
G01X249678Y625463D02*
X252878D01*
G01X247702Y655346D02*
Y649146D01*
G01X248502D02*
Y655346D01*
G01X251702Y649146D02*
X248502D01*
G01X251702Y655346D02*
Y649146D01*
G01X248502Y655346D02*
X251702D01*
G01X253083Y673013D02*
Y658013D01*
G01X247165Y674289D02*
Y677489D01*
G01X253365Y674289D02*
X247165D01*
G01X253365Y677489D02*
Y674289D01*
G01X247165Y677489D02*
X253365D01*
G01X254706Y1455551D02*
X254331Y1454991D01*
X254081Y1454338D01*
Y1453591D01*
X254456Y1452751D01*
X255081Y1452098D01*
X255831Y1451631D01*
X257081Y1451258D01*
X258206Y1451165D01*
X259331Y1451351D01*
X260081Y1451631D01*
X260831Y1452191D01*
X261331Y1452845D01*
X261581Y1453498D01*
Y1454151D01*
X261331Y1454805D01*
X260956Y1455365D01*
X260456Y1455831D01*
G01X261581Y1459131D02*
X254081D01*
Y1461371D01*
X254456Y1462118D01*
X255331Y1462678D01*
X256331Y1462865D01*
X257331Y1462678D01*
X258081Y1462211D01*
X258456Y1461371D01*
Y1459131D01*
G01X254081Y1466445D02*
X259456D01*
X260581Y1466818D01*
X261331Y1467565D01*
X261581Y1468498D01*
X261331Y1469431D01*
X260581Y1470178D01*
X259456Y1470551D01*
X254081D01*
G01X264081Y1473198D02*
Y1478798D01*
G01X257831Y1484058D02*
Y1485925D01*
X260081D01*
X260831Y1485365D01*
X261331Y1484711D01*
X261581Y1483778D01*
X261331Y1482845D01*
X260831Y1482191D01*
X260081Y1481631D01*
X259206Y1481258D01*
X258206Y1481071D01*
X257331D01*
X256581Y1481258D01*
X255706Y1481631D01*
X254956Y1482191D01*
X254456Y1482751D01*
X254081Y1483498D01*
Y1484151D01*
X254331Y1484898D01*
X254831Y1485458D01*
G01X251166Y1515769D02*
Y1512569D01*
G01Y1511742D02*
Y1508542D01*
G01X253285Y1516358D02*
X247085D01*
Y1519558D01*
X253285D01*
Y1516358D01*
G01X249311Y1564843D02*
Y1690040D01*
G01X261865Y1608930D02*
X262665Y1609430D01*
X263198Y1610030D01*
X263465Y1610730D01*
X263198Y1611530D01*
X262665Y1612130D01*
X261865Y1612730D01*
X260798Y1612930D01*
X255465D01*
G01X263465Y1618930D02*
X255465D01*
X257065Y1617730D01*
G01X263465D02*
Y1620130D01*
G01Y1626930D02*
X255465D01*
X257065Y1625730D01*
G01X263465D02*
Y1628130D01*
G01X268169Y57756D02*
Y104422D01*
G01X267873Y58150D02*
Y104422D01*
G01X273701Y97026D02*
Y103226D01*
G01X276901Y97026D02*
X273701D01*
G01X276901Y103226D02*
Y97026D01*
G01X279705Y86929D02*
X276505D01*
G01Y93129D02*
X279705D01*
G01X276505Y86929D02*
Y93129D01*
G01X275705Y86929D02*
X272505D01*
G01X275705Y93129D02*
Y86929D01*
G01X272505Y93129D02*
X275705D01*
G01X272505Y86929D02*
Y93129D01*
G01X268169Y111507D02*
Y107060D01*
G01X267873Y111507D02*
Y107060D01*
G01Y118680D02*
Y114087D01*
G01X268169Y118680D02*
Y114087D01*
G01X273701Y103226D02*
X276901D01*
G01X267873Y132859D02*
Y128325D01*
G01X268169Y132859D02*
Y128325D01*
G01Y125844D02*
Y121329D01*
G01X267873Y125844D02*
Y121329D01*
G01Y152756D02*
Y135450D01*
G01X268169Y153150D02*
Y135450D01*
G01X277399Y145940D02*
Y149140D01*
G01X283599Y145940D02*
X277399D01*
G01Y149140D02*
X283599D01*
G01X275069Y164436D02*
Y195440D01*
G01X277399Y153140D02*
X283599D01*
G01X277399Y149940D02*
Y153140D01*
G01X283599Y149940D02*
X277399D01*
G01X280035Y171473D02*
X276835D01*
G01Y177673D02*
X280035D01*
G01X276835Y171473D02*
Y177673D01*
G01X272382Y213035D02*
Y225035D01*
G01X278382Y213035D02*
X272382D01*
G01X278382Y225035D02*
Y213035D01*
G01X270320Y233011D02*
Y203452D01*
G01X272382Y225035D02*
X278382D01*
G01X279222Y226621D02*
Y232621D01*
G01X291222Y226621D02*
X279222D01*
G01Y232621D02*
X291222D01*
G01X271665Y250325D02*
Y234813D01*
G01D02*
X302757D01*
G01X270089Y292303D02*
Y262744D01*
G01X267352Y251746D02*
Y254846D01*
X268272D01*
X268579Y254691D01*
X268809Y254329D01*
X268886Y253916D01*
X268809Y253503D01*
X268617Y253193D01*
X268272Y253038D01*
X267352D01*
G01X270376Y251746D02*
Y254846D01*
X271142D01*
X271449Y254691D01*
X271679Y254484D01*
X271871Y254174D01*
X272024Y253813D01*
X272062Y253296D01*
X272024Y252779D01*
X271871Y252418D01*
X271679Y252108D01*
X271449Y251901D01*
X271142Y251746D01*
X270376D01*
G01X273591Y254329D02*
X273821Y254639D01*
X274089Y254794D01*
X274396Y254846D01*
X274779Y254743D01*
X275047Y254484D01*
X275124Y254174D01*
X275086Y253864D01*
X274932Y253606D01*
X274166Y253089D01*
X273821Y252728D01*
X273591Y252211D01*
X273514Y251746D01*
X275124D01*
G01X276767Y252108D02*
X277036Y251849D01*
X277342Y251746D01*
X277649Y251849D01*
X277917Y252159D01*
X278109Y252624D01*
X278186Y253089D01*
Y253658D01*
X278109Y254123D01*
X277917Y254536D01*
X277687Y254743D01*
X277419Y254846D01*
X277112Y254743D01*
X276882Y254536D01*
X276729Y254226D01*
X276652Y253813D01*
X276729Y253451D01*
X276921Y253089D01*
X277151Y252883D01*
X277419Y252831D01*
X277726Y252934D01*
X277956Y253193D01*
X278186Y253658D01*
G01X302757Y250325D02*
X271665D01*
G01X271960Y271655D02*
Y283655D01*
G01X277960Y271655D02*
X271960D01*
G01X277960Y283655D02*
Y271655D01*
G01X271960Y283655D02*
X277960D01*
G01X282143Y283383D02*
X278943D01*
G01Y289583D02*
X282143D01*
G01X278943Y283383D02*
Y289583D01*
G01X265640Y366063D02*
X273086D01*
G01X265640Y418006D02*
Y366063D01*
G01Y425116D02*
Y467867D01*
G01Y474925D02*
Y470260D01*
G01Y489023D02*
Y484398D01*
G01Y481999D02*
Y477273D01*
G01Y511780D02*
Y491483D01*
G01Y526062D02*
Y521356D01*
G01Y519090D02*
Y514395D01*
G01Y546456D02*
Y535678D01*
G01Y533279D02*
Y528543D01*
G01Y553556D02*
Y562026D01*
G01Y576183D02*
Y571518D01*
G01Y569098D02*
Y564383D01*
G01Y590310D02*
Y585655D01*
G01Y583287D02*
Y578613D01*
G01Y604489D02*
Y599824D01*
G01Y597384D02*
Y592730D01*
G01Y639449D02*
Y613963D01*
G01Y611543D02*
Y606908D01*
G01X280418Y646592D02*
X264818D01*
X280418Y655562D01*
X264818D01*
G01Y666637D02*
Y671317D01*
G01Y668977D02*
X280418D01*
G01Y666637D02*
Y671317D01*
G01X266118Y691167D02*
X265338Y689997D01*
X264818Y688632D01*
Y687072D01*
X265598Y685317D01*
X266898Y683952D01*
X268458Y682977D01*
X271058Y682197D01*
X273398Y682002D01*
X275738Y682392D01*
X277298Y682977D01*
X278858Y684147D01*
X279898Y685512D01*
X280418Y686877D01*
Y688242D01*
X279898Y689607D01*
X279118Y690777D01*
X278078Y691752D01*
G01X280418Y704777D02*
X264818D01*
X267938Y702437D01*
G01X280418D02*
Y707117D01*
G01X273136Y639449D02*
X265640D01*
G01X278900Y854114D02*
Y860314D01*
X282100D01*
Y854114D01*
X278900D01*
G01Y864214D02*
Y870414D01*
X282100D01*
Y864214D01*
X278900D01*
G01X266378Y1425158D02*
Y1689331D01*
G01X379370Y1425158D02*
X266378D01*
G01X278189Y1677520D02*
Y1436969D01*
G01D02*
X367559D01*
G01X278189Y1647993D02*
X367559D01*
G01X266378Y1689331D02*
X379370D01*
G01X367559Y1677520D02*
X278189D01*
G01X291818Y12065D02*
X318966D01*
G01X291818Y31751D02*
Y12065D01*
G01X282269Y25556D02*
Y28756D01*
G01X288469Y25556D02*
X282269D01*
G01X288469Y28756D02*
Y25556D01*
G01X282269Y28756D02*
X288469D01*
G01X299549Y31751D02*
X291818D01*
G01X294760Y66981D02*
Y70181D01*
G01X300960Y66981D02*
X294760D01*
G01X284094Y82540D02*
Y85740D01*
G01X290294Y82540D02*
X284094D01*
G01X290294Y85740D02*
Y82540D01*
G01X284094Y74540D02*
Y77740D01*
G01X290294Y74540D02*
X284094D01*
G01X290294Y77740D02*
Y74540D01*
G01X284094Y77740D02*
X290294D01*
G01X284094Y78540D02*
Y81740D01*
G01X290294Y78540D02*
X284094D01*
G01X290294Y81740D02*
Y78540D01*
G01X284094Y81740D02*
X290294D01*
G01X294760Y70181D02*
X300960D01*
G01X294760Y82181D02*
X300960D01*
G01X294760Y78981D02*
Y82181D01*
G01X300960Y78981D02*
X294760D01*
G01X294805Y74987D02*
Y78187D01*
G01X301005Y74987D02*
X294805D01*
G01Y78187D02*
X301005D01*
G01X294805Y70987D02*
Y74187D01*
G01X301005Y70987D02*
X294805D01*
G01Y74187D02*
X301005D01*
G01X279705Y93129D02*
Y86929D01*
G01X283705D02*
X280505D01*
G01X283705Y93129D02*
Y86929D01*
G01X280505Y93129D02*
X283705D01*
G01X280505Y86929D02*
Y93129D01*
G01X284094Y85740D02*
X290294D01*
G01X287714Y86929D02*
X284514D01*
G01X287714Y93129D02*
Y86929D01*
G01X284514Y93129D02*
X287714D01*
G01X284514Y86929D02*
Y93129D01*
G01X279784Y96673D02*
Y102873D01*
G01X282984Y96673D02*
X279784D01*
G01X282984Y102873D02*
Y96673D01*
G01X289288Y95950D02*
Y102150D01*
G01X292488Y95950D02*
X289288D01*
G01X292488Y102150D02*
Y95950D01*
G01X283784Y96673D02*
Y102873D01*
G01X286984Y96673D02*
X283784D01*
G01X286984Y102873D02*
Y96673D01*
G01X293952Y95913D02*
Y111267D01*
G01X306433Y95913D02*
X293952D01*
G01X279784Y102873D02*
X282984D01*
G01X289288Y102150D02*
X292488D01*
G01X283784Y102873D02*
X286984D01*
G01X289288Y109762D02*
X292488D01*
G01X289288Y103562D02*
Y109762D01*
G01X292488Y103562D02*
X289288D01*
G01X292488Y109762D02*
Y103562D01*
G01X293952Y111267D02*
X306630D01*
G01X285767Y144690D02*
Y154138D01*
G01X296603Y144690D02*
X285767D01*
G01X283599Y149140D02*
Y145940D01*
G01X288348Y139647D02*
Y142847D01*
G01X294548Y139647D02*
X288348D01*
G01X294548Y142847D02*
Y139647D01*
G01X288348Y142847D02*
X294548D01*
G01X281369Y139647D02*
Y142847D01*
G01X287569Y139647D02*
X281369D01*
G01X287569Y142847D02*
Y139647D01*
G01X281369Y142847D02*
X287569D01*
G01X286150Y155400D02*
X285843Y155452D01*
X285575Y155658D01*
X285345Y155968D01*
X285192Y156330D01*
X285115Y156743D01*
Y157157D01*
X285192Y157570D01*
X285345Y157932D01*
X285575Y158242D01*
X285843Y158448D01*
X286150Y158500D01*
X286457Y158448D01*
X286725Y158242D01*
X286955Y157932D01*
X287108Y157570D01*
X287185Y157157D01*
Y156743D01*
X287108Y156330D01*
X286955Y155968D01*
X286725Y155658D01*
X286457Y155452D01*
X286150Y155400D01*
G01X286457Y156227D02*
X286917Y155400D01*
G01X289250D02*
Y158500D01*
X288790Y157880D01*
G01Y155400D02*
X289710D01*
G01X291507Y156020D02*
X291737Y155658D01*
X292043Y155452D01*
X292388Y155400D01*
X292695Y155452D01*
X293002Y155710D01*
X293193Y156020D01*
X293232Y156330D01*
X293155Y156692D01*
X292887Y156950D01*
X292618Y157053D01*
X292273D01*
G01X292618D02*
X292848Y157208D01*
X293040Y157467D01*
X293117Y157777D01*
X293040Y158087D01*
X292848Y158345D01*
X292503Y158500D01*
X292158Y158448D01*
X291813Y158242D01*
G01X294722Y156692D02*
X294990Y157053D01*
X295220Y157260D01*
X295527Y157363D01*
X295795Y157260D01*
X295987Y157053D01*
X296140Y156743D01*
X296178Y156382D01*
X296140Y156072D01*
X295987Y155762D01*
X295757Y155503D01*
X295488Y155400D01*
X295182Y155503D01*
X294913Y155813D01*
X294760Y156278D01*
X294722Y156795D01*
X294798Y157467D01*
X294913Y157828D01*
X295105Y158190D01*
X295373Y158448D01*
X295642Y158500D01*
X295910Y158397D01*
X296102Y158138D01*
G01X293185Y154138D02*
X296603D01*
G01X291185Y152414D02*
X293185Y154138D01*
G01X289185D02*
X291185Y152414D01*
G01X285767Y154138D02*
X289185D01*
G01X283599Y153140D02*
Y149940D01*
G01X290657Y175100D02*
Y172878D01*
X290810Y172413D01*
X291117Y172103D01*
X291500Y172000D01*
X291883Y172103D01*
X292190Y172413D01*
X292343Y172878D01*
Y175100D01*
G01X293757Y172465D02*
X293987Y172207D01*
X294255Y172052D01*
X294600Y172000D01*
X294945Y172103D01*
X295213Y172310D01*
X295405Y172672D01*
X295443Y173085D01*
X295367Y173498D01*
X295175Y173757D01*
X294907Y173963D01*
X294638Y174015D01*
X294370Y173963D01*
X294025Y173757D01*
X294140Y175100D01*
X295175D01*
G01X296857Y172465D02*
X297087Y172207D01*
X297355Y172052D01*
X297700Y172000D01*
X298045Y172103D01*
X298313Y172310D01*
X298505Y172672D01*
X298543Y173085D01*
X298467Y173498D01*
X298275Y173757D01*
X298007Y173963D01*
X297738Y174015D01*
X297470Y173963D01*
X297125Y173757D01*
X297240Y175100D01*
X298275D01*
G01X288763Y176944D02*
Y178897D01*
G01X290716Y176944D02*
X288763D01*
G01X284035Y171473D02*
X280835D01*
G01X284035Y177673D02*
Y171473D01*
G01X280835Y177673D02*
X284035D01*
G01X280835Y171473D02*
Y177673D01*
G01X280035D02*
Y171473D01*
G01X287058Y170297D02*
Y167097D01*
G01X280858Y170297D02*
X287058D01*
G01X280858Y167097D02*
Y170297D01*
G01X287058Y167097D02*
X280858D01*
G01X288763Y188756D02*
X290716D01*
G01X288763Y186803D02*
Y188756D01*
G01X287253Y193541D02*
Y190341D01*
G01X281053Y193541D02*
X287253D01*
G01X281053Y190341D02*
Y193541D01*
G01X287253Y190341D02*
X281053D01*
G01X284262Y182730D02*
X281062D01*
G01X284262Y188930D02*
Y182730D01*
G01X281062Y188930D02*
X284262D01*
G01X281062Y182730D02*
Y188930D01*
G01X287402Y201473D02*
Y204573D01*
X288322D01*
X288629Y204418D01*
X288859Y204056D01*
X288936Y203643D01*
X288859Y203230D01*
X288667Y202920D01*
X288322Y202765D01*
X287402D01*
G01X290426Y204573D02*
Y202351D01*
X290579Y201886D01*
X290886Y201576D01*
X291269Y201473D01*
X291652Y201576D01*
X291959Y201886D01*
X292112Y202351D01*
Y204573D01*
G01X293526Y202093D02*
X293756Y201731D01*
X294062Y201525D01*
X294407Y201473D01*
X294714Y201525D01*
X295021Y201783D01*
X295212Y202093D01*
X295251Y202403D01*
X295174Y202765D01*
X294906Y203023D01*
X294637Y203126D01*
X294292D01*
G01X294637D02*
X294867Y203281D01*
X295059Y203540D01*
X295136Y203850D01*
X295059Y204160D01*
X294867Y204418D01*
X294522Y204573D01*
X294177Y204521D01*
X293832Y204315D01*
G01X297929Y201473D02*
Y204573D01*
X296511Y202351D01*
X298427D01*
G01X301538Y220252D02*
Y208048D01*
X286234D01*
Y220252D01*
X301538D01*
G01X291222Y232621D02*
Y226621D01*
G01X289222Y225921D02*
Y222721D01*
G01X283022Y225921D02*
X289222D01*
G01X283022Y222721D02*
Y225921D01*
G01X289222Y222721D02*
X283022D01*
G01X283201Y215082D02*
X280001D01*
G01X283201Y221282D02*
Y215082D01*
G01X280001Y221282D02*
X283201D01*
G01X280001Y215082D02*
Y221282D01*
G01X287890Y258010D02*
Y264210D01*
G01X291090Y258010D02*
X287890D01*
G01X291090Y264210D02*
Y258010D01*
G01X279890D02*
Y264210D01*
G01X283090Y258010D02*
X279890D01*
G01X283090Y264210D02*
Y258010D01*
G01X287090D02*
X283890D01*
G01X287090Y264210D02*
Y258010D01*
G01X283890D02*
Y264210D01*
G01X295531Y255580D02*
X292431D01*
Y256500D01*
X292586Y256807D01*
X292948Y257037D01*
X293361Y257114D01*
X293774Y257037D01*
X294084Y256845D01*
X294239Y256500D01*
Y255580D01*
G01X292431Y258604D02*
X294653D01*
X295118Y258757D01*
X295428Y259064D01*
X295531Y259447D01*
X295428Y259830D01*
X295118Y260137D01*
X294653Y260290D01*
X292431D01*
G01X295531Y262470D02*
X294859Y262547D01*
X294291Y262662D01*
X293774Y262815D01*
X293206Y263007D01*
X292431Y263314D01*
Y261780D01*
G01X295531Y265647D02*
X295479Y265915D01*
X295324Y266222D01*
X295066Y266414D01*
X294704Y266490D01*
X294343Y266414D01*
X294033Y266184D01*
X293878Y265839D01*
Y265455D01*
X293774Y265225D01*
X293516Y265034D01*
X293154Y264957D01*
X292793Y265072D01*
X292534Y265340D01*
X292431Y265647D01*
X292534Y265954D01*
X292793Y266222D01*
X293154Y266337D01*
X293516Y266260D01*
X293774Y266069D01*
X293878Y265839D01*
Y265455D01*
X294033Y265110D01*
X294343Y264880D01*
X294704Y264804D01*
X295066Y264880D01*
X295324Y265072D01*
X295479Y265379D01*
X295531Y265647D01*
G01X287890Y264210D02*
X291090D01*
G01X296169Y273701D02*
X292969D01*
G01D02*
Y279901D01*
G01X279890Y264210D02*
X283090D01*
G01X283890D02*
X287090D01*
G01X290611Y279427D02*
Y267653D01*
G01X280849D02*
Y279427D01*
G01X290611Y267653D02*
X280849D01*
G01X292969Y279901D02*
X296169D01*
G01X282143Y289583D02*
Y283383D01*
G01X286143D02*
X282943D01*
G01X286143Y289583D02*
Y283383D01*
G01X282943Y289583D02*
X286143D01*
G01X282943Y283383D02*
Y289583D01*
G01X286943Y283383D02*
Y289583D01*
X290143D01*
Y283383D01*
X286943D01*
G01X280849Y279427D02*
X290611D01*
G01X285415Y316273D02*
Y319473D01*
G01X291615Y316273D02*
X285415D01*
G01X291615Y319473D02*
Y316273D01*
G01X285415Y319473D02*
X291615D01*
G01X285656Y366063D02*
X301132D01*
G01X289920Y655146D02*
X289140Y653976D01*
X288620Y652611D01*
Y651051D01*
X289400Y649296D01*
X290700Y647931D01*
X292260Y646956D01*
X294860Y646176D01*
X297200Y645981D01*
X299540Y646371D01*
X301100Y646956D01*
X302660Y648126D01*
X303700Y649491D01*
X304220Y650856D01*
Y652221D01*
X303700Y653586D01*
X302920Y654756D01*
X301880Y655731D01*
G01X295900Y670316D02*
X295120Y671096D01*
X293820Y671681D01*
X292000Y672071D01*
X290440Y671681D01*
X289400Y670901D01*
X288620Y669536D01*
Y664271D01*
X304220D01*
Y670706D01*
X303180Y672071D01*
X301620Y672851D01*
X299800Y673241D01*
X297980Y672851D01*
X296420Y671681D01*
X295900Y670316D01*
Y664271D01*
G01X288620Y682756D02*
X304220D01*
Y690556D01*
G01X309420Y698706D02*
Y710406D01*
G01X295900Y724016D02*
X295120Y724796D01*
X293820Y725381D01*
X292000Y725771D01*
X290440Y725381D01*
X289400Y724601D01*
X288620Y723236D01*
Y717971D01*
X304220D01*
Y724406D01*
X303180Y725771D01*
X301620Y726551D01*
X299800Y726941D01*
X297980Y726551D01*
X296420Y725381D01*
X295900Y724016D01*
Y717971D01*
G01X304220Y740356D02*
X303960Y738796D01*
X302920Y737431D01*
X301360Y736261D01*
X299540Y735481D01*
X297460Y735091D01*
X295380D01*
X293300Y735481D01*
X291480Y736261D01*
X289920Y737431D01*
X288880Y738796D01*
X288620Y740356D01*
X288880Y741916D01*
X289920Y743281D01*
X291480Y744451D01*
X293300Y745231D01*
X295380Y745621D01*
X297460D01*
X299540Y745231D01*
X301360Y744451D01*
X302920Y743281D01*
X303960Y741916D01*
X304220Y740356D01*
G01X288620Y758256D02*
X304220D01*
G01X288620Y753771D02*
Y762741D01*
G01X301132Y639449D02*
X285586D01*
G01X284700Y889314D02*
Y895514D01*
X287900D01*
Y889314D01*
X284700D01*
G01Y899614D02*
Y905814D01*
X287900D01*
Y899614D01*
X284700D01*
G01X280700Y924814D02*
Y931014D01*
X283900D01*
Y924814D01*
X280700D01*
G01X280800Y934914D02*
Y941114D01*
X284000D01*
Y934914D01*
X280800D01*
G01X311998Y-529168D02*
X312598Y-528368D01*
X313298Y-527968D01*
X314098Y-527835D01*
X315098Y-528102D01*
X315798Y-528768D01*
X315998Y-529568D01*
X315898Y-530369D01*
X315498Y-531035D01*
X313498Y-532368D01*
X312598Y-533302D01*
X311998Y-534635D01*
X311798Y-535835D01*
X315998D01*
G01X321898Y-527835D02*
X321098Y-528102D01*
X320498Y-528768D01*
X320098Y-529568D01*
X319798Y-530635D01*
X319698Y-531835D01*
X319798Y-533035D01*
X320098Y-534102D01*
X320498Y-534902D01*
X321098Y-535568D01*
X321898Y-535835D01*
X322698Y-535568D01*
X323298Y-534902D01*
X323698Y-534102D01*
X323998Y-533035D01*
X324098Y-531835D01*
X323998Y-530635D01*
X323698Y-529568D01*
X323298Y-528768D01*
X322698Y-528102D01*
X321898Y-527835D01*
G01X327998Y-529168D02*
X328598Y-528368D01*
X329298Y-527968D01*
X330098Y-527835D01*
X331098Y-528102D01*
X331798Y-528768D01*
X331998Y-529568D01*
X331898Y-530369D01*
X331498Y-531035D01*
X329498Y-532368D01*
X328598Y-533302D01*
X327998Y-534635D01*
X327798Y-535835D01*
X331998D01*
G01X335698Y-534235D02*
X336298Y-535168D01*
X337098Y-535702D01*
X337998Y-535835D01*
X338798Y-535702D01*
X339598Y-535035D01*
X340098Y-534235D01*
X340198Y-533435D01*
X339998Y-532502D01*
X339298Y-531835D01*
X338598Y-531568D01*
X337698D01*
G01X338598D02*
X339198Y-531168D01*
X339698Y-530502D01*
X339898Y-529702D01*
X339698Y-528902D01*
X339198Y-528235D01*
X338298Y-527835D01*
X337398Y-527968D01*
X336498Y-528502D01*
G01X344098Y-536102D02*
X347698Y-527835D01*
G01X353898D02*
X353098Y-528102D01*
X352498Y-528768D01*
X352098Y-529568D01*
X351798Y-530635D01*
X351698Y-531835D01*
X351798Y-533035D01*
X352098Y-534102D01*
X352498Y-534902D01*
X353098Y-535568D01*
X353898Y-535835D01*
X354698Y-535568D01*
X355298Y-534902D01*
X355698Y-534102D01*
X355998Y-533035D01*
X356098Y-531835D01*
X355998Y-530635D01*
X355698Y-529568D01*
X355298Y-528768D01*
X354698Y-528102D01*
X353898Y-527835D01*
G01X361898Y-535835D02*
Y-527835D01*
X360698Y-529435D01*
G01Y-535835D02*
X363098D01*
G01X368098Y-536102D02*
X371698Y-527835D01*
G01X377898D02*
X377098Y-528102D01*
X376498Y-528768D01*
X376098Y-529568D01*
X375798Y-530635D01*
X375698Y-531835D01*
X375798Y-533035D01*
X376098Y-534102D01*
X376498Y-534902D01*
X377098Y-535568D01*
X377898Y-535835D01*
X378698Y-535568D01*
X379298Y-534902D01*
X379698Y-534102D01*
X379998Y-533035D01*
X380098Y-531835D01*
X379998Y-530635D01*
X379698Y-529568D01*
X379298Y-528768D01*
X378698Y-528102D01*
X377898Y-527835D01*
G01X384198Y-534902D02*
X384898Y-535568D01*
X385698Y-535835D01*
X386498Y-535568D01*
X387198Y-534769D01*
X387698Y-533568D01*
X387898Y-532368D01*
Y-530902D01*
X387698Y-529702D01*
X387198Y-528635D01*
X386598Y-528102D01*
X385898Y-527835D01*
X385098Y-528102D01*
X384498Y-528635D01*
X384098Y-529435D01*
X383898Y-530502D01*
X384098Y-531435D01*
X384598Y-532368D01*
X385198Y-532902D01*
X385898Y-533035D01*
X386698Y-532769D01*
X387298Y-532102D01*
X387898Y-530902D01*
G01X311698Y-510835D02*
Y-502835D01*
X313698D01*
X314498Y-503235D01*
X315098Y-503768D01*
X315598Y-504568D01*
X315998Y-505502D01*
X316098Y-506835D01*
X315998Y-508168D01*
X315598Y-509102D01*
X315098Y-509902D01*
X314498Y-510435D01*
X313698Y-510835D01*
X311698D01*
G01X319398D02*
X321898Y-502835D01*
X324398Y-510835D01*
G01X323498Y-508035D02*
X320298D01*
G01X329898Y-502835D02*
X329098Y-503102D01*
X328498Y-503768D01*
X328098Y-504568D01*
X327798Y-505635D01*
X327698Y-506835D01*
X327798Y-508035D01*
X328098Y-509102D01*
X328498Y-509902D01*
X329098Y-510568D01*
X329898Y-510835D01*
X330698Y-510568D01*
X331298Y-509902D01*
X331698Y-509102D01*
X331998Y-508035D01*
X332098Y-506835D01*
X331998Y-505635D01*
X331698Y-504568D01*
X331298Y-503768D01*
X330698Y-503102D01*
X329898Y-502835D01*
G01X335998Y-510835D02*
Y-502835D01*
X339798D01*
G01X338398Y-506702D02*
X335998D01*
G01X345898Y-502835D02*
X345098Y-503102D01*
X344498Y-503768D01*
X344098Y-504568D01*
X343798Y-505635D01*
X343698Y-506835D01*
X343798Y-508035D01*
X344098Y-509102D01*
X344498Y-509902D01*
X345098Y-510568D01*
X345898Y-510835D01*
X346698Y-510568D01*
X347298Y-509902D01*
X347698Y-509102D01*
X347998Y-508035D01*
X348098Y-506835D01*
X347998Y-505635D01*
X347698Y-504568D01*
X347298Y-503768D01*
X346698Y-503102D01*
X345898Y-502835D01*
G01X353898D02*
Y-510835D01*
G01X351598Y-502835D02*
X356198D01*
G01X363898Y-510835D02*
X359898D01*
Y-502835D01*
X363898D01*
G01X362298Y-506702D02*
X359898D01*
G01X370698Y-506568D02*
X371098Y-506168D01*
X371398Y-505502D01*
X371598Y-504568D01*
X371398Y-503768D01*
X370998Y-503235D01*
X370298Y-502835D01*
X367598D01*
Y-510835D01*
X370898D01*
X371598Y-510302D01*
X371998Y-509502D01*
X372198Y-508568D01*
X371998Y-507635D01*
X371398Y-506835D01*
X370698Y-506568D01*
X367598D01*
G01X376698Y-502835D02*
X379098D01*
G01X377898D02*
Y-510835D01*
G01X376698D02*
X379098D01*
G01X383998D02*
Y-502835D01*
X387798D01*
G01X386398Y-506702D02*
X383998D01*
G01X393898Y-502835D02*
X393098Y-503102D01*
X392498Y-503768D01*
X392098Y-504568D01*
X391798Y-505635D01*
X391698Y-506835D01*
X391798Y-508035D01*
X392098Y-509102D01*
X392498Y-509902D01*
X393098Y-510568D01*
X393898Y-510835D01*
X394698Y-510568D01*
X395298Y-509902D01*
X395698Y-509102D01*
X395998Y-508035D01*
X396098Y-506835D01*
X395998Y-505635D01*
X395698Y-504568D01*
X395298Y-503768D01*
X394698Y-503102D01*
X393898Y-502835D01*
G01X299907Y10900D02*
Y8678D01*
X300060Y8213D01*
X300367Y7903D01*
X300750Y7800D01*
X301133Y7903D01*
X301440Y8213D01*
X301593Y8678D01*
Y10900D01*
G01X304310Y7800D02*
Y10900D01*
X302892Y8678D01*
X304808D01*
G01X306950Y7800D02*
Y10900D01*
X306490Y10280D01*
G01Y7800D02*
X307410D01*
G01X309322Y9092D02*
X309590Y9453D01*
X309820Y9660D01*
X310127Y9763D01*
X310395Y9660D01*
X310587Y9453D01*
X310740Y9143D01*
X310778Y8782D01*
X310740Y8472D01*
X310587Y8162D01*
X310357Y7903D01*
X310088Y7800D01*
X309782Y7903D01*
X309513Y8213D01*
X309360Y8678D01*
X309322Y9195D01*
X309398Y9867D01*
X309513Y10228D01*
X309705Y10590D01*
X309973Y10848D01*
X310242Y10900D01*
X310510Y10797D01*
X310702Y10538D01*
G01X307581Y33407D02*
Y36607D01*
G01X313781Y33407D02*
X307581D01*
G01X311235Y31751D02*
X305392Y25908D01*
G01X318966Y31751D02*
X311235D01*
G01X305392Y25908D02*
X299549Y31751D01*
G01X307581Y36607D02*
X313781D01*
G01X315592Y67523D02*
X303388D01*
G01D02*
Y70183D01*
G01X310285Y59613D02*
Y56413D01*
G01X304085Y59613D02*
X310285D01*
G01X304085Y56413D02*
Y59613D01*
G01X310285Y56413D02*
X304085D01*
G01X300960Y70181D02*
Y66981D01*
G01X303388Y79047D02*
X315592D01*
G01X303388Y76285D02*
Y79047D01*
G01X306490Y73285D02*
X303388Y76285D01*
G01Y70183D02*
X306490Y73285D01*
G01X300960Y82181D02*
Y78981D01*
G01X301005Y78187D02*
Y74987D01*
G01Y74187D02*
Y70987D01*
G01X301795Y93476D02*
X304995D01*
G01X301795Y87276D02*
Y93476D01*
G01X304995Y87276D02*
X301795D01*
G01X304995Y93476D02*
Y87276D01*
G01X310495D02*
X307295D01*
G01X310495Y93476D02*
Y87276D01*
G01X307295Y93476D02*
X310495D01*
G01X307295Y87276D02*
Y93476D01*
G01X314444Y87204D02*
X311244D01*
G01Y93404D02*
X314444D01*
G01X311244Y87204D02*
Y93404D01*
G01X307500Y98107D02*
X309722D01*
X310187Y98260D01*
X310497Y98567D01*
X310600Y98950D01*
X310497Y99333D01*
X310187Y99640D01*
X309722Y99793D01*
X307500D01*
G01X310600Y102510D02*
X307500D01*
X309722Y101092D01*
Y103008D01*
G01X307500Y105150D02*
X307603Y104843D01*
X307862Y104613D01*
X308172Y104460D01*
X308585Y104345D01*
X309050Y104307D01*
X309515Y104345D01*
X309928Y104460D01*
X310238Y104613D01*
X310497Y104843D01*
X310600Y105150D01*
X310497Y105457D01*
X310238Y105687D01*
X309928Y105840D01*
X309515Y105955D01*
X309050Y105993D01*
X308585Y105955D01*
X308172Y105840D01*
X307862Y105687D01*
X307603Y105457D01*
X307500Y105150D01*
G01Y108250D02*
X307603Y107943D01*
X307862Y107713D01*
X308172Y107560D01*
X308585Y107445D01*
X309050Y107407D01*
X309515Y107445D01*
X309928Y107560D01*
X310238Y107713D01*
X310497Y107943D01*
X310600Y108250D01*
X310497Y108557D01*
X310238Y108787D01*
X309928Y108940D01*
X309515Y109055D01*
X309050Y109093D01*
X308585Y109055D01*
X308172Y108940D01*
X307862Y108787D01*
X307603Y108557D01*
X307500Y108250D01*
G01X306630Y111267D02*
Y95913D01*
G01X307786Y111951D02*
Y118151D01*
G01X310986Y111951D02*
X307786D01*
G01X310986Y118151D02*
Y111951D01*
G01X306503Y116088D02*
Y112888D01*
G01X300303Y116088D02*
X306503D01*
G01X300303Y112888D02*
Y116088D01*
G01X306503Y112888D02*
X300303D01*
G01X307786Y118151D02*
X310986D01*
G01X313931Y126223D02*
X310731D01*
G01Y132423D02*
X313931D01*
G01X310731Y126223D02*
Y132423D01*
G01X307578Y119149D02*
X304478D01*
Y120069D01*
X304633Y120376D01*
X304995Y120606D01*
X305408Y120683D01*
X305821Y120606D01*
X306131Y120414D01*
X306286Y120069D01*
Y119149D01*
G01X304478Y122173D02*
X306700D01*
X307165Y122326D01*
X307475Y122633D01*
X307578Y123016D01*
X307475Y123399D01*
X307165Y123706D01*
X306700Y123859D01*
X304478D01*
G01X307578Y126116D02*
X307526Y126384D01*
X307371Y126691D01*
X307113Y126883D01*
X306751Y126959D01*
X306390Y126883D01*
X306080Y126653D01*
X305925Y126308D01*
Y125924D01*
X305821Y125694D01*
X305563Y125503D01*
X305201Y125426D01*
X304840Y125541D01*
X304581Y125809D01*
X304478Y126116D01*
X304581Y126423D01*
X304840Y126691D01*
X305201Y126806D01*
X305563Y126729D01*
X305821Y126538D01*
X305925Y126308D01*
Y125924D01*
X306080Y125579D01*
X306390Y125349D01*
X306751Y125273D01*
X307113Y125349D01*
X307371Y125541D01*
X307526Y125848D01*
X307578Y126116D01*
G01Y129676D02*
X304478D01*
X306700Y128258D01*
Y130174D01*
G01X296603Y154138D02*
Y144690D01*
G01X298010Y144168D02*
Y147368D01*
G01X304210Y144168D02*
X298010D01*
G01X304210Y147368D02*
Y144168D01*
G01X298010Y147368D02*
X304210D01*
G01X313120Y146250D02*
X309920D01*
G01D02*
Y152450D01*
G01X304210Y151368D02*
Y148168D01*
G01X298010D02*
Y151368D01*
G01X304210Y148168D02*
X298010D01*
G01X305500Y133707D02*
X307722D01*
X308187Y133860D01*
X308497Y134167D01*
X308600Y134550D01*
X308497Y134933D01*
X308187Y135240D01*
X307722Y135393D01*
X305500D01*
G01X307980Y136807D02*
X308342Y137037D01*
X308548Y137343D01*
X308600Y137688D01*
X308548Y137995D01*
X308290Y138302D01*
X307980Y138493D01*
X307670Y138532D01*
X307308Y138455D01*
X307050Y138187D01*
X306947Y137918D01*
Y137573D01*
G01Y137918D02*
X306792Y138148D01*
X306533Y138340D01*
X306223Y138417D01*
X305913Y138340D01*
X305655Y138148D01*
X305500Y137803D01*
X305552Y137458D01*
X305758Y137113D01*
G01X308600Y140750D02*
X308548Y141018D01*
X308393Y141325D01*
X308135Y141517D01*
X307773Y141593D01*
X307412Y141517D01*
X307102Y141287D01*
X306947Y140942D01*
Y140558D01*
X306843Y140328D01*
X306585Y140137D01*
X306223Y140060D01*
X305862Y140175D01*
X305603Y140443D01*
X305500Y140750D01*
X305603Y141057D01*
X305862Y141325D01*
X306223Y141440D01*
X306585Y141363D01*
X306843Y141172D01*
X306947Y140942D01*
Y140558D01*
X307102Y140213D01*
X307412Y139983D01*
X307773Y139907D01*
X308135Y139983D01*
X308393Y140175D01*
X308548Y140482D01*
X308600Y140750D01*
G01Y144310D02*
X305500D01*
X307722Y142892D01*
Y144808D01*
G01X311610Y144395D02*
Y135095D01*
G01X322210Y144395D02*
X311610D01*
G01Y134995D02*
X322210D01*
G01X309920Y152450D02*
X313120D01*
G01X298010Y151368D02*
X304210D01*
G01X309920Y159540D02*
X313120D01*
G01X309920Y153340D02*
Y159540D01*
G01X313120Y153340D02*
X309920D01*
G01X300575Y178897D02*
Y176944D01*
G01D02*
X298622D01*
G01X304946Y179065D02*
Y182265D01*
G01X311146Y179065D02*
X304946D01*
G01X311146Y182265D02*
Y179065D01*
G01X304946Y171065D02*
Y174265D01*
G01X311146Y171065D02*
X304946D01*
G01X311146Y174265D02*
Y171065D01*
G01X304946Y174265D02*
X311146D01*
G01X304946Y175065D02*
Y178265D01*
G01X311146Y175065D02*
X304946D01*
G01X311146Y178265D02*
Y175065D01*
G01X304946Y178265D02*
X311146D01*
G01X304946Y167065D02*
Y170265D01*
G01X311146Y167065D02*
X304946D01*
G01X311146Y170265D02*
Y167065D01*
G01X304946Y170265D02*
X311146D01*
G01X300575Y188756D02*
Y186803D01*
G01X298622Y188756D02*
X300575D01*
G01X312714Y189435D02*
X314954D01*
G01X313741Y191060D02*
Y187810D01*
G01X304946Y183065D02*
Y186265D01*
G01X311146Y183065D02*
X304946D01*
G01X311146Y186265D02*
Y183065D01*
G01X304946Y186265D02*
X311146D01*
G01X304946Y182265D02*
X311146D01*
G01X297991Y194686D02*
Y197886D01*
G01X304191Y194686D02*
X297991D01*
G01X304191Y197886D02*
Y194686D01*
G01X297991Y197886D02*
X304191D01*
G01X304946Y187065D02*
Y190265D01*
G01X311146Y187065D02*
X304946D01*
G01X311146Y190265D02*
Y187065D01*
G01X304946Y190265D02*
X311146D01*
G01Y194265D02*
Y191065D01*
G01X304946Y194265D02*
X311146D01*
G01X304946Y191065D02*
Y194265D01*
G01X311146Y191065D02*
X304946D01*
G01X311146Y198265D02*
Y195065D01*
G01X304946D02*
Y198265D01*
G01X311146Y195065D02*
X304946D01*
G01Y198265D02*
X311146D01*
G01X305041Y207264D02*
Y210464D01*
G01X311241Y207264D02*
X305041D01*
G01X311241Y210464D02*
Y207264D01*
G01X305041Y210464D02*
X311241D01*
G01Y206464D02*
Y203264D01*
G01X305041Y206464D02*
X311241D01*
G01X305041Y203264D02*
Y206464D01*
G01X311241Y203264D02*
X305041D01*
G01Y214464D02*
X311241D01*
Y211264D01*
X305041D01*
Y214464D01*
G01Y202464D02*
X311241D01*
Y199264D01*
X305041D01*
Y202464D01*
G01Y215264D02*
Y218464D01*
G01X311241Y215264D02*
X305041D01*
G01X311241Y218464D02*
Y215264D01*
G01X305041Y218464D02*
X311241D01*
G01X305041Y220264D02*
Y223464D01*
G01X311241Y220264D02*
X305041D01*
G01X311241Y223464D02*
Y220264D01*
G01X305041Y223464D02*
X311241D01*
G01X305038Y227319D02*
X311238D01*
Y224119D01*
X305038D01*
Y227319D01*
G01X302757Y234813D02*
Y250325D01*
G01X297801Y264635D02*
X313313D01*
G01X297801Y295727D02*
Y264635D01*
G01X296169Y279901D02*
Y273701D01*
G01X299750Y311000D02*
X299443Y311052D01*
X299175Y311258D01*
X298945Y311568D01*
X298792Y311930D01*
X298715Y312343D01*
Y312757D01*
X298792Y313170D01*
X298945Y313532D01*
X299175Y313842D01*
X299443Y314048D01*
X299750Y314100D01*
X300057Y314048D01*
X300325Y313842D01*
X300555Y313532D01*
X300708Y313170D01*
X300785Y312757D01*
Y312343D01*
X300708Y311930D01*
X300555Y311568D01*
X300325Y311258D01*
X300057Y311052D01*
X299750Y311000D01*
G01X300057Y311827D02*
X300517Y311000D01*
G01X302122Y313583D02*
X302352Y313893D01*
X302620Y314048D01*
X302927Y314100D01*
X303310Y313997D01*
X303578Y313738D01*
X303655Y313428D01*
X303617Y313118D01*
X303463Y312860D01*
X302697Y312343D01*
X302352Y311982D01*
X302122Y311465D01*
X302045Y311000D01*
X303655D01*
G01X313313Y295727D02*
X297801D01*
G01X313863Y310215D02*
X310663D01*
G01D02*
Y316415D01*
G01X305904Y323621D02*
X303573Y321290D01*
G01X309013Y323621D02*
X305904D01*
G01X309013Y314959D02*
Y323621D01*
G01X298133Y314959D02*
X309013D01*
G01X298133Y323621D02*
Y314959D01*
G01X301242Y323621D02*
X298133D01*
G01X303573Y321290D02*
X301242Y323621D01*
G01X313951Y326084D02*
X307351D01*
G01D02*
Y339084D01*
G01X306143Y327342D02*
X302943D01*
G01X306143Y333542D02*
Y327342D01*
G01X302943D02*
Y333542D01*
G01X310663Y316415D02*
X313863D01*
G01X310663Y323415D02*
X313863D01*
G01X310663Y317215D02*
Y323415D01*
G01X313863Y317215D02*
X310663D01*
G01X300985Y340646D02*
Y349110D01*
G01X314247Y340646D02*
X300985D01*
G01X307351Y339084D02*
X323551D01*
G01X302943Y333542D02*
X306143D01*
G01X300823Y353745D02*
Y351523D01*
X300976Y351058D01*
X301283Y350748D01*
X301666Y350645D01*
X302049Y350748D01*
X302356Y351058D01*
X302509Y351523D01*
Y353745D01*
G01X304766Y350645D02*
Y353745D01*
X304306Y353125D01*
G01Y350645D02*
X305226D01*
G01X307023Y351110D02*
X307253Y350852D01*
X307521Y350697D01*
X307866Y350645D01*
X308211Y350748D01*
X308479Y350955D01*
X308671Y351317D01*
X308709Y351730D01*
X308633Y352143D01*
X308441Y352402D01*
X308173Y352608D01*
X307904Y352660D01*
X307636Y352608D01*
X307291Y352402D01*
X307406Y353745D01*
X308441D01*
G01X306116Y349110D02*
X307616Y347339D01*
G01X300985Y349110D02*
X306116D01*
G01X309116D02*
X314247D01*
G01X307616Y347339D02*
X309116Y349110D01*
G01X301132Y366063D02*
Y467697D01*
G01Y470189D02*
Y474925D01*
G01Y477324D02*
Y481824D01*
G01Y484428D02*
Y488909D01*
G01Y491595D02*
Y511832D01*
G01Y514354D02*
Y519080D01*
G01Y521427D02*
Y526164D01*
G01Y528512D02*
Y533125D01*
G01Y535565D02*
Y561873D01*
G01Y564498D02*
Y568894D01*
G01Y571662D02*
Y575968D01*
G01Y578695D02*
Y583103D01*
G01Y585748D02*
Y589992D01*
G01Y592945D02*
Y597230D01*
G01Y599937D02*
Y604181D01*
G01Y639449D02*
Y614064D01*
G01Y607072D02*
Y611439D01*
G01X317714Y855850D02*
Y853900D01*
X307714D01*
G01D02*
Y865850D01*
G01Y871950D02*
Y883900D01*
X317714D01*
Y881950D01*
G01X307497Y886087D02*
X307689Y885777D01*
X307919Y885570D01*
X308187Y885467D01*
X308494Y885570D01*
X308724Y885777D01*
X308954Y886087D01*
X309031Y886500D01*
Y888567D01*
G01X311287Y885467D02*
X311364Y886139D01*
X311479Y886707D01*
X311632Y887224D01*
X311824Y887792D01*
X312131Y888567D01*
X310597D01*
G01X314464D02*
X314157Y888464D01*
X313927Y888205D01*
X313774Y887895D01*
X313659Y887482D01*
X313621Y887017D01*
X313659Y886552D01*
X313774Y886139D01*
X313927Y885829D01*
X314157Y885570D01*
X314464Y885467D01*
X314771Y885570D01*
X315001Y885829D01*
X315154Y886139D01*
X315269Y886552D01*
X315307Y887017D01*
X315269Y887482D01*
X315154Y887895D01*
X315001Y888205D01*
X314771Y888464D01*
X314464Y888567D01*
G01X318714Y926350D02*
Y924400D01*
X308714D01*
G01D02*
Y936350D01*
G01Y942450D02*
Y954400D01*
X318714D01*
Y952450D01*
G01X308497Y956587D02*
X308689Y956277D01*
X308919Y956070D01*
X309187Y955967D01*
X309494Y956070D01*
X309724Y956277D01*
X309954Y956587D01*
X310031Y957000D01*
Y959067D01*
G01X312287Y955967D02*
X312364Y956639D01*
X312479Y957207D01*
X312632Y957724D01*
X312824Y958292D01*
X313131Y959067D01*
X311597D01*
G01X314621Y956587D02*
X314851Y956225D01*
X315157Y956019D01*
X315502Y955967D01*
X315809Y956019D01*
X316116Y956277D01*
X316307Y956587D01*
X316346Y956897D01*
X316269Y957259D01*
X316001Y957517D01*
X315732Y957620D01*
X315387D01*
G01X315732D02*
X315962Y957775D01*
X316154Y958034D01*
X316231Y958344D01*
X316154Y958654D01*
X315962Y958912D01*
X315617Y959067D01*
X315272Y959015D01*
X314927Y958809D01*
G01X308448Y1745941D02*
X318448D01*
G01X308448Y1748441D02*
Y1745941D01*
G01Y1758441D02*
Y1753441D01*
G01X308093Y1767141D02*
X309703Y1770241D01*
G01X308093D02*
X309703Y1767141D01*
G01X311155Y1767761D02*
X311385Y1767399D01*
X311691Y1767193D01*
X312036Y1767141D01*
X312343Y1767193D01*
X312650Y1767451D01*
X312841Y1767761D01*
X312880Y1768071D01*
X312803Y1768433D01*
X312535Y1768691D01*
X312266Y1768794D01*
X311921D01*
G01X312266D02*
X312496Y1768949D01*
X312688Y1769208D01*
X312765Y1769518D01*
X312688Y1769828D01*
X312496Y1770086D01*
X312151Y1770241D01*
X311806Y1770189D01*
X311461Y1769983D01*
G01X308448Y1765941D02*
Y1763441D01*
G01X318448Y1765941D02*
X308448D01*
G01X308348Y1794441D02*
Y1791941D01*
X318348D01*
Y1792491D01*
G01X308348Y1804441D02*
Y1799441D01*
G01X307993Y1813141D02*
X309603Y1816241D01*
G01X307993D02*
X309603Y1813141D01*
G01X311898D02*
X312166Y1813193D01*
X312473Y1813348D01*
X312665Y1813606D01*
X312741Y1813968D01*
X312665Y1814329D01*
X312435Y1814639D01*
X312090Y1814794D01*
X311706D01*
X311476Y1814898D01*
X311285Y1815156D01*
X311208Y1815518D01*
X311323Y1815879D01*
X311591Y1816138D01*
X311898Y1816241D01*
X312205Y1816138D01*
X312473Y1815879D01*
X312588Y1815518D01*
X312511Y1815156D01*
X312320Y1814898D01*
X312090Y1814794D01*
X311706D01*
X311361Y1814639D01*
X311131Y1814329D01*
X311055Y1813968D01*
X311131Y1813606D01*
X311323Y1813348D01*
X311630Y1813193D01*
X311898Y1813141D01*
G01X318348Y1811391D02*
Y1811941D01*
X308348D01*
G01D02*
Y1809441D01*
G01X323806Y14206D02*
Y17406D01*
G01X330006Y14206D02*
X323806D01*
G01Y17406D02*
X330006D01*
G01X323806Y18206D02*
Y21406D01*
G01X330006Y18206D02*
X323806D01*
G01Y10206D02*
Y13406D01*
G01X330006Y10206D02*
X323806D01*
G01Y13406D02*
X330006D01*
G01X318966Y12065D02*
Y31751D01*
G01X313781Y36607D02*
Y33407D01*
G01X323806Y21406D02*
X330006D01*
G01X323806Y26206D02*
Y29406D01*
G01X330006Y26206D02*
X323806D01*
G01Y29406D02*
X330006D01*
G01X323806Y22206D02*
Y25406D01*
G01X330006Y22206D02*
X323806D01*
G01Y25406D02*
X330006D01*
G01X323806Y30206D02*
Y33406D01*
G01X330006Y30206D02*
X323806D01*
G01Y33406D02*
X330006D01*
G01X316700Y67707D02*
X318922D01*
X319387Y67860D01*
X319697Y68167D01*
X319800Y68550D01*
X319697Y68933D01*
X319387Y69240D01*
X318922Y69393D01*
X316700D01*
G01X319800Y71650D02*
X316700D01*
X317320Y71190D01*
G01X319800D02*
Y72110D01*
G01X317217Y74022D02*
X316907Y74252D01*
X316752Y74520D01*
X316700Y74827D01*
X316803Y75210D01*
X317062Y75478D01*
X317372Y75555D01*
X317682Y75517D01*
X317940Y75363D01*
X318457Y74597D01*
X318818Y74252D01*
X319335Y74022D01*
X319800Y73945D01*
Y75555D01*
G01Y77850D02*
X319748Y78118D01*
X319593Y78425D01*
X319335Y78617D01*
X318973Y78693D01*
X318612Y78617D01*
X318302Y78387D01*
X318147Y78042D01*
Y77658D01*
X318043Y77428D01*
X317785Y77237D01*
X317423Y77160D01*
X317062Y77275D01*
X316803Y77543D01*
X316700Y77850D01*
X316803Y78157D01*
X317062Y78425D01*
X317423Y78540D01*
X317785Y78463D01*
X318043Y78272D01*
X318147Y78042D01*
Y77658D01*
X318302Y77313D01*
X318612Y77083D01*
X318973Y77007D01*
X319335Y77083D01*
X319593Y77275D01*
X319748Y77582D01*
X319800Y77850D01*
G01X315592Y79047D02*
Y67523D01*
G01X318351Y87299D02*
X315151D01*
G01X318351Y93499D02*
Y87299D01*
G01X315151Y93499D02*
X318351D01*
G01X315151Y87299D02*
Y93499D01*
G01X314444Y93404D02*
Y87204D01*
G01X325323Y110172D02*
Y122172D01*
G01X331323Y110172D02*
X325323D01*
G01X322706Y109424D02*
X325906D01*
G01X322706Y103224D02*
Y109424D01*
G01X325906Y103224D02*
X322706D01*
G01X325906Y109424D02*
Y103224D01*
G01X318706Y109424D02*
X321906D01*
G01X318706Y103224D02*
Y109424D01*
G01X321906Y103224D02*
X318706D01*
G01X321906Y109424D02*
Y103224D01*
G01X314706Y109424D02*
X317906D01*
G01X314706Y103224D02*
Y109424D01*
G01X317906Y103224D02*
X314706D01*
G01X317906Y109424D02*
Y103224D01*
G01X313160Y111734D02*
Y123508D01*
G01X322922Y111734D02*
X313160D01*
G01X322922Y123508D02*
Y111734D01*
G01X325323Y122172D02*
X331323D01*
G01X323931Y126223D02*
X320731D01*
G01X323931Y132423D02*
Y126223D01*
G01X320731Y132423D02*
X323931D01*
G01X320731Y126223D02*
Y132423D01*
G01X313931D02*
Y126223D01*
G01X316622Y132314D02*
X319822D01*
G01X316622Y126114D02*
Y132314D01*
G01X319822Y126114D02*
X316622D01*
G01X319822Y132314D02*
Y126114D01*
G01X327985Y126228D02*
X324785D01*
G01X327985Y132428D02*
Y126228D01*
G01X324785Y132428D02*
X327985D01*
G01X324785Y126228D02*
Y132428D01*
G01X313160Y123508D02*
X322922D01*
G01X328164Y141337D02*
X324964D01*
G01Y147537D02*
X328164D01*
G01X324964Y141337D02*
Y147537D01*
G01X324829Y133238D02*
Y136438D01*
G01X331029Y133238D02*
X324829D01*
G01Y136438D02*
X331029D01*
G01X324829Y137238D02*
Y140438D01*
G01X331029Y137238D02*
X324829D01*
G01Y140438D02*
X331029D01*
G01X313120Y152450D02*
Y146250D01*
G01X322210Y134995D02*
Y144395D01*
G01X313120Y159540D02*
Y153340D01*
G01X319833Y149950D02*
Y165304D01*
G01X332511Y149950D02*
X319833D01*
G01X320030Y165304D02*
X332511D01*
G01X316983Y179600D02*
Y182700D01*
X317903D01*
X318210Y182545D01*
X318440Y182183D01*
X318517Y181770D01*
X318440Y181357D01*
X318248Y181047D01*
X317903Y180892D01*
X316983D01*
G01X320007Y179600D02*
Y182700D01*
X320773D01*
X321080Y182545D01*
X321310Y182338D01*
X321502Y182028D01*
X321655Y181667D01*
X321693Y181150D01*
X321655Y180633D01*
X321502Y180272D01*
X321310Y179962D01*
X321080Y179755D01*
X320773Y179600D01*
X320007D01*
G01X323222Y180892D02*
X323490Y181253D01*
X323720Y181460D01*
X324027Y181563D01*
X324295Y181460D01*
X324487Y181253D01*
X324640Y180943D01*
X324678Y180582D01*
X324640Y180272D01*
X324487Y179962D01*
X324257Y179703D01*
X323988Y179600D01*
X323682Y179703D01*
X323413Y180013D01*
X323260Y180478D01*
X323222Y180995D01*
X323298Y181667D01*
X323413Y182028D01*
X323605Y182390D01*
X323873Y182648D01*
X324142Y182700D01*
X324410Y182597D01*
X324602Y182338D01*
G01X326322Y180892D02*
X326590Y181253D01*
X326820Y181460D01*
X327127Y181563D01*
X327395Y181460D01*
X327587Y181253D01*
X327740Y180943D01*
X327778Y180582D01*
X327740Y180272D01*
X327587Y179962D01*
X327357Y179703D01*
X327088Y179600D01*
X326782Y179703D01*
X326513Y180013D01*
X326360Y180478D01*
X326322Y180995D01*
X326398Y181667D01*
X326513Y182028D01*
X326705Y182390D01*
X326973Y182648D01*
X327242Y182700D01*
X327510Y182597D01*
X327702Y182338D01*
G01X316355Y195583D02*
X345914D01*
G01X316355Y184087D02*
Y195583D01*
G01X345914Y184087D02*
X316355D01*
G01X335331Y197645D02*
X323331D01*
G01D02*
Y203645D01*
G01D02*
X335331D01*
G01X316508Y204506D02*
Y216506D01*
G01X322508Y204506D02*
X316508D01*
G01X322508Y216506D02*
Y204506D01*
G01X323308Y208306D02*
Y214506D01*
G01X326508Y208306D02*
X323308D01*
G01X326508Y214506D02*
Y208306D01*
G01X327084Y208464D02*
X333284D01*
G01X327084Y205264D02*
Y208464D01*
G01X333284Y205264D02*
X327084D01*
G01X316508Y216506D02*
X322508D01*
G01X323308Y214506D02*
X326508D01*
G01X323674Y245521D02*
Y254969D01*
G01X334510Y245521D02*
X323674D01*
G01X327250Y231334D02*
X324050D01*
G01X327250Y237534D02*
Y231334D01*
G01X324050Y237534D02*
X327250D01*
G01X324050Y231334D02*
Y237534D01*
G01X325476Y243678D02*
Y240478D01*
G01X319276Y243678D02*
X325476D01*
G01X319276Y240478D02*
Y243678D01*
G01X325476Y240478D02*
X319276D01*
G01X326255Y243678D02*
X332455D01*
G01X326255Y240478D02*
Y243678D01*
G01X332455Y240478D02*
X326255D01*
G01X315306Y246771D02*
Y249971D01*
G01X321506Y246771D02*
X315306D01*
G01X321506Y249971D02*
Y246771D01*
G01X323560Y258971D02*
X323253Y259023D01*
X322985Y259229D01*
X322755Y259539D01*
X322602Y259901D01*
X322525Y260314D01*
Y260728D01*
X322602Y261141D01*
X322755Y261503D01*
X322985Y261813D01*
X323253Y262019D01*
X323560Y262071D01*
X323867Y262019D01*
X324135Y261813D01*
X324365Y261503D01*
X324518Y261141D01*
X324595Y260728D01*
Y260314D01*
X324518Y259901D01*
X324365Y259539D01*
X324135Y259229D01*
X323867Y259023D01*
X323560Y258971D01*
G01X323867Y259798D02*
X324327Y258971D01*
G01X326660D02*
Y262071D01*
X326200Y261451D01*
G01Y258971D02*
X327120D01*
G01X328917Y259591D02*
X329147Y259229D01*
X329453Y259023D01*
X329798Y258971D01*
X330105Y259023D01*
X330412Y259281D01*
X330603Y259591D01*
X330642Y259901D01*
X330565Y260263D01*
X330297Y260521D01*
X330028Y260624D01*
X329683D01*
G01X330028D02*
X330258Y260779D01*
X330450Y261038D01*
X330527Y261348D01*
X330450Y261658D01*
X330258Y261916D01*
X329913Y262071D01*
X329568Y262019D01*
X329223Y261813D01*
G01X332860Y262071D02*
X332553Y261968D01*
X332323Y261709D01*
X332170Y261399D01*
X332055Y260986D01*
X332017Y260521D01*
X332055Y260056D01*
X332170Y259643D01*
X332323Y259333D01*
X332553Y259074D01*
X332860Y258971D01*
X333167Y259074D01*
X333397Y259333D01*
X333550Y259643D01*
X333665Y260056D01*
X333703Y260521D01*
X333665Y260986D01*
X333550Y261399D01*
X333397Y261709D01*
X333167Y261968D01*
X332860Y262071D01*
G01X327092Y254969D02*
X329092Y253245D01*
G01X323674Y254969D02*
X327092D01*
G01X315306Y249971D02*
X321506D01*
G01Y253971D02*
Y250771D01*
G01X315306Y253971D02*
X321506D01*
G01X315306Y250771D02*
Y253971D01*
G01X321506Y250771D02*
X315306D01*
G01X317800Y264783D02*
X314700D01*
Y265703D01*
X314855Y266010D01*
X315217Y266240D01*
X315630Y266317D01*
X316043Y266240D01*
X316353Y266048D01*
X316508Y265703D01*
Y264783D01*
G01X317800Y267807D02*
X314700D01*
Y268573D01*
X314855Y268880D01*
X315062Y269110D01*
X315372Y269302D01*
X315733Y269455D01*
X316250Y269493D01*
X316767Y269455D01*
X317128Y269302D01*
X317438Y269110D01*
X317645Y268880D01*
X317800Y268573D01*
Y267807D01*
G01Y271750D02*
X317748Y272018D01*
X317593Y272325D01*
X317335Y272517D01*
X316973Y272593D01*
X316612Y272517D01*
X316302Y272287D01*
X316147Y271942D01*
Y271558D01*
X316043Y271328D01*
X315785Y271137D01*
X315423Y271060D01*
X315062Y271175D01*
X314803Y271443D01*
X314700Y271750D01*
X314803Y272057D01*
X315062Y272325D01*
X315423Y272440D01*
X315785Y272363D01*
X316043Y272172D01*
X316147Y271942D01*
Y271558D01*
X316302Y271213D01*
X316612Y270983D01*
X316973Y270907D01*
X317335Y270983D01*
X317593Y271175D01*
X317748Y271482D01*
X317800Y271750D01*
G01X317335Y274007D02*
X317593Y274237D01*
X317748Y274505D01*
X317800Y274850D01*
X317697Y275195D01*
X317490Y275463D01*
X317128Y275655D01*
X316715Y275693D01*
X316302Y275617D01*
X316043Y275425D01*
X315837Y275157D01*
X315785Y274888D01*
X315837Y274620D01*
X316043Y274275D01*
X314700Y274390D01*
Y275425D01*
G01X313313Y264635D02*
Y295727D01*
G01X322357Y308252D02*
X328557D01*
G01X322357Y305052D02*
Y308252D01*
G01X328557Y305052D02*
X322357D01*
G01X313863Y316415D02*
Y310215D01*
G01X316927Y309749D02*
Y324749D01*
G01X329927Y309749D02*
X316927D01*
G01X315451Y328584D02*
X313951Y326084D01*
G01X316951D02*
X315451Y328584D01*
G01X323551Y326084D02*
X316951D01*
G01X323551Y339084D02*
Y326084D01*
G01X313863Y323415D02*
Y317215D01*
G01X316927Y324749D02*
X329927D01*
G01X314247Y349110D02*
Y340646D01*
G01X324700Y331307D02*
X326922D01*
X327387Y331460D01*
X327697Y331767D01*
X327800Y332150D01*
X327697Y332533D01*
X327387Y332840D01*
X326922Y332993D01*
X324700D01*
G01X327800Y335250D02*
X324700D01*
X325320Y334790D01*
G01X327800D02*
Y335710D01*
G01X326508Y337622D02*
X326147Y337890D01*
X325940Y338120D01*
X325837Y338427D01*
X325940Y338695D01*
X326147Y338887D01*
X326457Y339040D01*
X326818Y339078D01*
X327128Y339040D01*
X327438Y338887D01*
X327697Y338657D01*
X327800Y338388D01*
X327697Y338082D01*
X327387Y337813D01*
X326922Y337660D01*
X326405Y337622D01*
X325733Y337698D01*
X325372Y337813D01*
X325010Y338005D01*
X324752Y338273D01*
X324700Y338542D01*
X324803Y338810D01*
X325062Y339002D01*
G01X315816Y340794D02*
Y346994D01*
G01X319016Y340794D02*
X315816D01*
G01X319016Y346994D02*
Y340794D01*
G01X319816D02*
Y346994D01*
G01X323016Y340794D02*
X319816D01*
G01X323016Y346994D02*
Y340794D01*
G01X315808Y349250D02*
Y352450D01*
G01X322008Y349250D02*
X315808D01*
G01X322008Y352450D02*
Y349250D01*
G01X315808Y352450D02*
X322008D01*
G01X315816Y346994D02*
X319016D01*
G01X319816D02*
X323016D01*
G01X320549Y429437D02*
Y417437D01*
G01X314549D02*
Y429437D01*
G01X320549Y417437D02*
X314549D01*
G01Y429437D02*
X320549D01*
G01X314549Y436931D02*
Y448931D01*
G01X320549Y436931D02*
X314549D01*
G01X320549Y448931D02*
Y436931D01*
G01X314549Y448931D02*
X320549D01*
G01X313985Y540312D02*
Y543512D01*
G01X320185Y540312D02*
X313985D01*
G01X320185Y543512D02*
Y540312D01*
G01X313985Y543512D02*
X320185D01*
G01Y547512D02*
Y544312D01*
G01X313985Y547512D02*
X320185D01*
G01X313985Y544312D02*
Y547512D01*
G01X320185Y544312D02*
X313985D01*
G01X321685Y554812D02*
X324885D01*
G01X321685Y548612D02*
Y554812D01*
G01X324885Y548612D02*
X321685D01*
G01X324885Y554812D02*
Y548612D01*
G01X325857Y546900D02*
Y544678D01*
X326010Y544213D01*
X326317Y543903D01*
X326700Y543800D01*
X327083Y543903D01*
X327390Y544213D01*
X327543Y544678D01*
Y546900D01*
G01X329800Y543800D02*
Y546900D01*
X329340Y546280D01*
G01Y543800D02*
X330260D01*
G01X333360D02*
Y546900D01*
X331942Y544678D01*
X333858D01*
G01X326346Y548035D02*
Y563389D01*
G01X338827Y548035D02*
X326346D01*
G01Y563389D02*
X339024D01*
G01X313985Y621312D02*
Y624512D01*
G01X320185Y621312D02*
X313985D01*
G01X320185Y624512D02*
Y621312D01*
G01X313985Y624512D02*
X320185D01*
G01Y628512D02*
Y625312D01*
G01X313985Y628512D02*
X320185D01*
G01X313985Y625312D02*
Y628512D01*
G01X320185Y625312D02*
X313985D01*
G01X328927Y858057D02*
X329289Y858287D01*
X329495Y858593D01*
X329547Y858938D01*
X329495Y859245D01*
X329237Y859552D01*
X328927Y859743D01*
X328617Y859782D01*
X328255Y859705D01*
X327997Y859437D01*
X327894Y859168D01*
Y858823D01*
G01Y859168D02*
X327739Y859398D01*
X327480Y859590D01*
X327170Y859667D01*
X326860Y859590D01*
X326602Y859398D01*
X326447Y859053D01*
X326499Y858708D01*
X326705Y858363D01*
G01X317714Y875850D02*
Y861950D01*
G01X329927Y928557D02*
X330289Y928787D01*
X330495Y929093D01*
X330547Y929438D01*
X330495Y929745D01*
X330237Y930052D01*
X329927Y930243D01*
X329617Y930282D01*
X329255Y930205D01*
X328997Y929937D01*
X328894Y929668D01*
Y929323D01*
G01Y929668D02*
X328739Y929898D01*
X328480Y930090D01*
X328170Y930167D01*
X327860Y930090D01*
X327602Y929898D01*
X327447Y929553D01*
X327499Y929208D01*
X327705Y928863D01*
G01X318714Y946350D02*
Y932450D01*
G01X321568Y1069190D02*
G03X384448Y1066535I31384J-2655D01*
G01Y1263386D02*
G03X321466Y1264186I-31496J0D01*
G01X326926Y1291837D02*
Y1294937D01*
G01X328536D02*
Y1291837D01*
G01Y1293387D02*
X326926D01*
G01X330831Y1291837D02*
X331099Y1291889D01*
X331406Y1292044D01*
X331598Y1292302D01*
X331674Y1292664D01*
X331598Y1293025D01*
X331368Y1293335D01*
X331023Y1293490D01*
X330639D01*
X330409Y1293594D01*
X330218Y1293852D01*
X330141Y1294214D01*
X330256Y1294575D01*
X330524Y1294834D01*
X330831Y1294937D01*
X331138Y1294834D01*
X331406Y1294575D01*
X331521Y1294214D01*
X331444Y1293852D01*
X331253Y1293594D01*
X331023Y1293490D01*
X330639D01*
X330294Y1293335D01*
X330064Y1293025D01*
X329988Y1292664D01*
X330064Y1292302D01*
X330256Y1292044D01*
X330563Y1291889D01*
X330831Y1291837D01*
G01X333931D02*
X334199Y1291889D01*
X334506Y1292044D01*
X334698Y1292302D01*
X334774Y1292664D01*
X334698Y1293025D01*
X334468Y1293335D01*
X334123Y1293490D01*
X333739D01*
X333509Y1293594D01*
X333318Y1293852D01*
X333241Y1294214D01*
X333356Y1294575D01*
X333624Y1294834D01*
X333931Y1294937D01*
X334238Y1294834D01*
X334506Y1294575D01*
X334621Y1294214D01*
X334544Y1293852D01*
X334353Y1293594D01*
X334123Y1293490D01*
X333739D01*
X333394Y1293335D01*
X333164Y1293025D01*
X333088Y1292664D01*
X333164Y1292302D01*
X333356Y1292044D01*
X333663Y1291889D01*
X333931Y1291837D01*
G01X318448Y1745941D02*
Y1746491D01*
G01Y1755391D02*
Y1756491D01*
G01Y1765391D02*
Y1765941D01*
G01X318348Y1801391D02*
Y1802491D01*
G01X329498Y-485835D02*
Y-477835D01*
X333298D01*
G01X331898Y-481702D02*
X329498D01*
G01X339398Y-477835D02*
X338598Y-478102D01*
X337998Y-478768D01*
X337598Y-479568D01*
X337298Y-480635D01*
X337198Y-481835D01*
X337298Y-483035D01*
X337598Y-484102D01*
X337998Y-484902D01*
X338598Y-485568D01*
X339398Y-485835D01*
X340198Y-485568D01*
X340798Y-484902D01*
X341198Y-484102D01*
X341498Y-483035D01*
X341598Y-481835D01*
X341498Y-480635D01*
X341198Y-479568D01*
X340798Y-478768D01*
X340198Y-478102D01*
X339398Y-477835D01*
G01X347398D02*
Y-485835D01*
G01X345098Y-477835D02*
X349698D01*
G01X352398Y-488502D02*
X358398D01*
G01X361898Y-482235D02*
X365098D01*
X364798Y-481302D01*
X364298Y-480768D01*
X363598Y-480502D01*
X362898Y-480635D01*
X362298Y-481035D01*
X361898Y-481968D01*
X361698Y-482769D01*
Y-483568D01*
X361898Y-484368D01*
X362398Y-485168D01*
X362998Y-485702D01*
X363698Y-485835D01*
X364398Y-485568D01*
X365098Y-484769D01*
G01X369898Y-480502D02*
X372898Y-485835D01*
G01Y-480502D02*
X369898Y-485835D01*
G01X377598Y-488502D02*
Y-480502D01*
G01Y-481702D02*
X378098Y-481035D01*
X378598Y-480635D01*
X379398Y-480502D01*
X380098Y-480635D01*
X380798Y-481302D01*
X381098Y-482235D01*
X381198Y-483168D01*
X381098Y-484102D01*
X380798Y-485035D01*
X380198Y-485568D01*
X379398Y-485835D01*
X378698Y-485702D01*
X377998Y-485302D01*
X377598Y-484769D01*
G01X389198Y-485835D02*
Y-480502D01*
G01Y-481435D02*
X388798Y-480902D01*
X388198Y-480635D01*
X387498Y-480502D01*
X386798Y-480768D01*
X386198Y-481302D01*
X385798Y-482102D01*
X385598Y-483168D01*
X385798Y-484235D01*
X386198Y-485035D01*
X386798Y-485568D01*
X387498Y-485835D01*
X388198Y-485702D01*
X388798Y-485302D01*
X389198Y-484769D01*
G01X393698Y-485835D02*
Y-480502D01*
G01Y-481835D02*
X394098Y-481168D01*
X394698Y-480635D01*
X395498Y-480502D01*
X396198Y-480635D01*
X396798Y-481168D01*
X397098Y-482102D01*
Y-485835D01*
G01X405198Y-477835D02*
Y-485835D01*
G01Y-484635D02*
X404798Y-485302D01*
X404198Y-485702D01*
X403498Y-485835D01*
X402698Y-485568D01*
X402098Y-484902D01*
X401698Y-484102D01*
X401598Y-483168D01*
X401698Y-482235D01*
X402098Y-481435D01*
X402698Y-480768D01*
X403498Y-480502D01*
X404198Y-480635D01*
X404698Y-480902D01*
X405198Y-481435D01*
G01X409898Y-482235D02*
X413098D01*
X412798Y-481302D01*
X412298Y-480768D01*
X411598Y-480502D01*
X410898Y-480635D01*
X410298Y-481035D01*
X409898Y-481968D01*
X409698Y-482769D01*
Y-483568D01*
X409898Y-484368D01*
X410398Y-485168D01*
X410998Y-485702D01*
X411698Y-485835D01*
X412398Y-485568D01*
X413098Y-484769D01*
G01X417998Y-485835D02*
Y-480502D01*
G01Y-481568D02*
X418498Y-481035D01*
X418998Y-480635D01*
X419698Y-480502D01*
X420198Y-480635D01*
X420798Y-481035D01*
G01X424398Y-488502D02*
X430398D01*
G01X433598Y-485835D02*
Y-477835D01*
G01Y-481835D02*
X434098Y-481035D01*
X434698Y-480635D01*
X435298Y-480502D01*
X436198Y-480768D01*
X436798Y-481302D01*
X437198Y-482235D01*
Y-483302D01*
X436998Y-484368D01*
X436598Y-485168D01*
X435898Y-485702D01*
X435298Y-485835D01*
X434698Y-485702D01*
X434098Y-485302D01*
X433598Y-484635D01*
G01X445198Y-477835D02*
Y-485835D01*
G01Y-484635D02*
X444798Y-485302D01*
X444198Y-485702D01*
X443498Y-485835D01*
X442698Y-485568D01*
X442098Y-484902D01*
X441698Y-484102D01*
X441598Y-483168D01*
X441698Y-482235D01*
X442098Y-481435D01*
X442698Y-480768D01*
X443498Y-480502D01*
X444198Y-480635D01*
X444698Y-480902D01*
X445198Y-481435D01*
G01X330006Y17406D02*
Y14206D01*
G01Y21406D02*
Y18206D01*
G01Y13406D02*
Y10206D01*
G01Y29406D02*
Y26206D01*
G01Y25406D02*
Y22206D01*
G01Y33406D02*
Y30206D01*
G01X343580Y58133D02*
X343890Y58325D01*
X344097Y58555D01*
X344200Y58823D01*
X344097Y59130D01*
X343890Y59360D01*
X343580Y59590D01*
X343167Y59667D01*
X341100D01*
G01X343580Y61157D02*
X343942Y61387D01*
X344148Y61693D01*
X344200Y62038D01*
X344148Y62345D01*
X343890Y62652D01*
X343580Y62843D01*
X343270Y62882D01*
X342908Y62805D01*
X342650Y62537D01*
X342547Y62268D01*
Y61923D01*
G01Y62268D02*
X342392Y62498D01*
X342133Y62690D01*
X341823Y62767D01*
X341513Y62690D01*
X341255Y62498D01*
X341100Y62153D01*
X341152Y61808D01*
X341358Y61463D01*
G01X343580Y64257D02*
X343942Y64487D01*
X344148Y64793D01*
X344200Y65138D01*
X344148Y65445D01*
X343890Y65752D01*
X343580Y65943D01*
X343270Y65982D01*
X342908Y65905D01*
X342650Y65637D01*
X342547Y65368D01*
Y65023D01*
G01Y65368D02*
X342392Y65598D01*
X342133Y65790D01*
X341823Y65867D01*
X341513Y65790D01*
X341255Y65598D01*
X341100Y65253D01*
X341152Y64908D01*
X341358Y64563D01*
G01X334584Y96067D02*
Y99267D01*
G01X340784Y96067D02*
X334584D01*
G01X340784Y99267D02*
Y96067D01*
G01X334584Y99267D02*
X340784D01*
G01X331323Y122172D02*
Y110172D01*
G01X336600Y108095D02*
Y104895D01*
G01X330400Y108095D02*
X336600D01*
G01X330400Y104895D02*
Y108095D01*
G01X336600Y104895D02*
X330400D01*
G01Y100895D02*
Y104095D01*
G01X336600Y100895D02*
X330400D01*
G01X336600Y104095D02*
Y100895D01*
G01X330400Y104095D02*
X336600D01*
G01X337457Y108086D02*
X340657D01*
G01X337457Y101886D02*
Y108086D01*
G01X340657Y101886D02*
X337457D01*
G01X340657Y108086D02*
Y101886D01*
G01X328164Y147537D02*
Y141337D01*
G01X331029Y136438D02*
Y133238D01*
G01Y140438D02*
Y137238D01*
G01X331375Y148437D02*
X334575D01*
G01X331375Y142237D02*
Y148437D01*
G01X334575Y142237D02*
X331375D01*
G01X334575Y148437D02*
Y142237D01*
G01X334300Y152907D02*
X336522D01*
X336987Y153060D01*
X337297Y153367D01*
X337400Y153750D01*
X337297Y154133D01*
X336987Y154440D01*
X336522Y154593D01*
X334300D01*
G01X336780Y156007D02*
X337142Y156237D01*
X337348Y156543D01*
X337400Y156888D01*
X337348Y157195D01*
X337090Y157502D01*
X336780Y157693D01*
X336470Y157732D01*
X336108Y157655D01*
X335850Y157387D01*
X335747Y157118D01*
Y156773D01*
G01Y157118D02*
X335592Y157348D01*
X335333Y157540D01*
X335023Y157617D01*
X334713Y157540D01*
X334455Y157348D01*
X334300Y157003D01*
X334352Y156658D01*
X334558Y156313D01*
G01X336108Y159222D02*
X335747Y159490D01*
X335540Y159720D01*
X335437Y160027D01*
X335540Y160295D01*
X335747Y160487D01*
X336057Y160640D01*
X336418Y160678D01*
X336728Y160640D01*
X337038Y160487D01*
X337297Y160257D01*
X337400Y159988D01*
X337297Y159682D01*
X336987Y159413D01*
X336522Y159260D01*
X336005Y159222D01*
X335333Y159298D01*
X334972Y159413D01*
X334610Y159605D01*
X334352Y159873D01*
X334300Y160142D01*
X334403Y160410D01*
X334662Y160602D01*
G01X336108Y162322D02*
X335747Y162590D01*
X335540Y162820D01*
X335437Y163127D01*
X335540Y163395D01*
X335747Y163587D01*
X336057Y163740D01*
X336418Y163778D01*
X336728Y163740D01*
X337038Y163587D01*
X337297Y163357D01*
X337400Y163088D01*
X337297Y162782D01*
X336987Y162513D01*
X336522Y162360D01*
X336005Y162322D01*
X335333Y162398D01*
X334972Y162513D01*
X334610Y162705D01*
X334352Y162973D01*
X334300Y163242D01*
X334403Y163510D01*
X334662Y163702D01*
G01X332511Y165304D02*
Y149950D01*
G01X335331Y203645D02*
Y197645D01*
G01X333284Y208464D02*
Y205264D01*
G01X328114Y226801D02*
X340318D01*
Y211497D01*
X328114D01*
Y226801D01*
G01X346603Y215121D02*
X343503D01*
Y216041D01*
X343658Y216348D01*
X344020Y216578D01*
X344433Y216655D01*
X344846Y216578D01*
X345156Y216386D01*
X345311Y216041D01*
Y215121D01*
G01X343503Y218145D02*
X345725D01*
X346190Y218298D01*
X346500Y218605D01*
X346603Y218988D01*
X346500Y219371D01*
X346190Y219678D01*
X345725Y219831D01*
X343503D01*
G01X345311Y221360D02*
X344950Y221628D01*
X344743Y221858D01*
X344640Y222165D01*
X344743Y222433D01*
X344950Y222625D01*
X345260Y222778D01*
X345621Y222816D01*
X345931Y222778D01*
X346241Y222625D01*
X346500Y222395D01*
X346603Y222126D01*
X346500Y221820D01*
X346190Y221551D01*
X345725Y221398D01*
X345208Y221360D01*
X344536Y221436D01*
X344175Y221551D01*
X343813Y221743D01*
X343555Y222011D01*
X343503Y222280D01*
X343606Y222548D01*
X343865Y222740D01*
G01X343503Y225188D02*
X343606Y224881D01*
X343865Y224651D01*
X344175Y224498D01*
X344588Y224383D01*
X345053Y224345D01*
X345518Y224383D01*
X345931Y224498D01*
X346241Y224651D01*
X346500Y224881D01*
X346603Y225188D01*
X346500Y225495D01*
X346241Y225725D01*
X345931Y225878D01*
X345518Y225993D01*
X345053Y226031D01*
X344588Y225993D01*
X344175Y225878D01*
X343865Y225725D01*
X343606Y225495D01*
X343503Y225188D01*
G01X334510Y254969D02*
Y245521D01*
G01X332777Y231446D02*
X329577D01*
G01X332777Y237646D02*
Y231446D01*
G01X329577Y237646D02*
X332777D01*
G01X329577Y231446D02*
Y237646D01*
G01X344887Y231459D02*
X341687D01*
G01Y237659D02*
X344887D01*
G01X341687Y231459D02*
Y237659D01*
G01X332455Y243678D02*
Y240478D01*
G01X336652Y231434D02*
X333452D01*
G01X336652Y237634D02*
Y231434D01*
G01X333452Y237634D02*
X336652D01*
G01X333452Y231434D02*
Y237634D01*
G01X337687Y237659D02*
X340887D01*
G01X337687Y231459D02*
Y237659D01*
G01X340887Y231459D02*
X337687D01*
G01X340887Y237659D02*
Y231459D01*
G01X336313Y240081D02*
Y243281D01*
G01X342513Y240081D02*
X336313D01*
G01X342513Y243281D02*
Y240081D01*
G01X336313Y243281D02*
X342513D01*
G01X331092Y254969D02*
X334510D01*
G01X329092Y253245D02*
X331092Y254969D01*
G01X342117Y252199D02*
Y248999D01*
G01X335917Y252199D02*
X342117D01*
G01X335917Y248999D02*
Y252199D01*
G01X342117Y248999D02*
X335917D01*
G01X328557Y308252D02*
Y305052D01*
G01X331100Y310657D02*
X333322D01*
X333787Y310810D01*
X334097Y311117D01*
X334200Y311500D01*
X334097Y311883D01*
X333787Y312190D01*
X333322Y312343D01*
X331100D01*
G01X334200Y314600D02*
X331100D01*
X331720Y314140D01*
G01X334200D02*
Y315060D01*
G01Y317623D02*
X333528Y317700D01*
X332960Y317815D01*
X332443Y317968D01*
X331875Y318160D01*
X331100Y318467D01*
Y316933D01*
G01X329927Y324749D02*
Y309749D01*
G01X340886Y384248D02*
X344086D01*
G01X340886Y378048D02*
Y384248D01*
G01X344086Y378048D02*
X340886D01*
G01X344086Y384248D02*
Y378048D01*
G01X340448Y415040D02*
X371452D01*
G01X340448Y429840D02*
Y415040D01*
G01X371452Y429840D02*
X340448D01*
G01X341172Y470598D02*
X338072D01*
Y471518D01*
X338227Y471825D01*
X338589Y472055D01*
X339002Y472132D01*
X339415Y472055D01*
X339725Y471863D01*
X339880Y471518D01*
Y470598D01*
G01X341172Y473622D02*
X338072D01*
Y474388D01*
X338227Y474695D01*
X338434Y474925D01*
X338744Y475117D01*
X339105Y475270D01*
X339622Y475308D01*
X340139Y475270D01*
X340500Y475117D01*
X340810Y474925D01*
X341017Y474695D01*
X341172Y474388D01*
Y473622D01*
G01X340707Y476722D02*
X340965Y476952D01*
X341120Y477220D01*
X341172Y477565D01*
X341069Y477910D01*
X340862Y478178D01*
X340500Y478370D01*
X340087Y478408D01*
X339674Y478332D01*
X339415Y478140D01*
X339209Y477872D01*
X339157Y477603D01*
X339209Y477335D01*
X339415Y476990D01*
X338072Y477105D01*
Y478140D01*
G01X341172Y481125D02*
X338072D01*
X340294Y479707D01*
Y481623D01*
G01X340822Y465640D02*
Y468066D01*
G01X354077Y467810D02*
X342581D01*
G01D02*
Y497369D01*
G01X342124Y461359D02*
Y464459D01*
X343044D01*
X343351Y464304D01*
X343581Y463942D01*
X343658Y463529D01*
X343581Y463116D01*
X343389Y462806D01*
X343044Y462651D01*
X342124D01*
G01X345148Y464459D02*
Y462237D01*
X345301Y461772D01*
X345608Y461462D01*
X345991Y461359D01*
X346374Y461462D01*
X346681Y461772D01*
X346834Y462237D01*
Y464459D01*
G01X349014Y461359D02*
X349091Y462031D01*
X349206Y462599D01*
X349359Y463116D01*
X349551Y463684D01*
X349858Y464459D01*
X348324D01*
G01X351539Y461721D02*
X351808Y461462D01*
X352114Y461359D01*
X352421Y461462D01*
X352689Y461772D01*
X352881Y462237D01*
X352958Y462702D01*
Y463271D01*
X352881Y463736D01*
X352689Y464149D01*
X352459Y464356D01*
X352191Y464459D01*
X351884Y464356D01*
X351654Y464149D01*
X351501Y463839D01*
X351424Y463426D01*
X351501Y463064D01*
X351693Y462702D01*
X351923Y462496D01*
X352191Y462444D01*
X352498Y462547D01*
X352728Y462806D01*
X352958Y463271D01*
G01X347929Y501010D02*
Y498770D01*
G01X349554Y499983D02*
X346304D01*
G01X342581Y497369D02*
X354077D01*
G01X340685Y553612D02*
Y559812D01*
G01X343885Y553612D02*
X340685D01*
G01X343885Y559812D02*
Y553612D01*
G01X339024Y563389D02*
Y548035D01*
G01X343885Y560612D02*
X340685D01*
G01X343885Y566812D02*
Y560612D01*
G01X340685Y566812D02*
X343885D01*
G01X340685Y560612D02*
Y566812D01*
G01Y559812D02*
X343885D01*
G01X328346Y1071456D02*
Y1258464D01*
G01X384448Y1066535D02*
G03X331419Y1089520I-31496J0D01*
G01X341614Y1100772D02*
Y1103872D01*
G01X343224D02*
Y1100772D01*
G01Y1102322D02*
X341614D01*
G01X344867Y1101134D02*
X345136Y1100875D01*
X345442Y1100772D01*
X345749Y1100875D01*
X346017Y1101185D01*
X346209Y1101650D01*
X346286Y1102115D01*
Y1102684D01*
X346209Y1103149D01*
X346017Y1103562D01*
X345787Y1103769D01*
X345519Y1103872D01*
X345212Y1103769D01*
X344982Y1103562D01*
X344829Y1103252D01*
X344752Y1102839D01*
X344829Y1102477D01*
X345021Y1102115D01*
X345251Y1101909D01*
X345519Y1101857D01*
X345826Y1101960D01*
X346056Y1102219D01*
X346286Y1102684D01*
G01X347891Y1102064D02*
X348159Y1102425D01*
X348389Y1102632D01*
X348696Y1102735D01*
X348964Y1102632D01*
X349156Y1102425D01*
X349309Y1102115D01*
X349347Y1101754D01*
X349309Y1101444D01*
X349156Y1101134D01*
X348926Y1100875D01*
X348657Y1100772D01*
X348351Y1100875D01*
X348082Y1101185D01*
X347929Y1101650D01*
X347891Y1102167D01*
X347967Y1102839D01*
X348082Y1103200D01*
X348274Y1103562D01*
X348542Y1103820D01*
X348811Y1103872D01*
X349079Y1103769D01*
X349271Y1103510D01*
G01X344148Y1135604D02*
Y1141804D01*
G01X347348Y1135604D02*
X344148D01*
G01X343348D02*
X340148D01*
G01X343348Y1141804D02*
Y1135604D01*
G01X340148D02*
Y1141804D01*
G01X338355D02*
Y1135604D01*
X335155D01*
Y1141804D01*
X338355D01*
G01X332279Y1156532D02*
X334501D01*
X334966Y1156685D01*
X335276Y1156992D01*
X335379Y1157375D01*
X335276Y1157758D01*
X334966Y1158065D01*
X334501Y1158218D01*
X332279D01*
G01X335379Y1160935D02*
X332279D01*
X334501Y1159517D01*
Y1161433D01*
G01X332796Y1162847D02*
X332486Y1163077D01*
X332331Y1163345D01*
X332279Y1163652D01*
X332382Y1164035D01*
X332641Y1164303D01*
X332951Y1164380D01*
X333261Y1164342D01*
X333519Y1164188D01*
X334036Y1163422D01*
X334397Y1163077D01*
X334914Y1162847D01*
X335379Y1162770D01*
Y1164380D01*
G01X334914Y1165832D02*
X335172Y1166062D01*
X335327Y1166330D01*
X335379Y1166675D01*
X335276Y1167020D01*
X335069Y1167288D01*
X334707Y1167480D01*
X334294Y1167518D01*
X333881Y1167442D01*
X333622Y1167250D01*
X333416Y1166982D01*
X333364Y1166713D01*
X333416Y1166445D01*
X333622Y1166100D01*
X332279Y1166215D01*
Y1167250D01*
G01X344148Y1141804D02*
X347348D01*
G01X340148D02*
X343348D01*
G01X348525Y1144471D02*
X342325D01*
Y1147671D01*
X348525D01*
Y1144471D01*
G01X336345Y1161425D02*
X337538Y1160525D01*
X336345Y1159525D01*
G01Y1161525D02*
Y1164625D01*
X348747D01*
Y1156425D01*
X336345D01*
Y1159525D01*
G01X339229Y1180425D02*
Y1174225D01*
X336029D01*
Y1180425D01*
X339229D01*
G01X339855Y1180445D02*
Y1186645D01*
X343055D01*
Y1180445D01*
X339855D01*
G01X343871Y1180375D02*
Y1186575D01*
X347071D01*
Y1180375D01*
X343871D01*
G01X343752Y1201918D02*
X340552D01*
G01X343752Y1208118D02*
Y1201918D01*
G01X340552D02*
Y1208118D01*
G01X336722Y1189370D02*
Y1195570D01*
X339922D01*
Y1189370D01*
X336722D01*
G01X343898Y1195516D02*
Y1189316D01*
X340698D01*
Y1195516D01*
X343898D01*
G01X340552Y1208118D02*
X343752D01*
G01X342257Y1220712D02*
X344519Y1222974D01*
G01X346641Y1216328D02*
X342257Y1220712D01*
G01X330944Y1240855D02*
G03X384448Y1263386I22008J22531D01*
G01X343641Y1722383D02*
X342031Y1719283D01*
G01X343641D02*
X342031Y1722383D01*
G01X339736D02*
Y1719283D01*
X340196Y1719903D01*
G01Y1722383D02*
X339276D01*
G01X336176D02*
Y1719283D01*
X337594Y1721505D01*
X335678D01*
G01X333286Y1723583D02*
X343286D01*
G01D02*
Y1726083D01*
G01X333286Y1724133D02*
Y1723583D01*
G01X343286Y1731083D02*
Y1736083D01*
G01X333286Y1734133D02*
Y1733033D01*
G01X343286Y1741083D02*
Y1743583D01*
G01D02*
X333286D01*
G01D02*
Y1743033D01*
G01X343567Y1768424D02*
X341957Y1765324D01*
G01X343567D02*
X341957Y1768424D01*
G01X340390Y1765841D02*
X340160Y1765531D01*
X339892Y1765376D01*
X339585Y1765324D01*
X339202Y1765427D01*
X338934Y1765686D01*
X338857Y1765996D01*
X338895Y1766306D01*
X339049Y1766564D01*
X339815Y1767081D01*
X340160Y1767442D01*
X340390Y1767959D01*
X340467Y1768424D01*
X338857D01*
G01X336562Y1765324D02*
X336869Y1765427D01*
X337099Y1765686D01*
X337252Y1765996D01*
X337367Y1766409D01*
X337405Y1766874D01*
X337367Y1767339D01*
X337252Y1767752D01*
X337099Y1768062D01*
X336869Y1768321D01*
X336562Y1768424D01*
X336255Y1768321D01*
X336025Y1768062D01*
X335872Y1767752D01*
X335757Y1767339D01*
X335719Y1766874D01*
X335757Y1766409D01*
X335872Y1765996D01*
X336025Y1765686D01*
X336255Y1765427D01*
X336562Y1765324D01*
G01X343212Y1769624D02*
Y1772124D01*
G01X333212Y1769624D02*
X343212D01*
G01X333212Y1770174D02*
Y1769624D01*
G01X343212Y1777124D02*
Y1782124D01*
G01X333212Y1780174D02*
Y1779074D01*
G01X343212Y1787124D02*
Y1789624D01*
G01X333212D02*
Y1789074D01*
G01X343212Y1789624D02*
X333212D01*
G01X345727Y57756D02*
Y111754D01*
G01X346023Y58150D02*
Y111754D01*
G01X352108Y57756D02*
X345727D01*
G01X351703Y58150D02*
X346023D01*
G01Y118848D02*
Y114048D01*
G01X345727Y118848D02*
Y114048D01*
G01X346023Y132607D02*
Y128340D01*
G01X345727Y132607D02*
Y128340D01*
G01Y125781D02*
Y121219D01*
G01X346023Y125781D02*
Y121219D01*
G01Y152756D02*
Y135371D01*
G01X345727Y153150D02*
Y135371D01*
G01X359181Y156615D02*
X359928Y155990D01*
X360768Y155615D01*
X361514D01*
X362261Y155990D01*
X362821Y156615D01*
X363101Y157490D01*
X362914Y158365D01*
X362448Y159115D01*
X361608Y159615D01*
X360488Y159865D01*
X359834Y160365D01*
X359554Y161240D01*
X359741Y162115D01*
X360208Y162740D01*
X360861Y163115D01*
X361514D01*
X362168Y162865D01*
X362728Y162240D01*
G01X366681Y156615D02*
X367428Y155990D01*
X368268Y155615D01*
X369014D01*
X369761Y155990D01*
X370321Y156615D01*
X370601Y157490D01*
X370414Y158365D01*
X369948Y159115D01*
X369108Y159615D01*
X367988Y159865D01*
X367334Y160365D01*
X367054Y161240D01*
X367241Y162115D01*
X367708Y162740D01*
X368361Y163115D01*
X369014D01*
X369668Y162865D01*
X370228Y162240D01*
G01X374088Y155615D02*
Y163115D01*
X375954D01*
X376701Y162740D01*
X377261Y162240D01*
X377728Y161490D01*
X378101Y160615D01*
X378194Y159365D01*
X378101Y158115D01*
X377728Y157240D01*
X377261Y156490D01*
X376701Y155990D01*
X375954Y155615D01*
X374088D01*
G01X381588Y157115D02*
X382148Y156240D01*
X382894Y155740D01*
X383734Y155615D01*
X384481Y155740D01*
X385228Y156365D01*
X385694Y157115D01*
X385788Y157865D01*
X385601Y158740D01*
X384948Y159365D01*
X384294Y159615D01*
X383454D01*
G01X384294D02*
X384854Y159990D01*
X385321Y160615D01*
X385508Y161365D01*
X385321Y162115D01*
X384854Y162740D01*
X384014Y163115D01*
X383174Y162990D01*
X382334Y162490D01*
G01X345727Y153150D02*
X352108D01*
G01X346023Y152756D02*
X351703D01*
G01X349454Y189535D02*
X347028D01*
G01X345914Y195583D02*
Y184087D01*
G01X360000Y204583D02*
X356900D01*
Y205503D01*
X357055Y205810D01*
X357417Y206040D01*
X357830Y206117D01*
X358243Y206040D01*
X358553Y205848D01*
X358708Y205503D01*
Y204583D01*
G01X360000Y207607D02*
X356900D01*
Y208373D01*
X357055Y208680D01*
X357262Y208910D01*
X357572Y209102D01*
X357933Y209255D01*
X358450Y209293D01*
X358967Y209255D01*
X359328Y209102D01*
X359638Y208910D01*
X359845Y208680D01*
X360000Y208373D01*
Y207607D01*
G01X359380Y210707D02*
X359742Y210937D01*
X359948Y211243D01*
X360000Y211588D01*
X359948Y211895D01*
X359690Y212202D01*
X359380Y212393D01*
X359070Y212432D01*
X358708Y212355D01*
X358450Y212087D01*
X358347Y211818D01*
Y211473D01*
G01Y211818D02*
X358192Y212048D01*
X357933Y212240D01*
X357623Y212317D01*
X357313Y212240D01*
X357055Y212048D01*
X356900Y211703D01*
X356952Y211358D01*
X357158Y211013D01*
G01X360000Y215110D02*
X356900D01*
X359122Y213692D01*
Y215608D01*
G01X344887Y237659D02*
Y231459D01*
G01X359600Y263983D02*
X356500D01*
Y264903D01*
X356655Y265210D01*
X357017Y265440D01*
X357430Y265517D01*
X357843Y265440D01*
X358153Y265248D01*
X358308Y264903D01*
Y263983D01*
G01X359600Y267007D02*
X356500D01*
Y267773D01*
X356655Y268080D01*
X356862Y268310D01*
X357172Y268502D01*
X357533Y268655D01*
X358050Y268693D01*
X358567Y268655D01*
X358928Y268502D01*
X359238Y268310D01*
X359445Y268080D01*
X359600Y267773D01*
Y267007D01*
G01X359238Y270298D02*
X359497Y270567D01*
X359600Y270873D01*
X359497Y271180D01*
X359187Y271448D01*
X358722Y271640D01*
X358257Y271717D01*
X357688D01*
X357223Y271640D01*
X356810Y271448D01*
X356603Y271218D01*
X356500Y270950D01*
X356603Y270643D01*
X356810Y270413D01*
X357120Y270260D01*
X357533Y270183D01*
X357895Y270260D01*
X358257Y270452D01*
X358463Y270682D01*
X358515Y270950D01*
X358412Y271257D01*
X358153Y271487D01*
X357688Y271717D01*
G01X359600Y274050D02*
X356500D01*
X357120Y273590D01*
G01X359600D02*
Y274510D01*
G01X355543Y388619D02*
X353590D01*
G01D02*
Y390572D01*
G01X344886Y384248D02*
X348086D01*
G01X344886Y378048D02*
Y384248D01*
G01X348086Y378048D02*
X344886D01*
G01X348086Y384248D02*
Y378048D01*
G01X356886Y384248D02*
X360086D01*
G01X356886Y378048D02*
Y384248D01*
G01X360086Y378048D02*
X356886D01*
G01X360086Y384248D02*
Y378048D01*
G01X349191Y392408D02*
X345991D01*
G01X349191Y398608D02*
Y392408D01*
G01X345991D02*
Y398608D01*
G01X348886Y384248D02*
X352086D01*
G01X348886Y378048D02*
Y384248D01*
G01X352086Y378048D02*
X348886D01*
G01X352086Y384248D02*
Y378048D01*
G01X352886Y384248D02*
X356086D01*
G01X352886Y378048D02*
Y384248D01*
G01X356086Y378048D02*
X352886D01*
G01X356086Y384248D02*
Y378048D01*
G01X353590Y400431D02*
X355543D01*
G01X353590Y398478D02*
Y400431D01*
G01X359876Y404932D02*
Y408132D01*
G01X366076Y404932D02*
X359876D01*
G01Y408132D02*
X366076D01*
G01X349814Y399509D02*
X347552Y401771D01*
G01X354198Y403893D02*
X349814Y399509D01*
G01X351936Y406155D02*
X354198Y403893D01*
G01X347552Y401771D02*
X351936Y406155D01*
G01X345991Y398608D02*
X349191D01*
G01X351602Y407402D02*
Y413602D01*
G01X354802Y407402D02*
X351602D01*
G01X354802Y413602D02*
Y407402D01*
G01X351602Y413602D02*
X354802D01*
G01X359042Y431902D02*
Y443902D01*
G01X365042Y431902D02*
X359042D01*
G01Y443902D02*
X365042D01*
G01X360220Y445757D02*
Y448957D01*
G01X366420Y445757D02*
X360220D01*
G01Y448957D02*
X366420D01*
G01X352125Y459934D02*
Y456734D01*
G01X345925D02*
Y459934D01*
G01X352125Y456734D02*
X345925D01*
G01X352125Y451934D02*
Y448734D01*
G01X345925Y451934D02*
X352125D01*
G01X345925Y448734D02*
Y451934D01*
G01X352125Y448734D02*
X345925D01*
G01Y452734D02*
Y455934D01*
G01X352125Y452734D02*
X345925D01*
G01X352125Y455934D02*
Y452734D01*
G01X345925Y455934D02*
X352125D01*
G01X366614Y451163D02*
X354840D01*
G01D02*
Y460925D01*
G01X356176Y469326D02*
X368176D01*
G01X356176Y463326D02*
Y469326D01*
G01X368176Y463326D02*
X356176D01*
G01X354077Y497369D02*
Y467810D01*
G01X345925Y459934D02*
X352125D01*
G01X354840Y460925D02*
X366614D01*
G01X355933Y478517D02*
Y490517D01*
G01X361933Y478517D02*
X355933D01*
G01Y490517D02*
X361933D01*
G01X347348Y1141804D02*
Y1135604D01*
G01X359348D02*
X356148D01*
G01X359348Y1141804D02*
Y1135604D01*
G01X356148D02*
Y1141804D01*
G01X355348Y1135604D02*
X352148D01*
G01X355348Y1141804D02*
Y1135604D01*
G01X352148D02*
Y1141804D01*
G01X363348Y1135604D02*
X360148D01*
G01D02*
Y1141804D01*
G01X351348Y1135604D02*
X348148D01*
G01X351348Y1141804D02*
Y1135604D01*
G01X348148D02*
Y1141804D01*
G01X350746Y1149643D02*
Y1161167D01*
G01X362950Y1149643D02*
X350746D01*
G01X359848Y1155405D02*
X362950Y1152405D01*
G01Y1158507D02*
X359848Y1155405D01*
G01X356148Y1141804D02*
X359348D01*
G01X352148D02*
X355348D01*
G01X360148D02*
X363348D01*
G01X348148D02*
X351348D01*
G01X350746Y1161167D02*
X362950D01*
G01X349256Y1169520D02*
Y1172720D01*
G01X355456Y1169520D02*
X349256D01*
G01X355456Y1172720D02*
Y1169520D01*
G01X356298Y1168770D02*
Y1171970D01*
G01X362498Y1168770D02*
X356298D01*
G01Y1171970D02*
X362498D01*
G01X356843Y1172586D02*
Y1178786D01*
G01X360043Y1172586D02*
X356843D01*
G01X360043Y1178786D02*
Y1172586D01*
G01X349256Y1172720D02*
X355456D01*
G01X348814Y1179765D02*
X352014D01*
G01X348814Y1173565D02*
Y1179765D01*
G01X352014Y1173565D02*
X348814D01*
G01X352014Y1179765D02*
Y1173565D01*
G01X356843Y1178786D02*
X360043D01*
G01X352814Y1179765D02*
X356014D01*
G01X352814Y1173565D02*
Y1179765D01*
G01X356014Y1173565D02*
X352814D01*
G01X356014Y1179765D02*
Y1173565D01*
G01X358161Y1186726D02*
X361361D01*
G01X358161Y1180526D02*
Y1186726D01*
G01X361361Y1180526D02*
X358161D01*
G01X352842Y1186730D02*
X356042D01*
G01X352842Y1180530D02*
Y1186730D01*
G01X356042Y1180530D02*
X352842D01*
G01X356042Y1186730D02*
Y1180530D01*
G01X348842Y1186730D02*
X352042D01*
G01X348842Y1180530D02*
Y1186730D01*
G01X352042Y1180530D02*
X348842D01*
G01X352042Y1186730D02*
Y1180530D01*
G01X347987Y1201880D02*
X344787D01*
G01X347987Y1208080D02*
Y1201880D01*
G01X344787D02*
Y1208080D01*
G01X352002Y1201918D02*
X348802D01*
G01X352002Y1208118D02*
Y1201918D01*
G01X348802D02*
Y1208118D01*
G01X356002Y1201918D02*
X352802D01*
G01X356002Y1208118D02*
Y1201918D01*
G01X352802D02*
Y1208118D01*
G01X360002Y1201918D02*
X356802D01*
G01X360002Y1208118D02*
Y1201918D01*
G01X356802D02*
Y1208118D01*
G01X352000Y1193894D02*
X348800D01*
G01X352000Y1200094D02*
Y1193894D01*
G01X348800Y1200094D02*
X352000D01*
G01X348800Y1193894D02*
Y1200094D01*
G01X356000Y1193894D02*
X352800D01*
G01X356000Y1200094D02*
Y1193894D01*
G01X352800Y1200094D02*
X356000D01*
G01X352800Y1193894D02*
Y1200094D01*
G01X360000Y1193894D02*
X356800D01*
G01X360000Y1200094D02*
Y1193894D01*
G01X356800Y1200094D02*
X360000D01*
G01X356800Y1193894D02*
Y1200094D01*
G01X355867Y1189999D02*
X349667D01*
Y1193199D01*
X355867D01*
Y1189999D01*
G01X347736Y1195651D02*
Y1189451D01*
X344536D01*
Y1195651D01*
X347736D01*
G01X344787Y1208080D02*
X347987D01*
G01X348903Y1218590D02*
X346641Y1216328D01*
G01X344519Y1222974D02*
X348903Y1218590D01*
G01X351732Y1221417D02*
X349470Y1219155D01*
G01X347348Y1225801D02*
X351732Y1221417D01*
G01X349470Y1219155D02*
X345086Y1223539D01*
G01X348802Y1208118D02*
X352002D01*
G01X352802D02*
X356002D01*
G01X356802D02*
X360002D01*
G01X361826Y1219035D02*
X357442Y1223419D01*
G01X358430Y1215639D02*
X356168Y1213377D01*
G01X354046Y1220023D02*
X358430Y1215639D01*
G01X351784Y1217761D02*
X354046Y1220023D01*
G01X356168Y1213377D02*
X351784Y1217761D01*
G01X361259Y1218468D02*
X358997Y1216206D01*
G01X356875Y1222852D02*
X361259Y1218468D01*
G01X354613Y1220590D02*
X356875Y1222852D01*
G01X358997Y1216206D02*
X354613Y1220590D01*
G01X355602Y1212811D02*
X353340Y1210549D01*
G01X351218Y1217195D02*
X355602Y1212811D01*
G01X348956Y1214933D02*
X351218Y1217195D01*
G01X353340Y1210549D02*
X348956Y1214933D01*
G01X345086Y1223539D02*
X347348Y1225801D01*
G01X354561Y1224246D02*
X352299Y1221984D01*
G01X350177Y1228630D02*
X354561Y1224246D01*
G01X347915Y1226368D02*
X350177Y1228630D01*
G01X352299Y1221984D02*
X347915Y1226368D01*
G01X357442Y1223419D02*
X359704Y1225681D01*
G01D02*
X364088Y1221297D01*
G01X360270Y1226247D02*
X362532Y1228509D01*
G01X364654Y1221863D02*
X360270Y1226247D01*
G01X357390Y1227075D02*
X355128Y1224813D01*
G01X353006Y1231459D02*
X357390Y1227075D01*
G01X350744Y1229197D02*
X353006Y1231459D01*
G01X355128Y1224813D02*
X350744Y1229197D01*
G01X370531Y57756D02*
Y104670D01*
G01X370235Y58150D02*
Y104670D01*
G01X370531Y57756D02*
X364150D01*
G01X370235Y58150D02*
X364555D01*
G01X376063Y97026D02*
Y103226D01*
G01X379263Y97026D02*
X376063D01*
G01X378067Y86929D02*
X374867D01*
G01Y93129D02*
X378067D01*
G01X374867Y86929D02*
Y93129D01*
G01X370531Y111507D02*
Y107060D01*
G01X370235Y111507D02*
Y107060D01*
G01Y118680D02*
Y114087D01*
G01X370531Y118680D02*
Y114087D01*
G01X376063Y103226D02*
X379263D01*
G01X370235Y132859D02*
Y128325D01*
G01X370531Y132859D02*
Y128325D01*
G01Y125844D02*
Y121329D01*
G01X370235Y125844D02*
Y121329D01*
G01Y152756D02*
Y135390D01*
G01X370531Y153150D02*
Y135390D01*
G01X362631Y164436D02*
X377431D01*
G01X362631Y195440D02*
Y164436D01*
G01X364150Y153150D02*
X370531D01*
G01X364555Y152756D02*
X370235D01*
G01X377431Y195440D02*
X362631D01*
G01X374744Y213035D02*
Y225035D01*
G01X380744Y213035D02*
X374744D01*
G01X366634Y199912D02*
Y202338D01*
G01X372682Y203452D02*
X361186D01*
G01X372682Y233011D02*
Y203452D01*
G01X361186D02*
Y233011D01*
G01X374744Y225035D02*
X380744D01*
G01X366534Y236652D02*
Y234412D01*
G01X368159Y235625D02*
X364909D01*
G01X361186Y233011D02*
X372682D01*
G01X374027Y250325D02*
Y234813D01*
G01D02*
X405119D01*
G01X366403Y259204D02*
Y261630D01*
G01X372451Y262744D02*
X360955D01*
G01X372451Y292303D02*
Y262744D01*
G01X360955D02*
Y292303D01*
G01X374206Y251936D02*
Y255036D01*
X375126D01*
X375433Y254881D01*
X375663Y254519D01*
X375740Y254106D01*
X375663Y253693D01*
X375471Y253383D01*
X375126Y253228D01*
X374206D01*
G01X377230Y251936D02*
Y255036D01*
X377996D01*
X378303Y254881D01*
X378533Y254674D01*
X378725Y254364D01*
X378878Y254003D01*
X378916Y253486D01*
X378878Y252969D01*
X378725Y252608D01*
X378533Y252298D01*
X378303Y252091D01*
X377996Y251936D01*
X377230D01*
G01X380330Y252556D02*
X380560Y252194D01*
X380866Y251988D01*
X381211Y251936D01*
X381518Y251988D01*
X381825Y252246D01*
X382016Y252556D01*
X382055Y252866D01*
X381978Y253228D01*
X381710Y253486D01*
X381441Y253589D01*
X381096D01*
G01X381441D02*
X381671Y253744D01*
X381863Y254003D01*
X381940Y254313D01*
X381863Y254623D01*
X381671Y254881D01*
X381326Y255036D01*
X380981Y254984D01*
X380636Y254778D01*
G01X383430Y252556D02*
X383660Y252194D01*
X383966Y251988D01*
X384311Y251936D01*
X384618Y251988D01*
X384925Y252246D01*
X385116Y252556D01*
X385155Y252866D01*
X385078Y253228D01*
X384810Y253486D01*
X384541Y253589D01*
X384196D01*
G01X384541D02*
X384771Y253744D01*
X384963Y254003D01*
X385040Y254313D01*
X384963Y254623D01*
X384771Y254881D01*
X384426Y255036D01*
X384081Y254984D01*
X383736Y254778D01*
G01X405119Y250325D02*
X374027D01*
G01X374322Y271655D02*
Y283655D01*
G01X380322Y271655D02*
X374322D01*
G01Y283655D02*
X380322D01*
G01X366672Y297627D02*
Y295387D01*
G01X368297Y296600D02*
X365047D01*
G01X360955Y292303D02*
X372451D01*
G01X378837Y372155D02*
X375637D01*
G01D02*
Y378355D01*
G01X369331Y368964D02*
X372531D01*
G01X369331Y362764D02*
Y368964D01*
G01X372531Y362764D02*
X369331D01*
G01X372531Y368964D02*
Y362764D01*
G01X374864Y377279D02*
Y371079D01*
X371664D01*
Y377279D01*
X374864D01*
G01X367100Y389057D02*
X369322D01*
X369787Y389210D01*
X370097Y389517D01*
X370200Y389900D01*
X370097Y390283D01*
X369787Y390590D01*
X369322Y390743D01*
X367100D01*
G01X370200Y393000D02*
X370148Y393268D01*
X369993Y393575D01*
X369735Y393767D01*
X369373Y393843D01*
X369012Y393767D01*
X368702Y393537D01*
X368547Y393192D01*
Y392808D01*
X368443Y392578D01*
X368185Y392387D01*
X367823Y392310D01*
X367462Y392425D01*
X367203Y392693D01*
X367100Y393000D01*
X367203Y393307D01*
X367462Y393575D01*
X367823Y393690D01*
X368185Y393613D01*
X368443Y393422D01*
X368547Y393192D01*
Y392808D01*
X368702Y392463D01*
X369012Y392233D01*
X369373Y392157D01*
X369735Y392233D01*
X369993Y392425D01*
X370148Y392732D01*
X370200Y393000D01*
G01X367100Y396100D02*
X367203Y395793D01*
X367462Y395563D01*
X367772Y395410D01*
X368185Y395295D01*
X368650Y395257D01*
X369115Y395295D01*
X369528Y395410D01*
X369838Y395563D01*
X370097Y395793D01*
X370200Y396100D01*
X370097Y396407D01*
X369838Y396637D01*
X369528Y396790D01*
X369115Y396905D01*
X368650Y396943D01*
X368185Y396905D01*
X367772Y396790D01*
X367462Y396637D01*
X367203Y396407D01*
X367100Y396100D01*
G01X365402Y388619D02*
X363449D01*
G01X365402Y390572D02*
Y388619D01*
G01X375637Y378355D02*
X378837D01*
G01X368086Y378048D02*
X364886D01*
G01X368086Y384248D02*
Y378048D01*
G01X364886Y384248D02*
X368086D01*
G01X364886Y378048D02*
Y384248D01*
G01X372086Y378048D02*
X368886D01*
G01X372086Y384248D02*
Y378048D01*
G01X368886Y384248D02*
X372086D01*
G01X368886Y378048D02*
Y384248D01*
G01X360886D02*
X364086D01*
G01X360886Y378048D02*
Y384248D01*
G01X364086Y378048D02*
X360886D01*
G01X364086Y384248D02*
Y378048D01*
G01X376646Y383139D02*
X373546D01*
Y384059D01*
X373701Y384366D01*
X374063Y384596D01*
X374476Y384673D01*
X374889Y384596D01*
X375199Y384404D01*
X375354Y384059D01*
Y383139D01*
G01X373546Y386163D02*
X375768D01*
X376233Y386316D01*
X376543Y386623D01*
X376646Y387006D01*
X376543Y387389D01*
X376233Y387696D01*
X375768Y387849D01*
X373546D01*
G01X374063Y389378D02*
X373753Y389608D01*
X373598Y389876D01*
X373546Y390183D01*
X373649Y390566D01*
X373908Y390834D01*
X374218Y390911D01*
X374528Y390873D01*
X374786Y390719D01*
X375303Y389953D01*
X375664Y389608D01*
X376181Y389378D01*
X376646Y389301D01*
Y390911D01*
G01Y393666D02*
X373546D01*
X375768Y392248D01*
Y394164D01*
G01X365402Y400431D02*
Y398478D01*
G01X363449Y400431D02*
X365402D01*
G01X374179Y411597D02*
X376605D01*
G01X370187Y401941D02*
X366987D01*
G01X370187Y408141D02*
Y401941D01*
G01X366987Y408141D02*
X370187D01*
G01X366987Y401941D02*
Y408141D01*
G01X366076Y408132D02*
Y404932D01*
G01X371452Y415040D02*
Y429840D01*
G01X373583Y425800D02*
Y428900D01*
X374503D01*
X374810Y428745D01*
X375040Y428383D01*
X375117Y427970D01*
X375040Y427557D01*
X374848Y427247D01*
X374503Y427092D01*
X373583D01*
G01X376607Y425800D02*
Y428900D01*
X377373D01*
X377680Y428745D01*
X377910Y428538D01*
X378102Y428228D01*
X378255Y427867D01*
X378293Y427350D01*
X378255Y426833D01*
X378102Y426472D01*
X377910Y426162D01*
X377680Y425955D01*
X377373Y425800D01*
X376607D01*
G01X380473D02*
X380550Y426472D01*
X380665Y427040D01*
X380818Y427557D01*
X381010Y428125D01*
X381317Y428900D01*
X379783D01*
G01X382998Y426162D02*
X383267Y425903D01*
X383573Y425800D01*
X383880Y425903D01*
X384148Y426213D01*
X384340Y426678D01*
X384417Y427143D01*
Y427712D01*
X384340Y428177D01*
X384148Y428590D01*
X383918Y428797D01*
X383650Y428900D01*
X383343Y428797D01*
X383113Y428590D01*
X382960Y428280D01*
X382883Y427867D01*
X382960Y427505D01*
X383152Y427143D01*
X383382Y426937D01*
X383650Y426885D01*
X383957Y426988D01*
X384187Y427247D01*
X384417Y427712D01*
G01X373684Y413204D02*
Y424700D01*
G01X403243Y413204D02*
X373684D01*
G01Y424700D02*
X403243D01*
G01X368919Y438502D02*
Y450502D01*
G01X374919Y438502D02*
X368919D01*
G01X374919Y450502D02*
Y438502D01*
G01X365042Y443902D02*
Y431902D01*
G01X368919Y450502D02*
X374919D01*
G01X366420Y448957D02*
Y445757D01*
G01X368924Y456709D02*
Y459909D01*
G01X375124Y456709D02*
X368924D01*
G01X375124Y459909D02*
Y456709D01*
G01X368924Y452709D02*
Y455909D01*
G01X375124Y452709D02*
X368924D01*
G01X375124Y455909D02*
Y452709D01*
G01X368924Y455909D02*
X375124D01*
G01X366614Y460925D02*
Y451163D01*
G01X368176Y469326D02*
Y463326D01*
G01X368924Y460709D02*
Y463909D01*
G01X375124Y460709D02*
X368924D01*
G01X375124Y463909D02*
Y460709D01*
G01X368924Y463909D02*
X375124D01*
G01X368924Y459909D02*
X375124D01*
G01X372066Y464995D02*
Y468095D01*
X372986D01*
X373293Y467940D01*
X373523Y467578D01*
X373600Y467165D01*
X373523Y466752D01*
X373331Y466442D01*
X372986Y466287D01*
X372066D01*
G01X375090Y468095D02*
Y465873D01*
X375243Y465408D01*
X375550Y465098D01*
X375933Y464995D01*
X376316Y465098D01*
X376623Y465408D01*
X376776Y465873D01*
Y468095D01*
G01X379493Y464995D02*
Y468095D01*
X378075Y465873D01*
X379991D01*
G01X382133Y464995D02*
X382401Y465047D01*
X382708Y465202D01*
X382900Y465460D01*
X382976Y465822D01*
X382900Y466183D01*
X382670Y466493D01*
X382325Y466648D01*
X381941D01*
X381711Y466752D01*
X381520Y467010D01*
X381443Y467372D01*
X381558Y467733D01*
X381826Y467992D01*
X382133Y468095D01*
X382440Y467992D01*
X382708Y467733D01*
X382823Y467372D01*
X382746Y467010D01*
X382555Y466752D01*
X382325Y466648D01*
X381941D01*
X381596Y466493D01*
X381366Y466183D01*
X381290Y465822D01*
X381366Y465460D01*
X381558Y465202D01*
X381865Y465047D01*
X382133Y464995D01*
G01X382736Y483629D02*
Y471425D01*
X367432D01*
Y483629D01*
X382736D01*
G01X361933Y490517D02*
Y478517D01*
G01X373000Y490416D02*
Y487216D01*
G01X366800Y490416D02*
X373000D01*
G01X366800Y487216D02*
Y490416D01*
G01X373000Y487216D02*
X366800D01*
G01X365926Y480358D02*
X362726D01*
G01X365926Y486558D02*
Y480358D01*
G01X362726Y486558D02*
X365926D01*
G01X362726Y480358D02*
Y486558D01*
G01X363000Y497216D02*
X375000D01*
G01X363000Y491216D02*
Y497216D01*
G01X375000Y491216D02*
X363000D01*
G01X375000Y497216D02*
Y491216D01*
G01X374500Y751600D02*
X380700D01*
Y748400D01*
X374500D01*
Y751600D01*
G01X380686Y743700D02*
X374486D01*
Y746900D01*
X380686D01*
Y743700D01*
G01X378986Y762900D02*
X372786D01*
Y766100D01*
X378986D01*
Y762900D01*
G01X372500Y768500D02*
Y778700D01*
X377100D01*
Y768500D01*
X372500D01*
G01X372800Y788000D02*
X379000D01*
Y784800D01*
X372800D01*
Y788000D01*
G01X376314Y794869D02*
Y788669D01*
X373114D01*
Y794869D01*
X376314D01*
G01X371332Y938376D02*
Y941576D01*
G01X377532Y938376D02*
X371332D01*
G01Y941576D02*
X377532D01*
G01X371332Y942212D02*
Y945412D01*
G01X377532Y942212D02*
X371332D01*
G01X368568Y945080D02*
Y941880D01*
G01X362368Y945080D02*
X368568D01*
G01X362368Y941880D02*
Y945080D01*
G01X368568Y941880D02*
X362368D01*
G01X371332Y945412D02*
X377532D01*
G01X371332Y946212D02*
Y949412D01*
G01X377532Y946212D02*
X371332D01*
G01Y949412D02*
X377532D01*
G01X371332Y961412D02*
X377532D01*
G01X371332Y958212D02*
Y961412D01*
G01X377532Y958212D02*
X371332D01*
G01Y957412D02*
X377532D01*
G01X371332Y954212D02*
Y957412D01*
G01X377532Y954212D02*
X371332D01*
G01Y953412D02*
X377532D01*
G01X371332Y950212D02*
Y953412D01*
G01X377532Y950212D02*
X371332D01*
G01Y965412D02*
X377532D01*
G01X371332Y962212D02*
Y965412D01*
G01X377532Y962212D02*
X371332D01*
G01Y969412D02*
X377532D01*
G01X371332Y966212D02*
Y969412D01*
G01X377532Y966212D02*
X371332D01*
G01Y973412D02*
X377532D01*
G01X371332Y970212D02*
Y973412D01*
G01X377532Y970212D02*
X371332D01*
G01X364148Y1135604D02*
Y1141804D01*
G01X367348Y1135604D02*
X364148D01*
G01X367348Y1141804D02*
Y1135604D01*
G01X363348Y1141804D02*
Y1135604D01*
G01X374260Y1152019D02*
X376482D01*
X376947Y1152172D01*
X377257Y1152479D01*
X377360Y1152862D01*
X377257Y1153245D01*
X376947Y1153552D01*
X376482Y1153705D01*
X374260D01*
G01X376740Y1155119D02*
X377102Y1155349D01*
X377308Y1155655D01*
X377360Y1156000D01*
X377308Y1156307D01*
X377050Y1156614D01*
X376740Y1156805D01*
X376430Y1156844D01*
X376068Y1156767D01*
X375810Y1156499D01*
X375707Y1156230D01*
Y1155885D01*
G01Y1156230D02*
X375552Y1156460D01*
X375293Y1156652D01*
X374983Y1156729D01*
X374673Y1156652D01*
X374415Y1156460D01*
X374260Y1156115D01*
X374312Y1155770D01*
X374518Y1155425D01*
G01X377360Y1159062D02*
X374260D01*
X374880Y1158602D01*
G01X377360D02*
Y1159522D01*
G01X376740Y1161319D02*
X377102Y1161549D01*
X377308Y1161855D01*
X377360Y1162200D01*
X377308Y1162507D01*
X377050Y1162814D01*
X376740Y1163005D01*
X376430Y1163044D01*
X376068Y1162967D01*
X375810Y1162699D01*
X375707Y1162430D01*
Y1162085D01*
G01Y1162430D02*
X375552Y1162660D01*
X375293Y1162852D01*
X374983Y1162929D01*
X374673Y1162852D01*
X374415Y1162660D01*
X374260Y1162315D01*
X374312Y1161970D01*
X374518Y1161625D01*
G01X362950Y1152405D02*
Y1149643D01*
G01X367757Y1145412D02*
X364557D01*
G01X367757Y1151612D02*
Y1145412D01*
G01X364557Y1151612D02*
X367757D01*
G01X364557Y1145412D02*
Y1151612D01*
G01X364148Y1141804D02*
X367348D01*
G01X362950Y1161167D02*
Y1158507D01*
G01X367733Y1163692D02*
X364533D01*
G01X367733Y1169892D02*
Y1163692D01*
G01X364533Y1169892D02*
X367733D01*
G01X364533Y1163692D02*
Y1169892D01*
G01X362498Y1171970D02*
Y1168770D01*
G01X360682Y1179449D02*
X363882D01*
G01X360682Y1173249D02*
Y1179449D01*
G01X363882Y1173249D02*
X360682D01*
G01X363882Y1179449D02*
Y1173249D01*
G01X362129Y1186763D02*
X365329D01*
G01X362129Y1180563D02*
Y1186763D01*
G01X365329Y1180563D02*
X362129D01*
G01X365329Y1186763D02*
Y1180563D01*
G01X361361Y1186726D02*
Y1180526D01*
G01X368000Y1193894D02*
X364800D01*
G01X368000Y1200094D02*
Y1193894D01*
G01X364800Y1200094D02*
X368000D01*
G01X364800Y1193894D02*
Y1200094D01*
G01X368002Y1201918D02*
X364802D01*
G01X368002Y1208118D02*
Y1201918D01*
G01X364802D02*
Y1208118D01*
G01X364002Y1201918D02*
X360802D01*
G01X364002Y1208118D02*
Y1201918D01*
G01X360802D02*
Y1208118D01*
G01X364000Y1193894D02*
X360800D01*
G01X364000Y1200094D02*
Y1193894D01*
G01X360800Y1200094D02*
X364000D01*
G01X360800Y1193894D02*
Y1200094D01*
G01X364802Y1208118D02*
X368002D01*
G01X360802D02*
X364002D01*
G01X364088Y1221297D02*
X361826Y1219035D01*
G01X366916Y1224125D02*
X364654Y1221863D01*
G01X362532Y1228509D02*
X366916Y1224125D01*
G01X367559Y1436969D02*
Y1677520D01*
G01X377679Y1460136D02*
X370179D01*
Y1462376D01*
X370554Y1463123D01*
X371429Y1463683D01*
X372429Y1463870D01*
X373429Y1463683D01*
X374179Y1463216D01*
X374554Y1462376D01*
Y1460136D01*
G01X377679Y1467636D02*
X370179D01*
Y1469970D01*
X370554Y1470716D01*
X371054Y1471183D01*
X372054Y1471370D01*
X373054Y1471183D01*
X373679Y1470623D01*
X374054Y1469970D01*
Y1467636D01*
G01Y1469970D02*
X377679Y1471370D01*
G01Y1478870D02*
Y1475136D01*
X370179D01*
Y1478870D01*
G01X373804Y1477376D02*
Y1475136D01*
G01X376679Y1482543D02*
X377304Y1483290D01*
X377679Y1484130D01*
Y1484876D01*
X377304Y1485623D01*
X376679Y1486183D01*
X375804Y1486463D01*
X374929Y1486276D01*
X374179Y1485810D01*
X373679Y1484970D01*
X373429Y1483850D01*
X372929Y1483196D01*
X372054Y1482916D01*
X371179Y1483103D01*
X370554Y1483570D01*
X370179Y1484223D01*
Y1484876D01*
X370429Y1485530D01*
X371054Y1486090D01*
G01X376679Y1490043D02*
X377304Y1490790D01*
X377679Y1491630D01*
Y1492376D01*
X377304Y1493123D01*
X376679Y1493683D01*
X375804Y1493963D01*
X374929Y1493776D01*
X374179Y1493310D01*
X373679Y1492470D01*
X373429Y1491350D01*
X372929Y1490696D01*
X372054Y1490416D01*
X371179Y1490603D01*
X370554Y1491070D01*
X370179Y1491723D01*
Y1492376D01*
X370429Y1493030D01*
X371054Y1493590D01*
G01X375179Y1498290D02*
Y1500716D01*
G01X377679Y1505230D02*
X370179D01*
Y1508776D01*
G01X373804Y1507470D02*
Y1505230D01*
G01X370179Y1513383D02*
Y1515623D01*
G01Y1514503D02*
X377679D01*
G01Y1513383D02*
Y1515623D01*
G01X370179Y1522003D02*
X377679D01*
G01X370179Y1519856D02*
Y1524150D01*
G01X387712Y29093D02*
X384512D01*
G01X387712Y35293D02*
Y29093D01*
G01X384512Y35293D02*
X387712D01*
G01X384512Y29093D02*
Y35293D01*
G01X386456Y82540D02*
Y85740D01*
G01X392656Y82540D02*
X386456D01*
G01X392656Y85740D02*
Y82540D01*
G01X386456Y78540D02*
Y81740D01*
G01X392656Y78540D02*
X386456D01*
G01X392656Y81740D02*
Y78540D01*
G01X386456Y81740D02*
X392656D01*
G01X386456Y74540D02*
Y77740D01*
G01X392656Y74540D02*
X386456D01*
G01X392656Y77740D02*
Y74540D01*
G01X386456Y77740D02*
X392656D01*
G01X379263Y103226D02*
Y97026D01*
G01X378067Y93129D02*
Y86929D01*
G01X386456Y85740D02*
X392656D01*
G01X382067Y86929D02*
X378867D01*
G01X382067Y93129D02*
Y86929D01*
G01X378867Y93129D02*
X382067D01*
G01X378867Y86929D02*
Y93129D01*
G01X390076Y86929D02*
X386876D01*
G01X390076Y93129D02*
Y86929D01*
G01X386876Y93129D02*
X390076D01*
G01X386876Y86929D02*
Y93129D01*
G01X386067Y86929D02*
X382867D01*
G01X386067Y93129D02*
Y86929D01*
G01X382867Y93129D02*
X386067D01*
G01X382867Y86929D02*
Y93129D01*
G01X391650Y95950D02*
Y102150D01*
G01X394850Y95950D02*
X391650D01*
G01X386146Y96673D02*
Y102873D01*
G01X389346Y96673D02*
X386146D01*
G01X389346Y102873D02*
Y96673D01*
G01X382146D02*
Y102873D01*
G01X385346Y96673D02*
X382146D01*
G01X385346Y102873D02*
Y96673D01*
G01X391650Y102150D02*
X394850D01*
G01X386146Y102873D02*
X389346D01*
G01X382146D02*
X385346D01*
G01X391650Y109762D02*
X394850D01*
G01X391650Y103562D02*
Y109762D01*
G01X394850Y103562D02*
X391650D01*
G01X377431Y164436D02*
Y195440D01*
G01X393257Y175300D02*
Y173078D01*
X393410Y172613D01*
X393717Y172303D01*
X394100Y172200D01*
X394483Y172303D01*
X394790Y172613D01*
X394943Y173078D01*
Y175300D01*
G01X396357Y172665D02*
X396587Y172407D01*
X396855Y172252D01*
X397200Y172200D01*
X397545Y172303D01*
X397813Y172510D01*
X398005Y172872D01*
X398043Y173285D01*
X397967Y173698D01*
X397775Y173957D01*
X397507Y174163D01*
X397238Y174215D01*
X396970Y174163D01*
X396625Y173957D01*
X396740Y175300D01*
X397775D01*
G01X399572Y173492D02*
X399840Y173853D01*
X400070Y174060D01*
X400377Y174163D01*
X400645Y174060D01*
X400837Y173853D01*
X400990Y173543D01*
X401028Y173182D01*
X400990Y172872D01*
X400837Y172562D01*
X400607Y172303D01*
X400338Y172200D01*
X400032Y172303D01*
X399763Y172613D01*
X399610Y173078D01*
X399572Y173595D01*
X399648Y174267D01*
X399763Y174628D01*
X399955Y174990D01*
X400223Y175248D01*
X400492Y175300D01*
X400760Y175197D01*
X400952Y174938D01*
G01X391125Y176944D02*
Y178897D01*
G01X393078Y176944D02*
X391125D01*
G01X386397Y171473D02*
X383197D01*
G01X386397Y177673D02*
Y171473D01*
G01X383197Y177673D02*
X386397D01*
G01X383197Y171473D02*
Y177673D01*
G01X389420Y170297D02*
Y167097D01*
G01X383220Y170297D02*
X389420D01*
G01X383220Y167097D02*
Y170297D01*
G01X389420Y167097D02*
X383220D01*
G01X382397Y171473D02*
X379197D01*
G01X382397Y177673D02*
Y171473D01*
G01X379197Y177673D02*
X382397D01*
G01X379197Y171473D02*
Y177673D01*
G01X391125Y188756D02*
X393078D01*
G01X391125Y186803D02*
Y188756D01*
G01X386624Y182730D02*
X383424D01*
G01X386624Y188930D02*
Y182730D01*
G01X383424Y188930D02*
X386624D01*
G01X383424Y182730D02*
Y188930D01*
G01X389615Y193541D02*
Y190341D01*
G01X383415Y193541D02*
X389615D01*
G01X383415Y190341D02*
Y193541D01*
G01X389615Y190341D02*
X383415D01*
G01X380744Y225035D02*
Y213035D01*
G01X389765Y201618D02*
Y204718D01*
X390685D01*
X390992Y204563D01*
X391222Y204201D01*
X391299Y203788D01*
X391222Y203375D01*
X391030Y203065D01*
X390685Y202910D01*
X389765D01*
G01X392789Y204718D02*
Y202496D01*
X392942Y202031D01*
X393249Y201721D01*
X393632Y201618D01*
X394015Y201721D01*
X394322Y202031D01*
X394475Y202496D01*
Y204718D01*
G01X395889Y202238D02*
X396119Y201876D01*
X396425Y201670D01*
X396770Y201618D01*
X397077Y201670D01*
X397384Y201928D01*
X397575Y202238D01*
X397614Y202548D01*
X397537Y202910D01*
X397269Y203168D01*
X397000Y203271D01*
X396655D01*
G01X397000D02*
X397230Y203426D01*
X397422Y203685D01*
X397499Y203995D01*
X397422Y204305D01*
X397230Y204563D01*
X396885Y204718D01*
X396540Y204666D01*
X396195Y204460D01*
G01X399104Y202910D02*
X399372Y203271D01*
X399602Y203478D01*
X399909Y203581D01*
X400177Y203478D01*
X400369Y203271D01*
X400522Y202961D01*
X400560Y202600D01*
X400522Y202290D01*
X400369Y201980D01*
X400139Y201721D01*
X399870Y201618D01*
X399564Y201721D01*
X399295Y202031D01*
X399142Y202496D01*
X399104Y203013D01*
X399180Y203685D01*
X399295Y204046D01*
X399487Y204408D01*
X399755Y204666D01*
X400024Y204718D01*
X400292Y204615D01*
X400484Y204356D01*
G01X403900Y220252D02*
Y208048D01*
X388596D01*
Y220252D01*
X403900D01*
G01X381584Y226621D02*
Y232621D01*
G01X393584Y226621D02*
X381584D01*
G01X385563Y215082D02*
X382363D01*
G01X385563Y221282D02*
Y215082D01*
G01X382363Y221282D02*
X385563D01*
G01X382363Y215082D02*
Y221282D01*
G01X391584Y225921D02*
Y222721D01*
G01X385384Y225921D02*
X391584D01*
G01X385384Y222721D02*
Y225921D01*
G01X391584Y222721D02*
X385384D01*
G01X381584Y232621D02*
X393584D01*
G01X382252Y258010D02*
Y264210D01*
G01X385452Y258010D02*
X382252D01*
G01X385452Y264210D02*
Y258010D01*
G01X390252D02*
Y264210D01*
G01X393452Y258010D02*
X390252D01*
G01X389452D02*
X386252D01*
G01X389452Y264210D02*
Y258010D01*
G01X386252D02*
Y264210D01*
G01X380322Y283655D02*
Y271655D01*
G01X382252Y264210D02*
X385452D01*
G01X390252D02*
X393452D01*
G01X386252D02*
X389452D01*
G01X392973Y279427D02*
Y267653D01*
G01X383211D02*
Y279427D01*
G01X392973Y267653D02*
X383211D01*
G01X384505Y283383D02*
X381305D01*
G01X384505Y289583D02*
Y283383D01*
G01X381305Y289583D02*
X384505D01*
G01X381305Y283383D02*
Y289583D01*
G01X388505Y283383D02*
X385305D01*
G01X388505Y289583D02*
Y283383D01*
G01X385305Y289583D02*
X388505D01*
G01X385305Y283383D02*
Y289583D01*
G01X389305Y283383D02*
Y289583D01*
X392505D01*
Y283383D01*
X389305D01*
G01X383211Y279427D02*
X392973D01*
G01X392637Y371956D02*
Y378156D01*
G01X395837Y371956D02*
X392637D01*
G01X387637Y371954D02*
Y378154D01*
G01X390837Y371954D02*
X387637D01*
G01X390837Y378154D02*
Y371954D01*
G01X378837Y378355D02*
Y372155D01*
G01X379637Y371954D02*
Y378154D01*
G01X382837Y371954D02*
X379637D01*
G01X382837Y378154D02*
Y371954D01*
G01X386837Y378154D02*
Y371954D01*
X383637D01*
Y378154D01*
X386837D01*
G01X392637Y378156D02*
X395837D01*
G01X387637Y378154D02*
X390837D01*
G01X396153Y391302D02*
X392953D01*
G01D02*
Y397502D01*
G01X379637Y378154D02*
X382837D01*
G01X390484Y381986D02*
X378280D01*
Y397290D01*
X390484D01*
Y381986D01*
G01X383267Y405142D02*
Y411142D01*
G01X395267Y405142D02*
X383267D01*
G01X392953Y397502D02*
X396153D01*
G01X385314Y400323D02*
Y403523D01*
G01X391514Y400323D02*
X385314D01*
G01X391514Y403523D02*
Y400323D01*
G01X385314Y403523D02*
X391514D01*
G01X383267Y411142D02*
X395267D01*
G01X390221Y425620D02*
Y428046D01*
G01X376919Y438502D02*
Y450502D01*
G01X382919Y438502D02*
X376919D01*
G01X382919Y450502D02*
Y438502D01*
G01X396269Y429160D02*
X384773D01*
G01D02*
Y458719D01*
G01X376919Y450502D02*
X382919D01*
G01X390121Y462360D02*
Y460120D01*
G01X391746Y461333D02*
X388496D01*
G01X384773Y458719D02*
X396269D01*
G01X386568Y464809D02*
Y468009D01*
G01X392768Y464809D02*
X386568D01*
G01X392768Y468009D02*
Y464809D01*
G01X386568Y468009D02*
X392768D01*
G01Y471982D02*
Y468782D01*
G01X386568Y471982D02*
X392768D01*
G01X386568Y468782D02*
Y471982D01*
G01X392768Y468782D02*
X386568D01*
G01Y472782D02*
Y475982D01*
G01X392768Y472782D02*
X386568D01*
G01X392768Y475982D02*
Y472782D01*
G01X386568Y485782D02*
Y488982D01*
G01X392768Y485782D02*
X386568D01*
G01X392768Y488982D02*
Y485782D01*
G01X386568Y488982D02*
X392768D01*
G01X386568Y480782D02*
Y483982D01*
G01X392768Y480782D02*
X386568D01*
G01X392768Y483982D02*
Y480782D01*
G01X386568Y483982D02*
X392768D01*
G01X386568Y475982D02*
X392768D01*
G01X386568Y479982D02*
X392768D01*
Y476782D01*
X386568D01*
Y479982D01*
G01X391218Y739026D02*
Y742126D01*
X390758Y741506D01*
G01Y739026D02*
X391678D01*
G01X394241D02*
X394318Y739698D01*
X394433Y740266D01*
X394586Y740783D01*
X394778Y741351D01*
X395085Y742126D01*
X393551D01*
G01X386501Y742538D02*
X389601D01*
X388981Y742998D01*
G01X386501D02*
Y742078D01*
G01X387793Y740166D02*
X388154Y739898D01*
X388361Y739668D01*
X388464Y739361D01*
X388361Y739093D01*
X388154Y738901D01*
X387844Y738748D01*
X387483Y738710D01*
X387173Y738748D01*
X386863Y738901D01*
X386604Y739131D01*
X386501Y739400D01*
X386604Y739706D01*
X386914Y739975D01*
X387379Y740128D01*
X387896Y740166D01*
X388568Y740090D01*
X388929Y739975D01*
X389291Y739783D01*
X389549Y739515D01*
X389601Y739246D01*
X389498Y738978D01*
X389239Y738786D01*
G01X390583Y746900D02*
Y745083D01*
G01D02*
X392400D01*
G01X388300Y750005D02*
X386300D01*
G01X384200Y759847D02*
X388200D01*
G01X378200Y770500D02*
Y776700D01*
X381400D01*
Y770500D01*
X378200D01*
G01X392400Y780517D02*
X390583D01*
Y778700D01*
G01X388300Y769690D02*
X386300D01*
G01X376872Y788669D02*
Y794869D01*
X380072D01*
Y788669D01*
X376872D01*
G01X392180Y801775D02*
Y799553D01*
X392333Y799088D01*
X392640Y798778D01*
X393023Y798675D01*
X393406Y798778D01*
X393713Y799088D01*
X393866Y799553D01*
Y801775D01*
G01X396583Y798675D02*
Y801775D01*
X395165Y799553D01*
X397081D01*
G01X398380Y799295D02*
X398610Y798933D01*
X398916Y798727D01*
X399261Y798675D01*
X399568Y798727D01*
X399875Y798985D01*
X400066Y799295D01*
X400105Y799605D01*
X400028Y799967D01*
X399760Y800225D01*
X399491Y800328D01*
X399146D01*
G01X399491D02*
X399721Y800483D01*
X399913Y800742D01*
X399990Y801052D01*
X399913Y801362D01*
X399721Y801620D01*
X399376Y801775D01*
X399031Y801723D01*
X398686Y801517D01*
G01X401480Y799140D02*
X401710Y798882D01*
X401978Y798727D01*
X402323Y798675D01*
X402668Y798778D01*
X402936Y798985D01*
X403128Y799347D01*
X403166Y799760D01*
X403090Y800173D01*
X402898Y800432D01*
X402630Y800638D01*
X402361Y800690D01*
X402093Y800638D01*
X401748Y800432D01*
X401863Y801775D01*
X402898D01*
G01X385022Y785839D02*
X385290Y786200D01*
X385520Y786407D01*
X385827Y786510D01*
X386095Y786407D01*
X386287Y786200D01*
X386440Y785890D01*
X386478Y785529D01*
X386440Y785219D01*
X386287Y784909D01*
X386057Y784650D01*
X385788Y784547D01*
X385482Y784650D01*
X385213Y784960D01*
X385060Y785425D01*
X385022Y785942D01*
X385098Y786614D01*
X385213Y786975D01*
X385405Y787337D01*
X385673Y787595D01*
X385942Y787647D01*
X386210Y787544D01*
X386402Y787285D01*
G01X389310Y784547D02*
Y787647D01*
X387892Y785425D01*
X389808D01*
G01X388070Y862808D02*
Y866008D01*
G01X394270Y862808D02*
X388070D01*
G01X388095Y869886D02*
X394295D01*
G01X388095Y866686D02*
Y869886D01*
G01X394295Y866686D02*
X388095D01*
G01X388070Y866008D02*
X394270D01*
G01X393214Y931551D02*
X390014D01*
G01Y937751D02*
X393214D01*
G01X390014Y931551D02*
Y937751D01*
G01X377532Y941576D02*
Y938376D01*
G01Y945412D02*
Y942212D01*
G01X393715Y951721D02*
X391762D01*
G01X381903D02*
Y953674D01*
G01X383856Y951721D02*
X381903D01*
G01X377532Y949412D02*
Y946212D01*
G01Y961412D02*
Y958212D01*
G01Y957412D02*
Y954212D01*
G01Y953412D02*
Y950212D01*
G01X383057Y968500D02*
Y966278D01*
X383210Y965813D01*
X383517Y965503D01*
X383900Y965400D01*
X384283Y965503D01*
X384590Y965813D01*
X384743Y966278D01*
Y968500D01*
G01X386348Y965762D02*
X386617Y965503D01*
X386923Y965400D01*
X387230Y965503D01*
X387498Y965813D01*
X387690Y966278D01*
X387767Y966743D01*
Y967312D01*
X387690Y967777D01*
X387498Y968190D01*
X387268Y968397D01*
X387000Y968500D01*
X386693Y968397D01*
X386463Y968190D01*
X386310Y967880D01*
X386233Y967467D01*
X386310Y967105D01*
X386502Y966743D01*
X386732Y966537D01*
X387000Y966485D01*
X387307Y966588D01*
X387537Y966847D01*
X387767Y967312D01*
G01X389372Y966692D02*
X389640Y967053D01*
X389870Y967260D01*
X390177Y967363D01*
X390445Y967260D01*
X390637Y967053D01*
X390790Y966743D01*
X390828Y966382D01*
X390790Y966072D01*
X390637Y965762D01*
X390407Y965503D01*
X390138Y965400D01*
X389832Y965503D01*
X389563Y965813D01*
X389410Y966278D01*
X389372Y966795D01*
X389448Y967467D01*
X389563Y967828D01*
X389755Y968190D01*
X390023Y968448D01*
X390292Y968500D01*
X390560Y968397D01*
X390752Y968138D01*
G01X381903Y961580D02*
Y963533D01*
G01X391762D02*
X393715D01*
G01X381903D02*
X383856D01*
G01X377532Y965412D02*
Y962212D01*
G01Y969412D02*
Y966212D01*
G01Y973412D02*
Y970212D01*
G01X381409Y1119154D02*
Y1122254D01*
G01X383019D02*
Y1119154D01*
G01Y1120704D02*
X381409D01*
G01X385314Y1119154D02*
Y1122254D01*
X384854Y1121634D01*
G01Y1119154D02*
X385774D01*
G01X387571Y1119774D02*
X387801Y1119412D01*
X388107Y1119206D01*
X388452Y1119154D01*
X388759Y1119206D01*
X389066Y1119464D01*
X389257Y1119774D01*
X389296Y1120084D01*
X389219Y1120446D01*
X388951Y1120704D01*
X388682Y1120807D01*
X388337D01*
G01X388682D02*
X388912Y1120962D01*
X389104Y1121221D01*
X389181Y1121531D01*
X389104Y1121841D01*
X388912Y1122099D01*
X388567Y1122254D01*
X388222Y1122202D01*
X387877Y1121996D01*
G01X390786Y1120446D02*
X391054Y1120807D01*
X391284Y1121014D01*
X391591Y1121117D01*
X391859Y1121014D01*
X392051Y1120807D01*
X392204Y1120497D01*
X392242Y1120136D01*
X392204Y1119826D01*
X392051Y1119516D01*
X391821Y1119257D01*
X391552Y1119154D01*
X391246Y1119257D01*
X390977Y1119567D01*
X390824Y1120032D01*
X390786Y1120549D01*
X390862Y1121221D01*
X390977Y1121582D01*
X391169Y1121944D01*
X391437Y1122202D01*
X391706Y1122254D01*
X391974Y1122151D01*
X392166Y1121892D01*
G01X379370Y1689331D02*
Y1425158D01*
G01X392020Y1511773D02*
Y1517973D01*
X395220D01*
G01X392210Y1530120D02*
X391960Y1530280D01*
X391835Y1530467D01*
X391793Y1530680D01*
X391876Y1530947D01*
X392085Y1531134D01*
X392335Y1531187D01*
X392585Y1531160D01*
X392793Y1531054D01*
X393210Y1530520D01*
X393501Y1530280D01*
X393918Y1530120D01*
X394293Y1530067D01*
Y1531187D01*
G01Y1532827D02*
X394251Y1533014D01*
X394126Y1533227D01*
X393918Y1533360D01*
X393626Y1533414D01*
X393335Y1533360D01*
X393085Y1533200D01*
X392960Y1532960D01*
Y1532694D01*
X392876Y1532534D01*
X392668Y1532400D01*
X392376Y1532347D01*
X392085Y1532427D01*
X391876Y1532614D01*
X391793Y1532827D01*
X391876Y1533040D01*
X392085Y1533227D01*
X392376Y1533307D01*
X392668Y1533254D01*
X392876Y1533120D01*
X392960Y1532960D01*
Y1532694D01*
X393085Y1532454D01*
X393335Y1532294D01*
X393626Y1532240D01*
X393918Y1532294D01*
X394126Y1532427D01*
X394251Y1532640D01*
X394293Y1532827D01*
G01X386700Y1524485D02*
X388922D01*
X389387Y1524638D01*
X389697Y1524945D01*
X389800Y1525328D01*
X389697Y1525711D01*
X389387Y1526018D01*
X388922Y1526171D01*
X386700D01*
G01X389180Y1527585D02*
X389542Y1527815D01*
X389748Y1528121D01*
X389800Y1528466D01*
X389748Y1528773D01*
X389490Y1529080D01*
X389180Y1529271D01*
X388870Y1529310D01*
X388508Y1529233D01*
X388250Y1528965D01*
X388147Y1528696D01*
Y1528351D01*
G01Y1528696D02*
X387992Y1528926D01*
X387733Y1529118D01*
X387423Y1529195D01*
X387113Y1529118D01*
X386855Y1528926D01*
X386700Y1528581D01*
X386752Y1528236D01*
X386958Y1527891D01*
G01X389335Y1530685D02*
X389593Y1530915D01*
X389748Y1531183D01*
X389800Y1531528D01*
X389697Y1531873D01*
X389490Y1532141D01*
X389128Y1532333D01*
X388715Y1532371D01*
X388302Y1532295D01*
X388043Y1532103D01*
X387837Y1531835D01*
X387785Y1531566D01*
X387837Y1531298D01*
X388043Y1530953D01*
X386700Y1531068D01*
Y1532103D01*
G01X389180Y1533785D02*
X389542Y1534015D01*
X389748Y1534321D01*
X389800Y1534666D01*
X389748Y1534973D01*
X389490Y1535280D01*
X389180Y1535471D01*
X388870Y1535510D01*
X388508Y1535433D01*
X388250Y1535165D01*
X388147Y1534896D01*
Y1534551D01*
G01Y1534896D02*
X387992Y1535126D01*
X387733Y1535318D01*
X387423Y1535395D01*
X387113Y1535318D01*
X386855Y1535126D01*
X386700Y1534781D01*
X386752Y1534436D01*
X386958Y1534091D01*
G01X395145Y1514848D02*
X388945D01*
Y1518048D01*
X395145D01*
G01X395220Y1514923D02*
X392020D01*
Y1521123D01*
G01X389117Y1549300D02*
Y1546100D01*
G01X382917D02*
Y1549300D01*
G01X389117Y1546100D02*
X382917D01*
G01Y1538100D02*
Y1541300D01*
G01X389117Y1538100D02*
X382917D01*
G01X389117Y1541300D02*
Y1538100D01*
G01X382917Y1541300D02*
X389117D01*
G01X382917Y1542100D02*
Y1545300D01*
G01X389117Y1542100D02*
X382917D01*
G01X389117Y1545300D02*
Y1542100D01*
G01X382917Y1545300D02*
X389117D01*
G01X382917Y1549300D02*
X389117D01*
G01X382917Y1550100D02*
Y1553300D01*
G01X389117Y1550100D02*
X382917D01*
G01X389117Y1553300D02*
Y1550100D01*
G01X382917Y1553300D02*
X389117D01*
G01X382917Y1558100D02*
Y1561300D01*
G01X389117Y1558100D02*
X382917D01*
G01X389117Y1561300D02*
Y1558100D01*
G01X382917Y1561300D02*
X389117D01*
G01Y1557300D02*
Y1554100D01*
G01X382917Y1557300D02*
X389117D01*
G01X382917Y1554100D02*
Y1557300D01*
G01X389117Y1554100D02*
X382917D01*
G01X391966Y1623246D02*
Y1626346D01*
G01X393576D02*
Y1623246D01*
G01Y1624796D02*
X391966D01*
G01X395028Y1623711D02*
X395258Y1623453D01*
X395526Y1623298D01*
X395871Y1623246D01*
X396216Y1623349D01*
X396484Y1623556D01*
X396676Y1623918D01*
X396714Y1624331D01*
X396638Y1624744D01*
X396446Y1625003D01*
X396178Y1625209D01*
X395909Y1625261D01*
X395641Y1625209D01*
X395296Y1625003D01*
X395411Y1626346D01*
X396446D01*
G01X398971D02*
X398664Y1626243D01*
X398434Y1625984D01*
X398281Y1625674D01*
X398166Y1625261D01*
X398128Y1624796D01*
X398166Y1624331D01*
X398281Y1623918D01*
X398434Y1623608D01*
X398664Y1623349D01*
X398971Y1623246D01*
X399278Y1623349D01*
X399508Y1623608D01*
X399661Y1623918D01*
X399776Y1624331D01*
X399814Y1624796D01*
X399776Y1625261D01*
X399661Y1625674D01*
X399508Y1625984D01*
X399278Y1626243D01*
X398971Y1626346D01*
G01X400398Y-538835D02*
Y-530835D01*
X399198Y-532435D01*
G01Y-538835D02*
X401598D01*
G01X406498Y-535502D02*
X407198Y-534568D01*
X407798Y-534035D01*
X408598Y-533768D01*
X409298Y-534035D01*
X409798Y-534568D01*
X410198Y-535368D01*
X410298Y-536302D01*
X410198Y-537102D01*
X409798Y-537902D01*
X409198Y-538568D01*
X408498Y-538835D01*
X407698Y-538568D01*
X406998Y-537769D01*
X406598Y-536568D01*
X406498Y-535235D01*
X406698Y-533502D01*
X406998Y-532568D01*
X407498Y-531635D01*
X408198Y-530968D01*
X408898Y-530835D01*
X409598Y-531102D01*
X410098Y-531768D01*
G01X416398Y-539102D02*
X416198Y-538968D01*
Y-538702D01*
X416398Y-538568D01*
X416598Y-538702D01*
Y-538968D01*
X416398Y-539102D01*
G01X422498Y-535502D02*
X423198Y-534568D01*
X423798Y-534035D01*
X424598Y-533768D01*
X425298Y-534035D01*
X425798Y-534568D01*
X426198Y-535368D01*
X426298Y-536302D01*
X426198Y-537102D01*
X425798Y-537902D01*
X425198Y-538568D01*
X424498Y-538835D01*
X423698Y-538568D01*
X422998Y-537769D01*
X422598Y-536568D01*
X422498Y-535235D01*
X422698Y-533502D01*
X422998Y-532568D01*
X423498Y-531635D01*
X424198Y-530968D01*
X424898Y-530835D01*
X425598Y-531102D01*
X426098Y-531768D01*
G01X396707Y22300D02*
Y20078D01*
X396860Y19613D01*
X397167Y19303D01*
X397550Y19200D01*
X397933Y19303D01*
X398240Y19613D01*
X398393Y20078D01*
Y22300D01*
G01X400650Y19200D02*
Y22300D01*
X400190Y21680D01*
G01Y19200D02*
X401110D01*
G01X403022Y21783D02*
X403252Y22093D01*
X403520Y22248D01*
X403827Y22300D01*
X404210Y22197D01*
X404478Y21938D01*
X404555Y21628D01*
X404517Y21318D01*
X404363Y21060D01*
X403597Y20543D01*
X403252Y20182D01*
X403022Y19665D01*
X402945Y19200D01*
X404555D01*
G01X406198Y19562D02*
X406467Y19303D01*
X406773Y19200D01*
X407080Y19303D01*
X407348Y19613D01*
X407540Y20078D01*
X407617Y20543D01*
Y21112D01*
X407540Y21577D01*
X407348Y21990D01*
X407118Y22197D01*
X406850Y22300D01*
X406543Y22197D01*
X406313Y21990D01*
X406160Y21680D01*
X406083Y21267D01*
X406160Y20905D01*
X406352Y20543D01*
X406582Y20337D01*
X406850Y20285D01*
X407157Y20388D01*
X407387Y20647D01*
X407617Y21112D01*
G01X395622Y23786D02*
Y35990D01*
G01X407146Y23786D02*
X395622D01*
G01X407146Y35990D02*
Y23786D01*
G01X401384Y32888D02*
X404384Y35990D01*
G01X398282D02*
X401384Y32888D01*
G01X404384Y35990D02*
X407146D01*
G01X395622D02*
X398282D01*
G01X410280Y38418D02*
X407080D01*
G01Y44618D02*
X410280D01*
G01X407080Y38418D02*
Y44618D01*
G01X398280Y38418D02*
X395080D01*
G01X398280Y44618D02*
Y38418D01*
G01X395080Y44618D02*
X398280D01*
G01X395080Y38418D02*
Y44618D01*
G01X403086Y44573D02*
X406286D01*
G01X403086Y38373D02*
Y44573D01*
G01X406286Y38373D02*
X403086D01*
G01X406286Y44573D02*
Y38373D01*
G01X399086Y44573D02*
X402286D01*
G01X399086Y38373D02*
Y44573D01*
G01X402286Y38373D02*
X399086D01*
G01X402286Y44573D02*
Y38373D01*
G01X394850Y102150D02*
Y95950D01*
G01X408992Y111267D02*
Y95913D01*
G01X396314D02*
Y111267D01*
G01X408795Y95913D02*
X396314D01*
G01X408865Y116088D02*
Y112888D01*
G01X402665Y116088D02*
X408865D01*
G01X402665Y112888D02*
Y116088D01*
G01X408865Y112888D02*
X402665D01*
G01X394850Y109762D02*
Y103562D01*
G01X396314Y111267D02*
X408992D01*
G01X402937Y178897D02*
Y176944D01*
G01D02*
X400984D01*
G01X407308Y179065D02*
Y182265D01*
G01X413508Y179065D02*
X407308D01*
G01Y171065D02*
Y174265D01*
G01X413508Y171065D02*
X407308D01*
G01Y174265D02*
X413508D01*
G01X407308Y175065D02*
Y178265D01*
G01X413508Y175065D02*
X407308D01*
G01Y178265D02*
X413508D01*
G01X407308Y167065D02*
Y170265D01*
G01X413508Y167065D02*
X407308D01*
G01Y170265D02*
X413508D01*
G01X402937Y188756D02*
Y186803D01*
G01X400984Y188756D02*
X402937D01*
G01X407308Y182265D02*
X413508D01*
G01X407308Y183065D02*
Y186265D01*
G01X413508Y183065D02*
X407308D01*
G01Y186265D02*
X413508D01*
G01X407308Y187065D02*
Y190265D01*
G01X413508Y187065D02*
X407308D01*
G01Y190265D02*
X413508D01*
G01X399984Y195020D02*
Y198220D01*
G01X406184Y195020D02*
X399984D01*
G01X406184Y198220D02*
Y195020D01*
G01X407308Y194265D02*
X413508D01*
G01X407308Y191065D02*
Y194265D01*
G01X413508Y191065D02*
X407308D01*
G01Y195065D02*
Y198265D01*
G01X413508Y195065D02*
X407308D01*
G01X399984Y198220D02*
X406184D01*
G01X407308Y198265D02*
X413508D01*
G01X407403Y207264D02*
Y210464D01*
G01X413603Y207264D02*
X407403D01*
G01Y210464D02*
X413603D01*
G01X407403Y206464D02*
X413603D01*
G01X407403Y203264D02*
Y206464D01*
G01X413603Y203264D02*
X407403D01*
G01Y214464D02*
X413603D01*
Y211264D01*
X407403D01*
Y214464D01*
G01Y202464D02*
X413603D01*
Y199264D01*
X407403D01*
Y202464D01*
G01X393584Y232621D02*
Y226621D01*
G01X407403Y215264D02*
Y218464D01*
G01X413603Y215264D02*
X407403D01*
G01Y218464D02*
X413603D01*
G01X407403Y220264D02*
Y223464D01*
G01X413603Y220264D02*
X407403D01*
G01Y223464D02*
X413603D01*
G01X407400Y227319D02*
X413600D01*
Y224119D01*
X407400D01*
Y227319D01*
G01X405119Y234813D02*
Y250325D01*
G01X393452Y264210D02*
Y258010D01*
G01X400163Y264635D02*
X415675D01*
G01X400163Y295727D02*
Y264635D01*
G01X398531Y273701D02*
X395331D01*
G01X398531Y279901D02*
Y273701D01*
G01X395331D02*
Y279901D01*
G01D02*
X398531D01*
G01X397200Y282783D02*
X394100D01*
Y283703D01*
X394255Y284010D01*
X394617Y284240D01*
X395030Y284317D01*
X395443Y284240D01*
X395753Y284048D01*
X395908Y283703D01*
Y282783D01*
G01X394100Y285807D02*
X396322D01*
X396787Y285960D01*
X397097Y286267D01*
X397200Y286650D01*
X397097Y287033D01*
X396787Y287340D01*
X396322Y287493D01*
X394100D01*
G01X397200Y289673D02*
X396528Y289750D01*
X395960Y289865D01*
X395443Y290018D01*
X394875Y290210D01*
X394100Y290517D01*
Y288983D01*
G01X397200Y292773D02*
X396528Y292850D01*
X395960Y292965D01*
X395443Y293118D01*
X394875Y293310D01*
X394100Y293617D01*
Y292083D01*
G01X415675Y295727D02*
X400163D01*
G01X408728Y346739D02*
Y342139D01*
G01X398528D02*
Y346739D01*
G01X408728Y342139D02*
X398528D01*
G01X408656Y333189D02*
Y329989D01*
G01X402456Y333189D02*
X408656D01*
G01X402456Y329989D02*
Y333189D01*
G01X408656Y329989D02*
X402456D01*
G01X408656Y337189D02*
Y333989D01*
G01X402456Y337189D02*
X408656D01*
G01X402456Y333989D02*
Y337189D01*
G01X408656Y333989D02*
X402456D01*
G01X398528Y346739D02*
X408728D01*
G01X398528Y347639D02*
Y352239D01*
G01X408728Y347639D02*
X398528D01*
G01X408728Y352239D02*
Y347639D01*
G01X398528Y352239D02*
X408728D01*
G01X405045Y373767D02*
X420557D01*
G01X405045Y404859D02*
Y373767D01*
G01X395837Y378156D02*
Y371956D01*
G01X399837D02*
X396637D01*
G01X399837Y378156D02*
Y371956D01*
G01X396637D02*
Y378156D01*
G01X402853Y401302D02*
Y389302D01*
G01X396853D02*
Y401302D01*
G01X402853Y389302D02*
X396853D01*
G01X396153Y397502D02*
Y391302D01*
G01X396637Y378156D02*
X399837D01*
G01X396853Y401302D02*
X402853D01*
G01X395267Y411142D02*
Y405142D01*
G01X420557Y404859D02*
X405045D01*
G01X406979Y422140D02*
Y406628D01*
G01D02*
X438071D01*
G01X406143Y423435D02*
X403903D01*
G01X405116Y421810D02*
Y425060D01*
G01X403243Y424700D02*
Y413204D01*
G01X438071Y422140D02*
X406979D01*
G01X400600Y429783D02*
X397500D01*
Y430703D01*
X397655Y431010D01*
X398017Y431240D01*
X398430Y431317D01*
X398843Y431240D01*
X399153Y431048D01*
X399308Y430703D01*
Y429783D01*
G01X400600Y432807D02*
X397500D01*
Y433573D01*
X397655Y433880D01*
X397862Y434110D01*
X398172Y434302D01*
X398533Y434455D01*
X399050Y434493D01*
X399567Y434455D01*
X399928Y434302D01*
X400238Y434110D01*
X400445Y433880D01*
X400600Y433573D01*
Y432807D01*
G01Y436750D02*
X397500D01*
X398120Y436290D01*
G01X400600D02*
Y437210D01*
G01X397500Y439850D02*
X397603Y439543D01*
X397862Y439313D01*
X398172Y439160D01*
X398585Y439045D01*
X399050Y439007D01*
X399515Y439045D01*
X399928Y439160D01*
X400238Y439313D01*
X400497Y439543D01*
X400600Y439850D01*
X400497Y440157D01*
X400238Y440387D01*
X399928Y440540D01*
X399515Y440655D01*
X399050Y440693D01*
X398585Y440655D01*
X398172Y440540D01*
X397862Y440387D01*
X397603Y440157D01*
X397500Y439850D01*
G01X396269Y458719D02*
Y429160D01*
G01X410600Y434983D02*
X407500D01*
Y435903D01*
X407655Y436210D01*
X408017Y436440D01*
X408430Y436517D01*
X408843Y436440D01*
X409153Y436248D01*
X409308Y435903D01*
Y434983D01*
G01X407500Y438007D02*
X409722D01*
X410187Y438160D01*
X410497Y438467D01*
X410600Y438850D01*
X410497Y439233D01*
X410187Y439540D01*
X409722Y439693D01*
X407500D01*
G01X410600Y441873D02*
X409928Y441950D01*
X409360Y442065D01*
X408843Y442218D01*
X408275Y442410D01*
X407500Y442717D01*
Y441183D01*
G01X408017Y444322D02*
X407707Y444552D01*
X407552Y444820D01*
X407500Y445127D01*
X407603Y445510D01*
X407862Y445778D01*
X408172Y445855D01*
X408482Y445817D01*
X408740Y445663D01*
X409257Y444897D01*
X409618Y444552D01*
X410135Y444322D01*
X410600Y444245D01*
Y445855D01*
G01X408473Y447001D02*
X403873D01*
G01X408473Y457201D02*
Y447001D01*
G01X403873Y457201D02*
X408473D01*
G01X403873Y447001D02*
Y457201D01*
G01X402765Y443937D02*
X399565D01*
G01X402765Y450137D02*
Y443937D01*
G01X399565Y450137D02*
X402765D01*
G01X399565Y443937D02*
Y450137D01*
G01X406883Y466836D02*
Y476284D01*
G01X417719Y466836D02*
X406883D01*
G01X404401Y469160D02*
Y465960D01*
G01X398201Y469160D02*
X404401D01*
G01X398201Y465960D02*
Y469160D01*
G01X404401Y465960D02*
X398201D01*
G01Y469960D02*
Y473160D01*
G01X404401Y469960D02*
X398201D01*
G01X404401Y473160D02*
Y469960D01*
G01X398201Y473160D02*
X404401D01*
G01X398201Y473960D02*
Y477160D01*
G01X404401Y473960D02*
X398201D01*
G01X404401Y477160D02*
Y473960D01*
G01X410161Y477776D02*
X409854Y477828D01*
X409586Y478034D01*
X409356Y478344D01*
X409203Y478706D01*
X409126Y479119D01*
Y479533D01*
X409203Y479946D01*
X409356Y480308D01*
X409586Y480618D01*
X409854Y480824D01*
X410161Y480876D01*
X410468Y480824D01*
X410736Y480618D01*
X410966Y480308D01*
X411119Y479946D01*
X411196Y479533D01*
Y479119D01*
X411119Y478706D01*
X410966Y478344D01*
X410736Y478034D01*
X410468Y477828D01*
X410161Y477776D01*
G01X410468Y478603D02*
X410928Y477776D01*
G01X412533Y480359D02*
X412763Y480669D01*
X413031Y480824D01*
X413338Y480876D01*
X413721Y480773D01*
X413989Y480514D01*
X414066Y480204D01*
X414028Y479894D01*
X413874Y479636D01*
X413108Y479119D01*
X412763Y478758D01*
X412533Y478241D01*
X412456Y477776D01*
X414066D01*
G01X416361D02*
Y480876D01*
X415901Y480256D01*
G01Y477776D02*
X416821D01*
G01X418618Y478396D02*
X418848Y478034D01*
X419154Y477828D01*
X419499Y477776D01*
X419806Y477828D01*
X420113Y478086D01*
X420304Y478396D01*
X420343Y478706D01*
X420266Y479068D01*
X419998Y479326D01*
X419729Y479429D01*
X419384D01*
G01X419729D02*
X419959Y479584D01*
X420151Y479843D01*
X420228Y480153D01*
X420151Y480463D01*
X419959Y480721D01*
X419614Y480876D01*
X419269Y480824D01*
X418924Y480618D01*
G01X406883Y476284D02*
X410301D01*
G01X404401Y481160D02*
Y477960D01*
G01X398201Y481160D02*
X404401D01*
G01X398201Y477960D02*
Y481160D01*
G01X404401Y477960D02*
X398201D01*
G01Y477160D02*
X404401D01*
G01X409600Y559383D02*
X406500D01*
Y560303D01*
X406655Y560610D01*
X407017Y560840D01*
X407430Y560917D01*
X407843Y560840D01*
X408153Y560648D01*
X408308Y560303D01*
Y559383D01*
G01X406500Y562483D02*
X409600D01*
Y564017D01*
G01Y566810D02*
X406500D01*
X408722Y565392D01*
Y567308D01*
G01X402710Y659652D02*
X424545D01*
G01X402710Y669338D02*
Y659652D01*
G01Y676738D02*
Y686424D01*
G01D02*
X424545D01*
G01X399442Y743000D02*
Y739000D01*
G01X401410Y786700D02*
Y782700D01*
G01X397100Y796100D02*
X407300D01*
Y791500D01*
X397100D01*
Y796100D01*
G01X399100Y790600D02*
X405300D01*
Y787400D01*
X399100D01*
Y790600D01*
G01X408200Y831183D02*
X405100D01*
Y832103D01*
X405255Y832410D01*
X405617Y832640D01*
X406030Y832717D01*
X406443Y832640D01*
X406753Y832448D01*
X406908Y832103D01*
Y831183D01*
G01X405100Y834283D02*
X408200D01*
Y835817D01*
G01X405617Y837422D02*
X405307Y837652D01*
X405152Y837920D01*
X405100Y838227D01*
X405203Y838610D01*
X405462Y838878D01*
X405772Y838955D01*
X406082Y838917D01*
X406340Y838763D01*
X406857Y837997D01*
X407218Y837652D01*
X407735Y837422D01*
X408200Y837345D01*
Y838955D01*
G01X407735Y840407D02*
X407993Y840637D01*
X408148Y840905D01*
X408200Y841250D01*
X408097Y841595D01*
X407890Y841863D01*
X407528Y842055D01*
X407115Y842093D01*
X406702Y842017D01*
X406443Y841825D01*
X406237Y841557D01*
X406185Y841288D01*
X406237Y841020D01*
X406443Y840675D01*
X405100Y840790D01*
Y841825D01*
G01X410468Y843677D02*
X398468D01*
G01D02*
Y849677D01*
G01D02*
X410468D01*
G01X394270Y866008D02*
Y862808D01*
G01X397309Y858935D02*
Y862135D01*
G01X403509Y858935D02*
X397309D01*
G01X403509Y862135D02*
Y858935D01*
G01X397309Y862135D02*
X403509D01*
G01X397309Y862809D02*
Y866009D01*
G01X403509Y862809D02*
X397309D01*
G01X403509Y866009D02*
Y862809D01*
G01X394295Y869886D02*
Y866686D01*
G01X396990Y871170D02*
X393790D01*
G01X396990Y877370D02*
Y871170D01*
G01X393790Y877370D02*
X396990D01*
G01X393790Y871170D02*
Y877370D01*
G01X400652Y879673D02*
X397452D01*
G01X400652Y885873D02*
Y879673D01*
G01X397452D02*
Y885873D01*
G01X397309Y866009D02*
X403509D01*
G01X401878Y877368D02*
X405078D01*
G01X401878Y871168D02*
Y877368D01*
G01X405078Y871168D02*
X401878D01*
G01X405078Y877368D02*
Y871168D01*
G01X397769Y877368D02*
X400969D01*
G01X397769Y871168D02*
Y877368D01*
G01X400969Y871168D02*
X397769D01*
G01X400969Y877368D02*
Y871168D01*
G01X404566Y879774D02*
X401366D01*
G01X404566Y885974D02*
Y879774D01*
G01X401366D02*
Y885974D01*
G01X397251Y866686D02*
Y869886D01*
G01X403451Y866686D02*
X397251D01*
G01X403451Y869886D02*
Y866686D01*
G01X397251Y869886D02*
X403451D01*
G01X406409Y869151D02*
X406200Y868965D01*
X406117Y868751D01*
X406200Y868538D01*
X406450Y868351D01*
X406825Y868218D01*
X407200Y868165D01*
X407659D01*
X408034Y868218D01*
X408367Y868351D01*
X408534Y868511D01*
X408617Y868698D01*
X408534Y868911D01*
X408367Y869071D01*
X408117Y869178D01*
X407784Y869231D01*
X407492Y869178D01*
X407200Y869045D01*
X407034Y868885D01*
X406992Y868698D01*
X407075Y868485D01*
X407284Y868325D01*
X407659Y868165D01*
G01X408650Y876798D02*
X407150D01*
G01X407488Y891386D02*
Y888186D01*
G01X401288Y891386D02*
X407488D01*
G01X401288Y888186D02*
Y891386D01*
G01X407488Y888186D02*
X401288D01*
G01X397452Y885873D02*
X400652D01*
G01X401366Y885974D02*
X404566D01*
G01X397800Y896583D02*
X394700D01*
Y897503D01*
X394855Y897810D01*
X395217Y898040D01*
X395630Y898117D01*
X396043Y898040D01*
X396353Y897848D01*
X396508Y897503D01*
Y896583D01*
G01X394700Y899683D02*
X397800D01*
Y901217D01*
G01X395217Y902822D02*
X394907Y903052D01*
X394752Y903320D01*
X394700Y903627D01*
X394803Y904010D01*
X395062Y904278D01*
X395372Y904355D01*
X395682Y904317D01*
X395940Y904163D01*
X396457Y903397D01*
X396818Y903052D01*
X397335Y902822D01*
X397800Y902745D01*
Y904355D01*
G01X396508Y905922D02*
X396147Y906190D01*
X395940Y906420D01*
X395837Y906727D01*
X395940Y906995D01*
X396147Y907187D01*
X396457Y907340D01*
X396818Y907378D01*
X397128Y907340D01*
X397438Y907187D01*
X397697Y906957D01*
X397800Y906688D01*
X397697Y906382D01*
X397387Y906113D01*
X396922Y905960D01*
X396405Y905922D01*
X395733Y905998D01*
X395372Y906113D01*
X395010Y906305D01*
X394752Y906573D01*
X394700Y906842D01*
X394803Y907110D01*
X395062Y907302D01*
G01X399563Y895803D02*
Y924573D01*
G01X405652Y895833D02*
X399563D01*
G01X402121Y928278D02*
Y940278D01*
G01X408121Y928278D02*
X402121D01*
G01X408121Y940278D02*
Y928278D01*
G01X394121D02*
Y940278D01*
G01X400121Y928278D02*
X394121D01*
G01X400121Y940278D02*
Y928278D01*
G01X399563Y924573D02*
X405652D01*
G01X402121Y940278D02*
X408121D01*
G01X394121D02*
X400121D01*
G01X407409Y945037D02*
X422209D01*
G01X407409Y976041D02*
Y945037D01*
G01X393214Y937751D02*
Y931551D01*
G01X393715Y953674D02*
Y951721D01*
G01X398216Y957747D02*
X401416D01*
G01X398216Y951547D02*
Y957747D01*
G01X401416Y951547D02*
X398216D01*
G01X401416Y957747D02*
Y951547D01*
G01X395225Y946936D02*
Y950136D01*
G01X401425Y946936D02*
X395225D01*
G01X401425Y950136D02*
Y946936D01*
G01X395225Y950136D02*
X401425D01*
G01X422209Y976041D02*
X407409D01*
G01X393715Y963533D02*
Y961580D01*
G01X398443Y969004D02*
X401643D01*
G01X398443Y962804D02*
Y969004D01*
G01X401643Y962804D02*
X398443D01*
G01X401643Y969004D02*
Y962804D01*
G01X402443Y969004D02*
X405643D01*
G01X402443Y962804D02*
Y969004D01*
G01X405643Y962804D02*
X402443D01*
G01X405643Y969004D02*
Y962804D01*
G01X395420Y970180D02*
Y973380D01*
G01X401620Y970180D02*
X395420D01*
G01X401620Y973380D02*
Y970180D01*
G01X395420Y973380D02*
X401620D01*
G01X405025Y1051024D02*
Y1054124D01*
X405945D01*
X406252Y1053969D01*
X406482Y1053607D01*
X406559Y1053194D01*
X406482Y1052781D01*
X406290Y1052471D01*
X405945Y1052316D01*
X405025D01*
G01X408125Y1054124D02*
Y1051024D01*
X409659D01*
G01X411149Y1051489D02*
X411379Y1051231D01*
X411647Y1051076D01*
X411992Y1051024D01*
X412337Y1051127D01*
X412605Y1051334D01*
X412797Y1051696D01*
X412835Y1052109D01*
X412759Y1052522D01*
X412567Y1052781D01*
X412299Y1052987D01*
X412030Y1053039D01*
X411762Y1052987D01*
X411417Y1052781D01*
X411532Y1054124D01*
X412567D01*
G01X405518Y1062632D02*
X402110D01*
G01D02*
Y1080348D01*
G01X407690Y1090068D02*
X395690D01*
G01X407690Y1096068D02*
Y1090068D01*
G01X395690D02*
Y1096068D01*
G01X395684Y1082881D02*
Y1088881D01*
X407684D01*
Y1082881D01*
X395684D01*
G01X402110Y1080348D02*
X405518D01*
G01X395690Y1096068D02*
X407690D01*
G01X409068Y1107230D02*
X412268D01*
G01X409068Y1101030D02*
Y1107230D01*
G01X412268Y1101030D02*
X409068D01*
G01X407590Y1097226D02*
Y1100426D01*
G01X413790Y1097226D02*
X407590D01*
G01Y1100426D02*
X413790D01*
G01X404759Y1118297D02*
X401559D01*
G01X404759Y1124497D02*
Y1118297D01*
G01X401559D02*
Y1124497D01*
G01X404759Y1118297D02*
X401559D01*
G01X404759Y1124497D02*
Y1118297D01*
G01X401559D02*
Y1124497D01*
G01X407368Y1109839D02*
Y1112030D01*
G01X408101Y1109839D02*
X407368D01*
G01X401559Y1124497D02*
X404759D01*
G01X401559D02*
X404759D01*
G01X407368Y1133461D02*
X408161D01*
G01X407368Y1130861D02*
Y1133461D01*
G01X406463Y1136752D02*
Y1174548D01*
G01X412461Y1136752D02*
X406463D01*
G01X401663Y1153659D02*
Y1159859D01*
G01X404863Y1153659D02*
X401663D01*
G01X404863Y1159859D02*
Y1153659D01*
G01X401663Y1159859D02*
X404863D01*
G01X401887Y1177271D02*
Y1179511D01*
G01X400262Y1178298D02*
X403512D01*
G01X405002Y1177793D02*
X421942Y1177790D01*
G01X405002Y1177193D02*
X421977Y1177189D01*
G01X405002Y1176593D02*
X421985Y1176599D01*
G01X405002Y1176593D02*
Y1177793D01*
G01X421934D02*
X405004D01*
G01D02*
Y1213533D01*
G01X406463Y1174548D02*
X412461D01*
G01X397004Y1189471D02*
Y1201471D01*
G01X403004Y1189471D02*
X397004D01*
G01X403004Y1201471D02*
Y1189471D01*
G01X397004Y1201471D02*
X403004D01*
G01X403011Y1219792D02*
Y1209592D01*
X398411D01*
Y1219792D01*
X403011D01*
G01X412623Y1215696D02*
Y1218122D01*
G01X405004Y1213533D02*
X421934D01*
G01X394869Y1266904D02*
Y1249202D01*
G01D02*
X408502D01*
G01X408285Y1266904D02*
X394869D01*
G01X403015Y1444542D02*
X409215D01*
Y1441342D01*
X403015D01*
Y1444542D01*
G01X409065Y1448407D02*
Y1445207D01*
G01X402865Y1448407D02*
X409065D01*
G01X402865Y1445207D02*
Y1448407D01*
G01X409065Y1445207D02*
X402865D01*
G01X402503Y1518081D02*
Y1511881D01*
G01X399303D02*
Y1515048D01*
G01X395220Y1514839D02*
Y1511773D01*
G01X414104Y1521696D02*
X409101D01*
Y1524896D01*
X414020D01*
G01X399378Y1518156D02*
X405578D01*
Y1514956D01*
X399378D01*
G01X395220Y1521123D02*
Y1517995D01*
G01X402503Y1521231D02*
Y1515031D01*
X399303D01*
G01Y1518162D02*
Y1521231D01*
G01Y1518081D02*
X402503D01*
G01X395496Y1543915D02*
X393996D01*
G01X408996Y1532415D02*
Y1530915D01*
G01X399996Y1534072D02*
X397153D01*
G01D02*
Y1536915D01*
G01X394486Y1558223D02*
X394646Y1558473D01*
X394833Y1558598D01*
X395046Y1558640D01*
X395313Y1558557D01*
X395500Y1558348D01*
X395553Y1558098D01*
X395526Y1557848D01*
X395420Y1557640D01*
X394886Y1557223D01*
X394646Y1556932D01*
X394486Y1556515D01*
X394433Y1556140D01*
X395553D01*
G01X397193D02*
Y1558640D01*
X396873Y1558140D01*
G01Y1556140D02*
X397513D01*
G01X393546Y1551108D02*
X393296Y1551268D01*
X393171Y1551455D01*
X393129Y1551668D01*
X393212Y1551935D01*
X393421Y1552122D01*
X393671Y1552175D01*
X393921Y1552148D01*
X394129Y1552042D01*
X394546Y1551508D01*
X394837Y1551268D01*
X395254Y1551108D01*
X395629Y1551055D01*
Y1552175D01*
G01X393546Y1553308D02*
X393296Y1553468D01*
X393171Y1553655D01*
X393129Y1553868D01*
X393212Y1554135D01*
X393421Y1554322D01*
X393671Y1554375D01*
X393921Y1554348D01*
X394129Y1554242D01*
X394546Y1553708D01*
X394837Y1553468D01*
X395254Y1553308D01*
X395629Y1553255D01*
Y1554375D01*
G01X402996Y1555415D02*
Y1558415D01*
G01X397153Y1553758D02*
X399996D01*
G01X397153Y1550915D02*
Y1553758D01*
G01X411061Y1561909D02*
X407861D01*
G01D02*
Y1568109D01*
G01X407061Y1561909D02*
X403861D01*
G01X407061Y1568109D02*
Y1561909D01*
G01X403861D02*
Y1568109D01*
G01X395861Y1561909D02*
Y1568109D01*
G01X399061Y1561909D02*
X395861D01*
G01X399061Y1568109D02*
Y1561909D01*
G01X399861D02*
Y1568109D01*
G01X403061Y1561909D02*
X399861D01*
G01X403061Y1568109D02*
Y1561909D01*
G01X407861Y1568109D02*
X411061D01*
G01X403861D02*
X407061D01*
G01X395861D02*
X399061D01*
G01X399861D02*
X403061D01*
G01X421575Y37583D02*
Y34383D01*
G01X415375D02*
Y37583D01*
G01X421575Y34383D02*
X415375D01*
G01X415303Y24934D02*
Y28134D01*
G01X421503Y24934D02*
X415303D01*
G01X421503Y28134D02*
Y24934D01*
G01X415303Y28134D02*
X421503D01*
G01X415398Y21027D02*
Y24227D01*
G01X421598Y21027D02*
X415398D01*
G01X421598Y24227D02*
Y21027D01*
G01X415398Y24227D02*
X421598D01*
G01X415375Y28883D02*
Y32083D01*
G01X421575Y28883D02*
X415375D01*
G01X421575Y32083D02*
Y28883D01*
G01X415375Y32083D02*
X421575D01*
G01X415375Y37583D02*
X421575D01*
G01X410280Y44618D02*
Y38418D01*
G01X410100Y98307D02*
X412322D01*
X412787Y98460D01*
X413097Y98767D01*
X413200Y99150D01*
X413097Y99533D01*
X412787Y99840D01*
X412322Y99993D01*
X410100D01*
G01X413200Y102710D02*
X410100D01*
X412322Y101292D01*
Y103208D01*
G01X410100Y105350D02*
X410203Y105043D01*
X410462Y104813D01*
X410772Y104660D01*
X411185Y104545D01*
X411650Y104507D01*
X412115Y104545D01*
X412528Y104660D01*
X412838Y104813D01*
X413097Y105043D01*
X413200Y105350D01*
X413097Y105657D01*
X412838Y105887D01*
X412528Y106040D01*
X412115Y106155D01*
X411650Y106193D01*
X411185Y106155D01*
X410772Y106040D01*
X410462Y105887D01*
X410203Y105657D01*
X410100Y105350D01*
G01X413200Y108450D02*
X410100D01*
X410720Y107990D01*
G01X413200D02*
Y108910D01*
G01X414020Y89678D02*
Y92778D01*
G01X415630D02*
Y89678D01*
G01Y91228D02*
X414020D01*
G01X417082Y90143D02*
X417312Y89885D01*
X417580Y89730D01*
X417925Y89678D01*
X418270Y89781D01*
X418538Y89988D01*
X418730Y90350D01*
X418768Y90763D01*
X418692Y91176D01*
X418500Y91435D01*
X418232Y91641D01*
X417963Y91693D01*
X417695Y91641D01*
X417350Y91435D01*
X417465Y92778D01*
X418500D01*
G01X421025Y89678D02*
Y92778D01*
X420565Y92158D01*
G01Y89678D02*
X421485D01*
G01X413508Y182265D02*
Y179065D01*
G01Y174265D02*
Y171065D01*
G01Y178265D02*
Y175065D01*
G01Y170265D02*
Y167065D01*
G01Y186265D02*
Y183065D01*
G01Y190265D02*
Y187065D01*
G01Y194265D02*
Y191065D01*
G01Y198265D02*
Y195065D01*
G01X413603Y210464D02*
Y207264D01*
G01Y206464D02*
Y203264D01*
G01Y218464D02*
Y215264D01*
G01Y223464D02*
Y220264D01*
G01X419800Y264783D02*
X416700D01*
Y265703D01*
X416855Y266010D01*
X417217Y266240D01*
X417630Y266317D01*
X418043Y266240D01*
X418353Y266048D01*
X418508Y265703D01*
Y264783D01*
G01X419800Y267807D02*
X416700D01*
Y268573D01*
X416855Y268880D01*
X417062Y269110D01*
X417372Y269302D01*
X417733Y269455D01*
X418250Y269493D01*
X418767Y269455D01*
X419128Y269302D01*
X419438Y269110D01*
X419645Y268880D01*
X419800Y268573D01*
Y267807D01*
G01Y271750D02*
X419748Y272018D01*
X419593Y272325D01*
X419335Y272517D01*
X418973Y272593D01*
X418612Y272517D01*
X418302Y272287D01*
X418147Y271942D01*
Y271558D01*
X418043Y271328D01*
X417785Y271137D01*
X417423Y271060D01*
X417062Y271175D01*
X416803Y271443D01*
X416700Y271750D01*
X416803Y272057D01*
X417062Y272325D01*
X417423Y272440D01*
X417785Y272363D01*
X418043Y272172D01*
X418147Y271942D01*
Y271558D01*
X418302Y271213D01*
X418612Y270983D01*
X418973Y270907D01*
X419335Y270983D01*
X419593Y271175D01*
X419748Y271482D01*
X419800Y271750D01*
G01X419438Y274198D02*
X419697Y274467D01*
X419800Y274773D01*
X419697Y275080D01*
X419387Y275348D01*
X418922Y275540D01*
X418457Y275617D01*
X417888D01*
X417423Y275540D01*
X417010Y275348D01*
X416803Y275118D01*
X416700Y274850D01*
X416803Y274543D01*
X417010Y274313D01*
X417320Y274160D01*
X417733Y274083D01*
X418095Y274160D01*
X418457Y274352D01*
X418663Y274582D01*
X418715Y274850D01*
X418612Y275157D01*
X418353Y275387D01*
X417888Y275617D01*
G01X415675Y264635D02*
Y295727D01*
G01X421951Y311161D02*
X424184D01*
G01X414077D02*
X416337D01*
G01X420877D02*
X418818D01*
G01X414077D02*
Y317361D01*
G01X421951Y311161D02*
Y317361D01*
G01X420877D02*
Y311161D01*
G01X425151Y316426D02*
Y312030D01*
G01X417277Y316436D02*
Y312061D01*
G01X417677Y316436D02*
Y312061D01*
G01X421951Y317361D02*
X424085D01*
G01X420877D02*
X418648D01*
G01X414077D02*
X416246D01*
G01X416689Y328900D02*
Y326689D01*
G01D02*
X418900D01*
G01X413907Y356100D02*
Y353878D01*
X414060Y353413D01*
X414367Y353103D01*
X414750Y353000D01*
X415133Y353103D01*
X415440Y353413D01*
X415593Y353878D01*
Y356100D01*
G01X417850Y353000D02*
Y356100D01*
X417390Y355480D01*
G01Y353000D02*
X418310D01*
G01X420950D02*
Y356100D01*
X420490Y355480D01*
G01Y353000D02*
X421410D01*
G01X423207Y353465D02*
X423437Y353207D01*
X423705Y353052D01*
X424050Y353000D01*
X424395Y353103D01*
X424663Y353310D01*
X424855Y353672D01*
X424893Y354085D01*
X424817Y354498D01*
X424625Y354757D01*
X424357Y354963D01*
X424088Y355015D01*
X423820Y354963D01*
X423475Y354757D01*
X423590Y356100D01*
X424625D01*
G01X416689Y350311D02*
Y348100D01*
G01X418900Y350311D02*
X416689D01*
G01X424800Y373783D02*
X421700D01*
Y374703D01*
X421855Y375010D01*
X422217Y375240D01*
X422630Y375317D01*
X423043Y375240D01*
X423353Y375048D01*
X423508Y374703D01*
Y373783D01*
G01X424800Y376807D02*
X421700D01*
Y377573D01*
X421855Y377880D01*
X422062Y378110D01*
X422372Y378302D01*
X422733Y378455D01*
X423250Y378493D01*
X423767Y378455D01*
X424128Y378302D01*
X424438Y378110D01*
X424645Y377880D01*
X424800Y377573D01*
Y376807D01*
G01Y380750D02*
X421700D01*
X422320Y380290D01*
G01X424800D02*
Y381210D01*
G01X422217Y383122D02*
X421907Y383352D01*
X421752Y383620D01*
X421700Y383927D01*
X421803Y384310D01*
X422062Y384578D01*
X422372Y384655D01*
X422682Y384617D01*
X422940Y384463D01*
X423457Y383697D01*
X423818Y383352D01*
X424335Y383122D01*
X424800Y383045D01*
Y384655D01*
G01X420557Y373767D02*
Y404859D01*
G01X426079Y360557D02*
X422879D01*
G01Y366757D02*
X426079D01*
G01X422879Y360557D02*
Y366757D01*
G01X417918Y360549D02*
X414718D01*
G01X417918Y366749D02*
Y360549D01*
G01X414718Y366749D02*
X417918D01*
G01X414718Y360549D02*
Y366749D01*
G01X418822Y366757D02*
X422022D01*
G01X418822Y360557D02*
Y366757D01*
G01X422022Y360557D02*
X418822D01*
G01X422022Y366757D02*
Y360557D01*
G01X410718Y366749D02*
X413918D01*
G01X410718Y360549D02*
Y366749D01*
G01X413918Y360549D02*
X410718D01*
G01X413918Y366749D02*
Y360549D01*
G01X420233Y427013D02*
Y423813D01*
G01X414033D02*
Y427013D01*
G01X420233Y423813D02*
X414033D01*
G01X433063Y425070D02*
X432903Y424820D01*
X432716Y424695D01*
X432503Y424653D01*
X432236Y424736D01*
X432049Y424945D01*
X431996Y425195D01*
X432023Y425445D01*
X432129Y425653D01*
X432663Y426070D01*
X432903Y426361D01*
X433063Y426778D01*
X433116Y427153D01*
X431996D01*
G01X430356D02*
Y424653D01*
X430676Y425153D01*
G01Y427153D02*
X430036D01*
G01X428956Y427986D02*
X427356D01*
G01X426463Y425070D02*
X426303Y424820D01*
X426116Y424695D01*
X425903Y424653D01*
X425636Y424736D01*
X425449Y424945D01*
X425396Y425195D01*
X425423Y425445D01*
X425529Y425653D01*
X426063Y426070D01*
X426303Y426361D01*
X426463Y426778D01*
X426516Y427153D01*
X425396D01*
G01X424263Y425070D02*
X424103Y424820D01*
X423916Y424695D01*
X423703Y424653D01*
X423436Y424736D01*
X423249Y424945D01*
X423196Y425195D01*
X423223Y425445D01*
X423329Y425653D01*
X423863Y426070D01*
X424103Y426361D01*
X424263Y426778D01*
X424316Y427153D01*
X423196D01*
G01X410247Y433937D02*
X413447D01*
G01X410247Y427737D02*
Y433937D01*
G01X413447Y427737D02*
X410247D01*
G01X413447Y433937D02*
Y427737D01*
G01X414033Y427013D02*
X420233D01*
G01X414623Y427594D02*
X414373Y427754D01*
X414248Y427941D01*
X414206Y428154D01*
X414289Y428421D01*
X414498Y428608D01*
X414748Y428661D01*
X414998Y428634D01*
X415206Y428528D01*
X415623Y427994D01*
X415914Y427754D01*
X416331Y427594D01*
X416706Y427541D01*
Y428661D01*
G01X414206Y430301D02*
X414289Y430088D01*
X414498Y429928D01*
X414748Y429821D01*
X415081Y429741D01*
X415456Y429714D01*
X415831Y429741D01*
X416164Y429821D01*
X416414Y429928D01*
X416623Y430088D01*
X416706Y430301D01*
X416623Y430514D01*
X416414Y430674D01*
X416164Y430781D01*
X415831Y430861D01*
X415456Y430888D01*
X415081Y430861D01*
X414748Y430781D01*
X414498Y430674D01*
X414289Y430514D01*
X414206Y430301D01*
G01X417571Y430062D02*
X420712D01*
G01X417571Y431227D02*
Y430062D01*
G01X422723D02*
X424623D01*
G01X409373Y457201D02*
X413973D01*
G01X409373Y447001D02*
Y457201D01*
G01X413973Y447001D02*
X409373D01*
G01X413973Y457201D02*
Y447001D01*
G01X422773Y460701D02*
Y457501D01*
G01X416573D02*
Y460701D01*
G01X422773Y457501D02*
X416573D01*
G01X422773Y456901D02*
Y453701D01*
G01X416573Y456901D02*
X422773D01*
G01X416573Y453701D02*
Y456901D01*
G01X422773Y453701D02*
X416573D01*
G01X424073Y454501D02*
Y460701D01*
G01X427273Y454501D02*
X424073D01*
G01X415025Y443260D02*
X412525D01*
X413025Y442940D01*
G01X415025D02*
Y443580D01*
G01X412942Y444953D02*
X412692Y445113D01*
X412567Y445300D01*
X412525Y445513D01*
X412608Y445780D01*
X412817Y445967D01*
X413067Y446020D01*
X413317Y445993D01*
X413525Y445887D01*
X413942Y445353D01*
X414233Y445113D01*
X414650Y444953D01*
X415025Y444900D01*
Y446020D01*
G01X419870Y453342D02*
Y450842D01*
X420190Y451342D01*
G01Y453342D02*
X419550D01*
G01X417670D02*
Y450842D01*
X417990Y451342D01*
G01Y453342D02*
X417350D01*
G01X424641Y450140D02*
X422705D01*
G01X417571D02*
Y448975D01*
G01X420705Y450140D02*
X417571D01*
G01X417719Y476284D02*
Y466836D01*
G01X416573Y460701D02*
X422773D01*
G01X424073D02*
X427273D01*
G01X422773Y464701D02*
Y461501D01*
G01X416573Y464701D02*
X422773D01*
G01X416573Y461501D02*
Y464701D01*
G01X422773Y461501D02*
X416573D01*
G01X420201Y472960D02*
Y476160D01*
G01X426401Y472960D02*
X420201D01*
G01X414301Y476284D02*
X417719D01*
G01X412301Y474560D02*
X414301Y476284D01*
G01X410301D02*
X412301Y474560D01*
G01X412600Y489383D02*
X409500D01*
Y490303D01*
X409655Y490610D01*
X410017Y490840D01*
X410430Y490917D01*
X410843Y490840D01*
X411153Y490648D01*
X411308Y490303D01*
Y489383D01*
G01X412600Y492407D02*
X409500D01*
Y493173D01*
X409655Y493480D01*
X409862Y493710D01*
X410172Y493902D01*
X410533Y494055D01*
X411050Y494093D01*
X411567Y494055D01*
X411928Y493902D01*
X412238Y493710D01*
X412445Y493480D01*
X412600Y493173D01*
Y492407D01*
G01X411980Y495507D02*
X412342Y495737D01*
X412548Y496043D01*
X412600Y496388D01*
X412548Y496695D01*
X412290Y497002D01*
X411980Y497193D01*
X411670Y497232D01*
X411308Y497155D01*
X411050Y496887D01*
X410947Y496618D01*
Y496273D01*
G01Y496618D02*
X410792Y496848D01*
X410533Y497040D01*
X410223Y497117D01*
X409913Y497040D01*
X409655Y496848D01*
X409500Y496503D01*
X409552Y496158D01*
X409758Y495813D01*
G01X419090Y484403D02*
Y486829D01*
G01X425138Y487943D02*
X413642D01*
G01X425138Y517502D02*
Y487943D01*
G01X413642D02*
Y517502D01*
G01X420201Y476160D02*
X426401D01*
G01X418990Y521143D02*
Y518903D01*
G01X420615Y520116D02*
X417365D01*
G01X413642Y517502D02*
X425138D01*
G01X413213Y530263D02*
X420340D01*
G01X413213Y548917D02*
Y530263D01*
G01X416213Y551917D02*
X413213Y548917D01*
G01X420340Y551917D02*
X416213D01*
G01X410807Y559001D02*
Y617601D01*
G01X461201Y559001D02*
X410807D01*
G01Y617601D02*
X461201D01*
G01X423059Y624226D02*
X419859D01*
G01X423059Y630426D02*
Y624226D01*
G01X419859Y630426D02*
X423059D01*
G01X419859Y624226D02*
Y630426D01*
G01X425941Y621555D02*
X423441D01*
X423941Y621235D01*
G01X425941D02*
Y621875D01*
G01X425649Y623302D02*
X425858Y623488D01*
X425941Y623702D01*
X425858Y623915D01*
X425608Y624102D01*
X425233Y624235D01*
X424858Y624288D01*
X424399D01*
X424024Y624235D01*
X423691Y624102D01*
X423524Y623942D01*
X423441Y623755D01*
X423524Y623542D01*
X423691Y623382D01*
X423941Y623275D01*
X424274Y623222D01*
X424566Y623275D01*
X424858Y623408D01*
X425024Y623568D01*
X425066Y623755D01*
X424983Y623968D01*
X424774Y624128D01*
X424399Y624288D01*
G01X423808Y632461D02*
X421308D01*
X421808Y632141D01*
G01X423808D02*
Y632781D01*
G01Y634661D02*
X421308D01*
X421808Y634341D01*
G01X423808D02*
Y634981D01*
G01X424641Y636061D02*
Y637661D01*
G01X423808Y639061D02*
X421308D01*
X421808Y638741D01*
G01X423808D02*
Y639381D01*
G01Y641261D02*
X423766Y641448D01*
X423641Y641661D01*
X423433Y641794D01*
X423141Y641848D01*
X422850Y641794D01*
X422600Y641634D01*
X422475Y641394D01*
Y641128D01*
X422391Y640968D01*
X422183Y640834D01*
X421891Y640781D01*
X421600Y640861D01*
X421391Y641048D01*
X421308Y641261D01*
X421391Y641474D01*
X421600Y641661D01*
X421891Y641741D01*
X422183Y641688D01*
X422391Y641554D01*
X422475Y641394D01*
Y641128D01*
X422600Y640888D01*
X422850Y640728D01*
X423141Y640674D01*
X423433Y640728D01*
X423641Y640861D01*
X423766Y641074D01*
X423808Y641261D01*
G01X431226Y651538D02*
X419226D01*
G01D02*
Y657538D01*
G01X431226Y644730D02*
X419226D01*
G01Y650730D02*
X431226D01*
G01X419226Y644730D02*
Y650730D01*
G01Y657538D02*
X431226D01*
G01X424545Y659652D02*
X429482Y664589D01*
G01X424545Y686424D02*
X429482Y681487D01*
G01X423407Y740387D02*
X423637Y740025D01*
X423943Y739819D01*
X424288Y739767D01*
X424595Y739819D01*
X424902Y740077D01*
X425093Y740387D01*
X425132Y740697D01*
X425055Y741059D01*
X424787Y741317D01*
X424518Y741420D01*
X424173D01*
G01X424518D02*
X424748Y741575D01*
X424940Y741834D01*
X425017Y742144D01*
X424940Y742454D01*
X424748Y742712D01*
X424403Y742867D01*
X424058Y742815D01*
X423713Y742609D01*
G01X426622Y742350D02*
X426852Y742660D01*
X427120Y742815D01*
X427427Y742867D01*
X427810Y742764D01*
X428078Y742505D01*
X428155Y742195D01*
X428117Y741885D01*
X427963Y741627D01*
X427197Y741110D01*
X426852Y740749D01*
X426622Y740232D01*
X426545Y739767D01*
X428155D01*
G01X424200Y745083D02*
X426017D01*
Y746900D01*
G01X419127Y742900D02*
Y738900D01*
G01X409284Y743000D02*
Y741000D01*
G01X426017Y778700D02*
Y780517D01*
X424200D01*
G01X421095Y786700D02*
Y782700D01*
G01X411253Y784800D02*
Y782800D01*
G01X427600Y790900D02*
Y784700D01*
X424400D01*
Y790900D01*
X427600D01*
G01X418800Y794014D02*
Y800214D01*
X422000D01*
Y794014D01*
X418800D01*
G01X417800Y800200D02*
Y794000D01*
X414600D01*
Y800200D01*
X417800D01*
G01X410500Y794014D02*
Y800214D01*
X413700D01*
Y794014D01*
X410500D01*
G01X414340Y832729D02*
X409740D01*
G01X414340Y842729D02*
X409740D01*
G01Y832729D02*
Y842729D01*
G01X409840Y832729D02*
X409740D01*
G01X414340Y842729D02*
Y832729D01*
G01X413741Y843644D02*
Y849644D01*
G01X425741Y843644D02*
X413741D01*
G01X410468Y849677D02*
Y843677D01*
G01X415338Y833200D02*
Y836400D01*
G01X421538Y833200D02*
X415338D01*
G01X421538Y836400D02*
Y833200D01*
G01X415338Y836400D02*
X421538D01*
G01X413741Y849644D02*
X425741D01*
G01X413741Y859644D02*
Y865644D01*
G01X425741Y859644D02*
X413741D01*
G01Y857644D02*
X425741D01*
G01X413741Y851644D02*
Y857644D01*
G01X425741Y851644D02*
X413741D01*
G01X412567Y856720D02*
X409467D01*
Y857640D01*
X409622Y857947D01*
X409984Y858177D01*
X410397Y858254D01*
X410810Y858177D01*
X411120Y857985D01*
X411275Y857640D01*
Y856720D01*
G01X409467Y859744D02*
X411689D01*
X412154Y859897D01*
X412464Y860204D01*
X412567Y860587D01*
X412464Y860970D01*
X412154Y861277D01*
X411689Y861430D01*
X409467D01*
G01X409984Y862959D02*
X409674Y863189D01*
X409519Y863457D01*
X409467Y863764D01*
X409570Y864147D01*
X409829Y864415D01*
X410139Y864492D01*
X410449Y864454D01*
X410707Y864300D01*
X411224Y863534D01*
X411585Y863189D01*
X412102Y862959D01*
X412567Y862882D01*
Y864492D01*
G01X409467Y866787D02*
X409570Y866480D01*
X409829Y866250D01*
X410139Y866097D01*
X410552Y865982D01*
X411017Y865944D01*
X411482Y865982D01*
X411895Y866097D01*
X412205Y866250D01*
X412464Y866480D01*
X412567Y866787D01*
X412464Y867094D01*
X412205Y867324D01*
X411895Y867477D01*
X411482Y867592D01*
X411017Y867630D01*
X410552Y867592D01*
X410139Y867477D01*
X409829Y867324D01*
X409570Y867094D01*
X409467Y866787D01*
G01X413741Y865644D02*
X425741D01*
G01X425217Y877298D02*
X427717D01*
X427217Y877618D01*
G01X425217D02*
Y876978D01*
G01Y875098D02*
X427717D01*
X427217Y875418D01*
G01X425217D02*
Y874778D01*
G01X424384Y873698D02*
Y872098D01*
G01X425217Y870698D02*
X427717D01*
X427217Y871018D01*
G01X425217D02*
Y870378D01*
G01Y868498D02*
X425259Y868311D01*
X425384Y868098D01*
X425592Y867965D01*
X425884Y867911D01*
X426175Y867965D01*
X426425Y868125D01*
X426550Y868365D01*
Y868631D01*
X426634Y868791D01*
X426842Y868925D01*
X427134Y868978D01*
X427425Y868898D01*
X427634Y868711D01*
X427717Y868498D01*
X427634Y868285D01*
X427425Y868098D01*
X427134Y868018D01*
X426842Y868071D01*
X426634Y868205D01*
X426550Y868365D01*
Y868631D01*
X426425Y868871D01*
X426175Y869031D01*
X425884Y869085D01*
X425592Y869031D01*
X425384Y868898D01*
X425259Y868685D01*
X425217Y868498D01*
G01X416450Y868727D02*
X422552D01*
Y869198D01*
G01X410348Y868998D02*
Y868727D01*
G01D02*
X414150D01*
G01X415250Y867098D02*
Y864098D01*
G01X415889Y891151D02*
Y887951D01*
G01X409689Y891151D02*
X415889D01*
G01X409689Y887951D02*
Y891151D01*
G01X415889Y887951D02*
X409689D01*
G01X425941Y895833D02*
X419952D01*
G01X422800Y888200D02*
X425300D01*
X424800Y888520D01*
G01X422800D02*
Y887880D01*
G01X423092Y886453D02*
X422883Y886267D01*
X422800Y886053D01*
X422883Y885840D01*
X423133Y885653D01*
X423508Y885520D01*
X423883Y885467D01*
X424342D01*
X424717Y885520D01*
X425050Y885653D01*
X425217Y885813D01*
X425300Y886000D01*
X425217Y886213D01*
X425050Y886373D01*
X424800Y886480D01*
X424467Y886533D01*
X424175Y886480D01*
X423883Y886347D01*
X423717Y886187D01*
X423675Y886000D01*
X423758Y885787D01*
X423967Y885627D01*
X424342Y885467D01*
G01X422552Y884598D02*
Y884869D01*
X418750D01*
G01X414150D02*
X410348D01*
Y884598D01*
G01X417650Y886498D02*
Y889498D01*
G01X410121Y928278D02*
Y940278D01*
G01X416121Y928278D02*
X410121D01*
G01X416121Y940278D02*
Y928278D01*
G01X418121D02*
Y940278D01*
G01X424121Y928278D02*
X418121D01*
G01X424121Y940278D02*
Y928278D01*
G01X419852Y924573D02*
X425941D01*
G01X410121Y940278D02*
X416121D01*
G01X418121D02*
X424121D01*
G01X422209Y945037D02*
Y976041D01*
G01X419282Y1059313D02*
Y1053113D01*
G01D02*
X416082D01*
G01D02*
Y1059313D01*
G01X434544Y1056313D02*
X424858D01*
G01D02*
Y1078148D01*
G01X416082Y1059313D02*
X419282D01*
G01X419826Y1080348D02*
Y1062632D01*
G01D02*
X416418D01*
G01Y1080348D02*
X419826D01*
G01X424858Y1078148D02*
X429795Y1083085D01*
G01X412268Y1107230D02*
Y1101030D01*
G01X413790Y1100426D02*
Y1097226D01*
G01X412855Y1107230D02*
X416055D01*
G01X412855Y1101030D02*
Y1107230D01*
G01X416055Y1101030D02*
X412855D01*
G01X416055Y1107230D02*
Y1101030D01*
G01X424132Y1103442D02*
Y1097242D01*
X420932D01*
Y1103442D01*
X424132D01*
G01X428966Y1178013D02*
Y1180253D01*
G01X427341Y1179040D02*
X430591D01*
G01X421935Y1176643D02*
X421931Y1178152D01*
G01X421934Y1213533D02*
Y1177793D01*
G01X423934Y1189471D02*
Y1201471D01*
G01X429934Y1189471D02*
X423934D01*
G01Y1201471D02*
X429934D01*
G01X429122Y1219935D02*
Y1209735D01*
X424522D01*
Y1219935D01*
X429122D01*
G01X420779Y1249202D02*
X434169D01*
G01X418969Y1247418D02*
X410069D01*
G01X418969Y1267704D02*
Y1247418D01*
G01X410069D02*
Y1267704D01*
G01X420787Y1271995D02*
Y1268895D01*
X422321D01*
G01X423811Y1269360D02*
X424041Y1269102D01*
X424309Y1268947D01*
X424654Y1268895D01*
X424999Y1268998D01*
X425267Y1269205D01*
X425459Y1269567D01*
X425497Y1269980D01*
X425421Y1270393D01*
X425229Y1270652D01*
X424961Y1270858D01*
X424692Y1270910D01*
X424424Y1270858D01*
X424079Y1270652D01*
X424194Y1271995D01*
X425229D01*
G01X427754D02*
X427447Y1271892D01*
X427217Y1271633D01*
X427064Y1271323D01*
X426949Y1270910D01*
X426911Y1270445D01*
X426949Y1269980D01*
X427064Y1269567D01*
X427217Y1269257D01*
X427447Y1268998D01*
X427754Y1268895D01*
X428061Y1268998D01*
X428291Y1269257D01*
X428444Y1269567D01*
X428559Y1269980D01*
X428597Y1270445D01*
X428559Y1270910D01*
X428444Y1271323D01*
X428291Y1271633D01*
X428061Y1271892D01*
X427754Y1271995D01*
G01X434169Y1266904D02*
X420346D01*
G01X410069Y1267704D02*
X418969D01*
G01X413087Y1496599D02*
X409887D01*
Y1502799D01*
G01X420439Y1502702D02*
Y1496502D01*
X417239D01*
G01Y1493352D02*
Y1496587D01*
G01Y1499552D02*
X420439D01*
Y1493352D01*
G01X409887Y1493449D02*
Y1499649D01*
X413087D01*
G01Y1496629D02*
Y1493449D01*
G01Y1502799D02*
Y1499513D01*
G01X417239Y1499492D02*
Y1502702D01*
G01X417285Y1530338D02*
X417338Y1530880D01*
X417418Y1531338D01*
X417525Y1531755D01*
X417658Y1532213D01*
X417871Y1532838D01*
X416805D01*
G01X416591Y1524896D02*
X421804D01*
Y1521696D01*
X416486D01*
G01X418975Y1534237D02*
X419162Y1534279D01*
X419375Y1534404D01*
X419508Y1534612D01*
X419562Y1534904D01*
X419508Y1535195D01*
X419348Y1535445D01*
X419108Y1535570D01*
X418842D01*
X418682Y1535654D01*
X418548Y1535862D01*
X418495Y1536154D01*
X418575Y1536445D01*
X418762Y1536654D01*
X418975Y1536737D01*
X419188Y1536654D01*
X419375Y1536445D01*
X419455Y1536154D01*
X419402Y1535862D01*
X419268Y1535654D01*
X419108Y1535570D01*
X418842D01*
X418602Y1535445D01*
X418442Y1535195D01*
X418388Y1534904D01*
X418442Y1534612D01*
X418575Y1534404D01*
X418788Y1534279D01*
X418975Y1534237D01*
G01X418496Y1541915D02*
X421496D01*
G01X416839Y1534072D02*
X413996D01*
G01X416839Y1536915D02*
Y1534072D01*
G01X422516Y1538688D02*
X428716D01*
G01X422516Y1535488D02*
Y1538688D01*
G01X428716Y1535488D02*
X422516D01*
G01X423124Y1547972D02*
X429324D01*
Y1544772D01*
X423124D01*
Y1547972D01*
G01X424824Y1553158D02*
X436624D01*
G01X424824Y1562958D02*
Y1553158D01*
G01X418691Y1552952D02*
Y1555452D01*
X418371Y1554952D01*
G01Y1552952D02*
X419011D01*
G01X421211D02*
Y1555452D01*
X420224Y1553660D01*
X421558D01*
G01X414394Y1554894D02*
Y1557394D01*
X414074Y1556894D01*
G01Y1554894D02*
X414714D01*
G01X416007Y1555269D02*
X416167Y1555061D01*
X416354Y1554936D01*
X416594Y1554894D01*
X416834Y1554977D01*
X417021Y1555144D01*
X417154Y1555436D01*
X417181Y1555769D01*
X417127Y1556102D01*
X416994Y1556311D01*
X416807Y1556477D01*
X416621Y1556519D01*
X416434Y1556477D01*
X416194Y1556311D01*
X416274Y1557394D01*
X416994D01*
G01X412996Y1555415D02*
Y1556915D01*
G01X416839Y1553758D02*
Y1550915D01*
G01X413996Y1553758D02*
X416839D01*
G01X423036Y1548611D02*
Y1551811D01*
G01X429236Y1548611D02*
X423036D01*
G01Y1551811D02*
X429236D01*
G01X411061Y1568109D02*
Y1561909D01*
G01X415061D02*
X411861D01*
G01X415061Y1568109D02*
Y1561909D01*
G01X411861D02*
Y1568109D01*
G01X419861Y1561909D02*
Y1568109D01*
G01X423061Y1561909D02*
X419861D01*
G01X423061Y1568109D02*
Y1561909D01*
G01X415861D02*
Y1568109D01*
G01X419061Y1561909D02*
X415861D01*
G01X419061Y1568109D02*
Y1561909D01*
G01X436624Y1562958D02*
X424824D01*
G01X411861Y1568109D02*
X415061D01*
G01X419861D02*
X423061D01*
G01X415861D02*
X419061D01*
G01X435768Y144690D02*
Y154138D01*
G01X446604Y144690D02*
X435768D01*
G01X438349Y139647D02*
Y142847D01*
G01X444549Y139647D02*
X438349D01*
G01Y142847D02*
X444549D01*
G01X431370Y139647D02*
Y142847D01*
G01X437570Y139647D02*
X431370D01*
G01X437570Y142847D02*
Y139647D01*
G01X431370Y142847D02*
X437570D01*
G01X427400Y145940D02*
Y149140D01*
G01X433600Y145940D02*
X427400D01*
G01X433600Y149140D02*
Y145940D01*
G01X427400Y149140D02*
X433600D01*
G01X436550Y155400D02*
X436243Y155452D01*
X435975Y155658D01*
X435745Y155968D01*
X435592Y156330D01*
X435515Y156743D01*
Y157157D01*
X435592Y157570D01*
X435745Y157932D01*
X435975Y158242D01*
X436243Y158448D01*
X436550Y158500D01*
X436857Y158448D01*
X437125Y158242D01*
X437355Y157932D01*
X437508Y157570D01*
X437585Y157157D01*
Y156743D01*
X437508Y156330D01*
X437355Y155968D01*
X437125Y155658D01*
X436857Y155452D01*
X436550Y155400D01*
G01X436857Y156227D02*
X437317Y155400D01*
G01X438922Y157983D02*
X439152Y158293D01*
X439420Y158448D01*
X439727Y158500D01*
X440110Y158397D01*
X440378Y158138D01*
X440455Y157828D01*
X440417Y157518D01*
X440263Y157260D01*
X439497Y156743D01*
X439152Y156382D01*
X438922Y155865D01*
X438845Y155400D01*
X440455D01*
G01X442022Y157983D02*
X442252Y158293D01*
X442520Y158448D01*
X442827Y158500D01*
X443210Y158397D01*
X443478Y158138D01*
X443555Y157828D01*
X443517Y157518D01*
X443363Y157260D01*
X442597Y156743D01*
X442252Y156382D01*
X442022Y155865D01*
X441945Y155400D01*
X443555D01*
G01X445850Y158500D02*
X445543Y158397D01*
X445313Y158138D01*
X445160Y157828D01*
X445045Y157415D01*
X445007Y156950D01*
X445045Y156485D01*
X445160Y156072D01*
X445313Y155762D01*
X445543Y155503D01*
X445850Y155400D01*
X446157Y155503D01*
X446387Y155762D01*
X446540Y156072D01*
X446655Y156485D01*
X446693Y156950D01*
X446655Y157415D01*
X446540Y157828D01*
X446387Y158138D01*
X446157Y158397D01*
X445850Y158500D01*
G01X441186Y152414D02*
X443186Y154138D01*
G01X439186D02*
X441186Y152414D01*
G01X435768Y154138D02*
X439186D01*
G01X433600Y153140D02*
Y149940D01*
G01X427400Y153140D02*
X433600D01*
G01X427400Y149940D02*
Y153140D01*
G01X433600Y149940D02*
X427400D01*
G01X436625Y311161D02*
X434514D01*
G01X429825D02*
X432063D01*
G01X428751D02*
X426506D01*
G01X436625Y317361D02*
Y311161D01*
G01X429825D02*
Y317361D01*
G01X428751D02*
Y311161D01*
G01X433025Y316376D02*
Y312089D01*
G01X433425Y316376D02*
Y312089D01*
G01X425551Y316426D02*
Y312030D01*
G01X436625Y317361D02*
X434464D01*
G01X429825D02*
X431894D01*
G01X428751D02*
X426496D01*
G01X440311Y326689D02*
Y328900D01*
G01X438100Y326689D02*
X440311D01*
G01X436624Y360418D02*
X434441D01*
G01X429824D02*
X432010D01*
G01X429824D02*
Y366618D01*
G01X436624D02*
Y360418D01*
G01X440311Y350311D02*
X438100D01*
G01X440311Y348100D02*
Y350311D01*
G01X433424Y365691D02*
Y361524D01*
G01X433024Y365691D02*
Y361524D01*
G01X436624Y366618D02*
X434390D01*
G01X429824D02*
X431984D01*
G01X426079Y366757D02*
Y360557D01*
G01X426383Y402000D02*
Y405100D01*
X427303D01*
X427610Y404945D01*
X427840Y404583D01*
X427917Y404170D01*
X427840Y403757D01*
X427648Y403447D01*
X427303Y403292D01*
X426383D01*
G01X429407Y402000D02*
Y405100D01*
X430173D01*
X430480Y404945D01*
X430710Y404738D01*
X430902Y404428D01*
X431055Y404067D01*
X431093Y403550D01*
X431055Y403033D01*
X430902Y402672D01*
X430710Y402362D01*
X430480Y402155D01*
X430173Y402000D01*
X429407D01*
G01X433273D02*
X433350Y402672D01*
X433465Y403240D01*
X433618Y403757D01*
X433810Y404325D01*
X434117Y405100D01*
X432583D01*
G01X436373Y402000D02*
X436450Y402672D01*
X436565Y403240D01*
X436718Y403757D01*
X436910Y404325D01*
X437217Y405100D01*
X435683D01*
G01X438071Y406628D02*
Y422140D01*
G01X439073Y423001D02*
Y426201D01*
G01X445273Y423001D02*
X439073D01*
G01Y429701D02*
X445273D01*
G01X439073Y426501D02*
Y429701D01*
G01X445273Y426501D02*
X439073D01*
G01Y433501D02*
Y436701D01*
G01X445273Y433501D02*
X439073D01*
G01Y436701D02*
X445273D01*
G01X439073Y441501D02*
Y444701D01*
G01X445273Y441501D02*
X439073D01*
G01Y426201D02*
X445273D01*
G01X437174Y437439D02*
X433974D01*
G01X437174Y443639D02*
Y437439D01*
G01X433974D02*
Y443639D01*
G01X439073Y437501D02*
Y440701D01*
G01X445273Y437501D02*
X439073D01*
G01Y440701D02*
X445273D01*
G01X439073Y433201D02*
X445273D01*
G01X439073Y430001D02*
Y433201D01*
G01X445273Y430001D02*
X439073D01*
G01X429775Y430062D02*
Y431235D01*
G01X426634Y430062D02*
X429775D01*
G01X439073Y444701D02*
X445273D01*
G01X439073Y445501D02*
Y448701D01*
G01X445273Y445501D02*
X439073D01*
G01Y448701D02*
X445273D01*
G01X433974Y443639D02*
X437174D01*
G01X439073Y451001D02*
Y454201D01*
G01X445273Y451001D02*
X439073D01*
G01Y454201D02*
X445273D01*
G01X431273Y454501D02*
X428073D01*
G01X431273Y460701D02*
Y454501D01*
G01X428073D02*
Y460701D01*
G01X435273Y454501D02*
X432073D01*
G01X435273Y460701D02*
Y454501D01*
G01X432073D02*
Y460701D01*
G01X427273D02*
Y454501D01*
G01X430373Y454034D02*
Y451534D01*
X430693Y452034D01*
G01Y454034D02*
X430053D01*
G01X428173Y451534D02*
X428386Y451617D01*
X428546Y451826D01*
X428653Y452076D01*
X428733Y452409D01*
X428760Y452784D01*
X428733Y453159D01*
X428653Y453492D01*
X428546Y453742D01*
X428386Y453951D01*
X428173Y454034D01*
X427960Y453951D01*
X427800Y453742D01*
X427693Y453492D01*
X427613Y453159D01*
X427586Y452784D01*
X427613Y452409D01*
X427693Y452076D01*
X427800Y451826D01*
X427960Y451617D01*
X428173Y451534D01*
G01X433714Y449848D02*
X433923Y450034D01*
X434006Y450248D01*
X433923Y450461D01*
X433673Y450648D01*
X433298Y450781D01*
X432923Y450834D01*
X432464D01*
X432089Y450781D01*
X431756Y450648D01*
X431589Y450488D01*
X431506Y450301D01*
X431589Y450088D01*
X431756Y449928D01*
X432006Y449821D01*
X432339Y449768D01*
X432631Y449821D01*
X432923Y449954D01*
X433089Y450114D01*
X433131Y450301D01*
X433048Y450514D01*
X432839Y450674D01*
X432464Y450834D01*
G01X429775Y450140D02*
X426641D01*
G01X429775Y448975D02*
Y450140D01*
G01X428073Y460701D02*
X431273D01*
G01X432073D02*
X435273D01*
G01X426401Y476160D02*
Y472960D01*
G01X428764Y498150D02*
Y510150D01*
G01X434764Y498150D02*
X428764D01*
G01X434764Y510150D02*
Y498150D01*
G01X439757Y501509D02*
X436557D01*
G01X439757Y507709D02*
Y501509D01*
G01X436557D02*
Y507709D01*
G01X456356Y504743D02*
Y492539D01*
X441052D01*
Y504743D01*
X456356D01*
G01X428764Y510150D02*
X434764D01*
G01X437590Y518536D02*
X449590D01*
G01X437590Y512536D02*
Y518536D01*
G01X449590Y512536D02*
X437590D01*
G01X441340Y510599D02*
X447540D01*
G01X441340Y507399D02*
Y510599D01*
G01X447540Y507399D02*
X441340D01*
G01X436557Y507709D02*
X439757D01*
G01X436877Y530263D02*
X444004D01*
G01X436877Y548917D02*
Y530263D01*
G01X434867D02*
Y548917D01*
G01X427740Y530263D02*
X434867D01*
G01X439877Y551917D02*
X436877Y548917D01*
G01X444004Y551917D02*
X439877D01*
G01X431867D02*
X427740D01*
G01X434867Y548917D02*
X431867Y551917D01*
G01X441537Y618856D02*
Y622056D01*
G01X447737Y618856D02*
X441537D01*
G01X432991D02*
Y622056D01*
G01X439191Y618856D02*
X432991D01*
G01X439191Y622056D02*
Y618856D01*
G01X431375Y623261D02*
Y620261D01*
G01X441537Y622056D02*
X447737D01*
G01X432991D02*
X439191D01*
G01X426473Y625161D02*
Y624890D01*
X430275D01*
G01X434875D02*
X438677D01*
Y625161D01*
G01X440375Y632961D02*
X441875D01*
G01X435726Y651538D02*
Y657538D01*
G01X447726Y651538D02*
X435726D01*
G01Y650730D02*
X447726D01*
G01X435726Y644730D02*
Y650730D01*
G01X447726Y644730D02*
X435726D01*
G01X431226Y657538D02*
Y651538D01*
G01Y650730D02*
Y644730D01*
G01X442616Y640608D02*
X442825Y640794D01*
X442908Y641008D01*
X442825Y641221D01*
X442575Y641408D01*
X442200Y641541D01*
X441825Y641594D01*
X441366D01*
X440991Y641541D01*
X440658Y641408D01*
X440491Y641248D01*
X440408Y641061D01*
X440491Y640848D01*
X440658Y640688D01*
X440908Y640581D01*
X441241Y640528D01*
X441533Y640581D01*
X441825Y640714D01*
X441991Y640874D01*
X442033Y641061D01*
X441950Y641274D01*
X441741Y641434D01*
X441366Y641594D01*
G01X432575Y641032D02*
X426473D01*
Y640561D01*
G01X438677Y640761D02*
Y641032D01*
G01D02*
X434875D01*
G01X433775Y642661D02*
Y645661D01*
G01X435726Y657538D02*
X447726D01*
G01X440470Y664589D02*
Y669338D01*
G01X445407Y659652D02*
X440470Y664589D01*
G01X429482D02*
Y669338D01*
G01X440470Y681487D02*
Y676738D01*
G01X445407Y686424D02*
X440470Y681487D01*
G01X429482D02*
Y676738D01*
G01X443194Y689841D02*
X439786D01*
G01X425478D02*
Y707557D01*
G01X428886Y689841D02*
X425478D01*
G01X440736Y709599D02*
Y712799D01*
G01X446936Y709599D02*
X440736D01*
G01Y712799D02*
X446936D01*
G01X425478Y707557D02*
X428886D01*
G01X439786D02*
X443194D01*
G01X428887Y748193D02*
X428525Y747963D01*
X428319Y747657D01*
X428267Y747312D01*
X428319Y747005D01*
X428577Y746698D01*
X428887Y746507D01*
X429197Y746468D01*
X429559Y746545D01*
X429817Y746813D01*
X429920Y747082D01*
Y747427D01*
G01Y747082D02*
X430075Y746852D01*
X430334Y746660D01*
X430644Y746583D01*
X430954Y746660D01*
X431212Y746852D01*
X431367Y747197D01*
X431315Y747542D01*
X431109Y747887D01*
G01X428887Y745093D02*
X428525Y744863D01*
X428319Y744557D01*
X428267Y744212D01*
X428319Y743905D01*
X428577Y743598D01*
X428887Y743407D01*
X429197Y743368D01*
X429559Y743445D01*
X429817Y743713D01*
X429920Y743982D01*
Y744327D01*
G01Y743982D02*
X430075Y743752D01*
X430334Y743560D01*
X430644Y743483D01*
X430954Y743560D01*
X431212Y743752D01*
X431367Y744097D01*
X431315Y744442D01*
X431109Y744787D01*
G01X428100Y761816D02*
X432100D01*
G01X430100Y751973D02*
X428100D01*
G01X431784Y783303D02*
X434884D01*
X432662Y784721D01*
Y782805D01*
G01X431784Y780663D02*
X431836Y780395D01*
X431991Y780088D01*
X432249Y779896D01*
X432611Y779820D01*
X432972Y779896D01*
X433282Y780126D01*
X433437Y780471D01*
Y780855D01*
X433541Y781085D01*
X433799Y781276D01*
X434161Y781353D01*
X434522Y781238D01*
X434781Y780970D01*
X434884Y780663D01*
X434781Y780356D01*
X434522Y780088D01*
X434161Y779973D01*
X433799Y780050D01*
X433541Y780241D01*
X433437Y780471D01*
Y780855D01*
X433282Y781200D01*
X432972Y781430D01*
X432611Y781506D01*
X432249Y781430D01*
X431991Y781238D01*
X431836Y780931D01*
X431784Y780663D01*
G01X430100Y771658D02*
X428100D01*
G01X429893Y785907D02*
Y789007D01*
X428475Y786785D01*
X430391D01*
G01X431881Y786269D02*
X432150Y786010D01*
X432456Y785907D01*
X432763Y786010D01*
X433031Y786320D01*
X433223Y786785D01*
X433300Y787250D01*
Y787819D01*
X433223Y788284D01*
X433031Y788697D01*
X432801Y788904D01*
X432533Y789007D01*
X432226Y788904D01*
X431996Y788697D01*
X431843Y788387D01*
X431766Y787974D01*
X431843Y787612D01*
X432035Y787250D01*
X432265Y787044D01*
X432533Y786992D01*
X432840Y787095D01*
X433070Y787354D01*
X433300Y787819D01*
G01X425741Y849644D02*
Y843644D01*
G01Y865644D02*
Y859644D01*
G01Y857644D02*
Y851644D01*
G01X425966Y879333D02*
Y885533D01*
G01X429166Y879333D02*
X425966D01*
G01X429166Y885533D02*
Y879333D01*
G01X425966Y885533D02*
X429166D01*
G01X425941Y924573D02*
Y895833D01*
G01X439339Y888564D02*
Y886138D01*
G01X430781Y891403D02*
Y927099D01*
G01X448497Y891403D02*
X430781D01*
G01X438316Y933267D02*
X440556D01*
G01X439343Y934892D02*
Y931642D01*
G01X430781Y927099D02*
X448497D01*
G01X437244Y1090088D02*
Y1096088D01*
G01X449244Y1090088D02*
X437244D01*
G01X429795Y1083085D02*
X434544D01*
G01X437244Y1096088D02*
X449244D01*
G01X441196Y1107230D02*
X444396D01*
G01X441196Y1101030D02*
Y1107230D01*
G01X444396Y1101030D02*
X441196D01*
G01X439718Y1097226D02*
Y1100426D01*
G01X445918Y1097226D02*
X439718D01*
G01Y1100426D02*
X445918D01*
G01X426313Y1103442D02*
X429513D01*
G01X426313Y1097242D02*
Y1103442D01*
G01X429513Y1097242D02*
X426313D01*
G01X429513Y1103442D02*
Y1097242D01*
G01X429685Y1114996D02*
X432885D01*
G01X429685Y1108796D02*
Y1114996D01*
G01X432885Y1108796D02*
X429685D01*
G01X432885Y1114996D02*
Y1108796D01*
G01Y1119296D02*
X429685D01*
G01X432885Y1125496D02*
Y1119296D01*
G01X429685D02*
Y1125496D01*
G01X436887Y1118297D02*
X433687D01*
G01X436887Y1124497D02*
Y1118297D01*
G01X433687D02*
Y1124497D01*
G01X439496Y1109839D02*
Y1112030D01*
G01X440229Y1109839D02*
X439496D01*
G01X427054Y1124250D02*
Y1122552D01*
G01Y1109839D02*
X426046D01*
G01X427054Y1111693D02*
Y1109839D01*
G01X429685Y1125496D02*
X432885D01*
G01X433687Y1124497D02*
X436887D01*
G01X439496Y1133461D02*
X440289D01*
G01X439496Y1130861D02*
Y1133461D01*
G01X427054D02*
Y1130861D01*
G01X426261Y1133461D02*
X427054D01*
G01X434291Y1136752D02*
Y1174548D01*
G01X440289Y1136752D02*
X434291D01*
G01X431659D02*
X425661D01*
G01X431659Y1174548D02*
Y1136752D01*
G01X448864Y1177793D02*
X431934D01*
G01D02*
Y1213533D01*
G01X431932Y1176593D02*
Y1177793D01*
G01Y1176593D02*
X448915Y1176599D01*
G01X431932Y1177193D02*
X448907Y1177189D01*
G01X431932Y1177793D02*
X448872Y1177790D01*
G01X434291Y1174548D02*
X440289D01*
G01X425661D02*
X431659D01*
G01X429934Y1201471D02*
Y1189471D01*
G01X435469Y1215076D02*
X453171D01*
G01X435469Y1228534D02*
Y1215076D01*
G01X432375Y1215878D02*
Y1218304D01*
G01X431934Y1213533D02*
X448864D01*
G01X434177Y1230276D02*
Y1239176D01*
G01X454463Y1230276D02*
X434177D01*
G01X435469Y1254376D02*
Y1240811D01*
G01X434169Y1249202D02*
Y1266904D01*
G01X434177Y1239176D02*
X454463D01*
G01X453171Y1254376D02*
X435469D01*
G01X439607Y1425158D02*
Y1445730D01*
G01X552599Y1425158D02*
X439607D01*
G01Y1451889D02*
Y1689331D01*
G01X428716Y1538688D02*
Y1535488D01*
G01X436624Y1553158D02*
Y1562958D01*
G01X430124Y1548558D02*
Y1551758D01*
G01X436324Y1548558D02*
X430124D01*
G01X436324Y1551758D02*
Y1548558D01*
G01X430124Y1551758D02*
X436324D01*
G01X429236Y1551811D02*
Y1548611D01*
G01X427407Y1565776D02*
Y1567171D01*
X426640Y1568876D01*
G01X428174D02*
X427407Y1567171D01*
G01X430507Y1565776D02*
X430775Y1565828D01*
X431082Y1565983D01*
X431274Y1566241D01*
X431350Y1566603D01*
X431274Y1566964D01*
X431044Y1567274D01*
X430699Y1567429D01*
X430315D01*
X430085Y1567533D01*
X429894Y1567791D01*
X429817Y1568153D01*
X429932Y1568514D01*
X430200Y1568773D01*
X430507Y1568876D01*
X430814Y1568773D01*
X431082Y1568514D01*
X431197Y1568153D01*
X431120Y1567791D01*
X430929Y1567533D01*
X430699Y1567429D01*
X430315D01*
X429970Y1567274D01*
X429740Y1566964D01*
X429664Y1566603D01*
X429740Y1566241D01*
X429932Y1565983D01*
X430239Y1565828D01*
X430507Y1565776D01*
G01X439607Y1689331D02*
X552599D01*
G01X445398Y-538835D02*
Y-530835D01*
X444198Y-532435D01*
G01Y-538835D02*
X446598D01*
G01X453198D02*
X453398Y-537102D01*
X453698Y-535635D01*
X454098Y-534302D01*
X454598Y-532835D01*
X455398Y-530835D01*
X451398D01*
G01X461398Y-539102D02*
X461198Y-538968D01*
Y-538702D01*
X461398Y-538568D01*
X461598Y-538702D01*
Y-538968D01*
X461398Y-539102D01*
G01X467498Y-532168D02*
X468098Y-531368D01*
X468798Y-530968D01*
X469598Y-530835D01*
X470598Y-531102D01*
X471298Y-531768D01*
X471498Y-532568D01*
X471398Y-533369D01*
X470998Y-534035D01*
X468998Y-535368D01*
X468098Y-536302D01*
X467498Y-537635D01*
X467298Y-538835D01*
X471498D01*
G01X457787Y111951D02*
Y118151D01*
G01X460987Y111951D02*
X457787D01*
G01X456736Y111503D02*
X453636D01*
Y112423D01*
X453791Y112730D01*
X454153Y112960D01*
X454566Y113037D01*
X454979Y112960D01*
X455289Y112768D01*
X455444Y112423D01*
Y111503D01*
G01X453636Y114527D02*
X455858D01*
X456323Y114680D01*
X456633Y114987D01*
X456736Y115370D01*
X456633Y115753D01*
X456323Y116060D01*
X455858Y116213D01*
X453636D01*
G01X456736Y118470D02*
X453636D01*
X454256Y118010D01*
G01X456736D02*
Y118930D01*
G01X454153Y120842D02*
X453843Y121072D01*
X453688Y121340D01*
X453636Y121647D01*
X453739Y122030D01*
X453998Y122298D01*
X454308Y122375D01*
X454618Y122337D01*
X454876Y122183D01*
X455393Y121417D01*
X455754Y121072D01*
X456271Y120842D01*
X456736Y120765D01*
Y122375D01*
G01X456116Y123827D02*
X456478Y124057D01*
X456684Y124363D01*
X456736Y124708D01*
X456684Y125015D01*
X456426Y125322D01*
X456116Y125513D01*
X455806Y125552D01*
X455444Y125475D01*
X455186Y125207D01*
X455083Y124938D01*
Y124593D01*
G01Y124938D02*
X454928Y125168D01*
X454669Y125360D01*
X454359Y125437D01*
X454049Y125360D01*
X453791Y125168D01*
X453636Y124823D01*
X453688Y124478D01*
X453894Y124133D01*
G01X457787Y118151D02*
X460987D01*
G01X455100Y133307D02*
X457322D01*
X457787Y133460D01*
X458097Y133767D01*
X458200Y134150D01*
X458097Y134533D01*
X457787Y134840D01*
X457322Y134993D01*
X455100D01*
G01X457580Y136407D02*
X457942Y136637D01*
X458148Y136943D01*
X458200Y137288D01*
X458148Y137595D01*
X457890Y137902D01*
X457580Y138093D01*
X457270Y138132D01*
X456908Y138055D01*
X456650Y137787D01*
X456547Y137518D01*
Y137173D01*
G01Y137518D02*
X456392Y137748D01*
X456133Y137940D01*
X455823Y138017D01*
X455513Y137940D01*
X455255Y137748D01*
X455100Y137403D01*
X455152Y137058D01*
X455358Y136713D01*
G01X458200Y140350D02*
X458148Y140618D01*
X457993Y140925D01*
X457735Y141117D01*
X457373Y141193D01*
X457012Y141117D01*
X456702Y140887D01*
X456547Y140542D01*
Y140158D01*
X456443Y139928D01*
X456185Y139737D01*
X455823Y139660D01*
X455462Y139775D01*
X455203Y140043D01*
X455100Y140350D01*
X455203Y140657D01*
X455462Y140925D01*
X455823Y141040D01*
X456185Y140963D01*
X456443Y140772D01*
X456547Y140542D01*
Y140158D01*
X456702Y139813D01*
X457012Y139583D01*
X457373Y139507D01*
X457735Y139583D01*
X457993Y139775D01*
X458148Y140082D01*
X458200Y140350D01*
G01Y143373D02*
X457528Y143450D01*
X456960Y143565D01*
X456443Y143718D01*
X455875Y143910D01*
X455100Y144217D01*
Y142683D01*
G01X446604Y154138D02*
Y144690D01*
G01X454211Y151368D02*
Y148168D01*
G01X448011D02*
Y151368D01*
G01X454211Y148168D02*
X448011D01*
G01Y144168D02*
Y147368D01*
G01X454211Y144168D02*
X448011D01*
G01X454211Y147368D02*
Y144168D01*
G01X448011Y147368D02*
X454211D01*
G01X444549Y142847D02*
Y139647D01*
G01X443186Y154138D02*
X446604D01*
G01X448011Y151368D02*
X454211D01*
G01X445143Y305321D02*
Y308421D01*
G01X446753D02*
Y305321D01*
G01Y306871D02*
X445143D01*
G01X449508Y305321D02*
Y308421D01*
X448090Y306199D01*
X450006D01*
G01X451496Y305683D02*
X451765Y305424D01*
X452071Y305321D01*
X452378Y305424D01*
X452646Y305734D01*
X452838Y306199D01*
X452915Y306664D01*
Y307233D01*
X452838Y307698D01*
X452646Y308111D01*
X452416Y308318D01*
X452148Y308421D01*
X451841Y308318D01*
X451611Y308111D01*
X451458Y307801D01*
X451381Y307388D01*
X451458Y307026D01*
X451650Y306664D01*
X451880Y306458D01*
X452148Y306406D01*
X452455Y306509D01*
X452685Y306768D01*
X452915Y307233D01*
G01X451997Y326685D02*
X456423D01*
G01X451997Y326285D02*
X456423D01*
G01X457259Y329885D02*
Y327619D01*
G01Y323085D02*
Y325168D01*
G01X451059Y329885D02*
Y327807D01*
G01Y323085D02*
Y325049D01*
G01X457259Y323085D02*
X451059D01*
G01X457259Y337759D02*
Y335467D01*
G01Y330959D02*
Y333006D01*
G01X451949Y334159D02*
X456422D01*
G01X451949Y334559D02*
X456422D01*
G01X451059Y337759D02*
Y335716D01*
G01Y330959D02*
Y333096D01*
G01X457259Y345633D02*
Y343435D01*
G01Y338833D02*
Y340884D01*
G01X452007Y342033D02*
X456363D01*
G01X452007Y342433D02*
X456363D01*
G01X451059Y345633D02*
Y343583D01*
G01Y338833D02*
Y340964D01*
G01Y329885D02*
X457259D01*
G01Y338833D02*
X451059D01*
G01Y337759D02*
X457259D01*
G01Y330959D02*
X451059D01*
G01X457259Y353507D02*
Y351363D01*
G01Y346707D02*
Y348843D01*
G01X451927Y349907D02*
X456134D01*
G01X451927Y350307D02*
X456134D01*
G01X451059Y353507D02*
Y351383D01*
G01Y346707D02*
Y348952D01*
G01Y345633D02*
X457259D01*
G01X451059Y353507D02*
X457259D01*
G01Y346707D02*
X451059D01*
G01X445273Y426201D02*
Y423001D01*
G01Y429701D02*
Y426501D01*
G01Y436701D02*
Y433501D01*
G01Y444701D02*
Y441501D01*
G01Y440701D02*
Y437501D01*
G01Y433201D02*
Y430001D01*
G01Y448701D02*
Y445501D01*
G01Y454201D02*
Y451001D01*
G01X452019Y466409D02*
X458219D01*
G01X452019Y463209D02*
Y466409D01*
G01X458219Y463209D02*
X452019D01*
G01Y471209D02*
Y474409D01*
G01X458219Y471209D02*
X452019D01*
G01Y467209D02*
Y470409D01*
G01X458219Y467209D02*
X452019D01*
G01Y470409D02*
X458219D01*
G01X452019Y474409D02*
X458219D01*
G01X445831Y488131D02*
Y491231D01*
X446751D01*
X447058Y491076D01*
X447288Y490714D01*
X447365Y490301D01*
X447288Y489888D01*
X447096Y489578D01*
X446751Y489423D01*
X445831D01*
G01X448855Y491231D02*
Y489009D01*
X449008Y488544D01*
X449315Y488234D01*
X449698Y488131D01*
X450081Y488234D01*
X450388Y488544D01*
X450541Y489009D01*
Y491231D01*
G01X452070Y490714D02*
X452300Y491024D01*
X452568Y491179D01*
X452875Y491231D01*
X453258Y491128D01*
X453526Y490869D01*
X453603Y490559D01*
X453565Y490249D01*
X453411Y489991D01*
X452645Y489474D01*
X452300Y489113D01*
X452070Y488596D01*
X451993Y488131D01*
X453603D01*
G01X455898D02*
Y491231D01*
X455438Y490611D01*
G01Y488131D02*
X456358D01*
G01X449590Y518536D02*
Y512536D01*
G01X447540Y510599D02*
Y507399D01*
G01X451404Y530263D02*
X458531D01*
G01X455531Y551917D02*
X451404D01*
G01X458531Y548917D02*
X455531Y551917D01*
G01X447737Y622056D02*
Y618856D01*
G01X450488Y619558D02*
Y622658D01*
X451408D01*
X451715Y622503D01*
X451945Y622141D01*
X452022Y621728D01*
X451945Y621315D01*
X451753Y621005D01*
X451408Y620850D01*
X450488D01*
G01X453512Y622658D02*
Y620436D01*
X453665Y619971D01*
X453972Y619661D01*
X454355Y619558D01*
X454738Y619661D01*
X455045Y619971D01*
X455198Y620436D01*
Y622658D01*
G01X456612Y620023D02*
X456842Y619765D01*
X457110Y619610D01*
X457455Y619558D01*
X457800Y619661D01*
X458068Y619868D01*
X458260Y620230D01*
X458298Y620643D01*
X458222Y621056D01*
X458030Y621315D01*
X457762Y621521D01*
X457493Y621573D01*
X457225Y621521D01*
X456880Y621315D01*
X456995Y622658D01*
X458030D01*
G01X448145Y630160D02*
X451345D01*
G01X448145Y623960D02*
Y630160D01*
G01X451345Y623960D02*
X448145D01*
G01X451345Y630160D02*
Y623960D01*
G01X448877Y632679D02*
Y635879D01*
G01X455077Y632679D02*
X448877D01*
G01X455077Y635879D02*
Y632679D01*
G01X448877Y635879D02*
X455077D01*
G01X446379Y632356D02*
X443179D01*
G01X446379Y638556D02*
Y632356D01*
G01X443179D02*
Y638556D01*
G01X444145Y630160D02*
X447345D01*
G01X444145Y623960D02*
Y630160D01*
G01X447345Y623960D02*
X444145D01*
G01X447345Y630160D02*
Y623960D01*
G01X447726Y657538D02*
Y651538D01*
G01Y650730D02*
Y644730D01*
G01X441908Y639276D02*
Y642476D01*
G01X448108Y639276D02*
X441908D01*
G01X448108Y642476D02*
Y639276D01*
G01X441908Y642476D02*
X448108D01*
G01X455077Y639879D02*
Y636679D01*
G01X448877Y639879D02*
X455077D01*
G01X448877Y636679D02*
Y639879D01*
G01X455077Y636679D02*
X448877D01*
G01X443179Y638556D02*
X446379D01*
G01X448872Y640988D02*
Y644188D01*
G01X455072Y640988D02*
X448872D01*
G01X455072Y644188D02*
Y640988D01*
G01X448872Y644188D02*
X455072D01*
G01X467242Y659652D02*
X445407D01*
G01X447600Y689983D02*
X444500D01*
Y690903D01*
X444655Y691210D01*
X445017Y691440D01*
X445430Y691517D01*
X445843Y691440D01*
X446153Y691248D01*
X446308Y690903D01*
Y689983D01*
G01X444500Y693083D02*
X447600D01*
Y694617D01*
G01X446980Y696107D02*
X447342Y696337D01*
X447548Y696643D01*
X447600Y696988D01*
X447548Y697295D01*
X447290Y697602D01*
X446980Y697793D01*
X446670Y697832D01*
X446308Y697755D01*
X446050Y697487D01*
X445947Y697218D01*
Y696873D01*
G01Y697218D02*
X445792Y697448D01*
X445533Y697640D01*
X445223Y697717D01*
X444913Y697640D01*
X444655Y697448D01*
X444500Y697103D01*
X444552Y696758D01*
X444758Y696413D01*
G01X443194Y707557D02*
Y689841D01*
G01X467242Y686424D02*
X445407D01*
G01X446936Y712799D02*
Y709599D01*
G01X447501Y784243D02*
Y787343D01*
G01X449111D02*
Y784243D01*
G01Y785793D02*
X447501D01*
G01X450563Y784708D02*
X450793Y784450D01*
X451061Y784295D01*
X451406Y784243D01*
X451751Y784346D01*
X452019Y784553D01*
X452211Y784915D01*
X452249Y785328D01*
X452173Y785741D01*
X451981Y786000D01*
X451713Y786206D01*
X451444Y786258D01*
X451176Y786206D01*
X450831Y786000D01*
X450946Y787343D01*
X451981D01*
G01X453663Y784708D02*
X453893Y784450D01*
X454161Y784295D01*
X454506Y784243D01*
X454851Y784346D01*
X455119Y784553D01*
X455311Y784915D01*
X455349Y785328D01*
X455273Y785741D01*
X455081Y786000D01*
X454813Y786206D01*
X454544Y786258D01*
X454276Y786206D01*
X453931Y786000D01*
X454046Y787343D01*
X455081D01*
G01X448497Y927099D02*
Y891403D01*
G01X462091Y993766D02*
X450091D01*
G01D02*
Y999766D01*
G01D02*
X462091D01*
G01X454685Y1003780D02*
X460885D01*
G01X454685Y1000580D02*
Y1003780D01*
G01X460885Y1000580D02*
X454685D01*
G01Y1008780D02*
X460885D01*
G01X454685Y1005580D02*
Y1008780D01*
G01X460885Y1005580D02*
X454685D01*
G01X452185Y1013925D02*
X458385D01*
G01X452185Y1010725D02*
Y1013925D01*
G01X458385Y1010725D02*
X452185D01*
G01X443991Y1024666D02*
Y1027866D01*
G01X450191Y1024666D02*
X443991D01*
G01X450191Y1027866D02*
Y1024666D01*
G01X452185Y1017925D02*
X458385D01*
G01X452185Y1014725D02*
Y1017925D01*
G01X458385Y1014725D02*
X452185D01*
G01X450191Y1021166D02*
X443991D01*
Y1024366D01*
X450191D01*
Y1021166D01*
G01X452491Y1026366D02*
X458691D01*
Y1023166D01*
X452491D01*
Y1026366D01*
G01X443991Y1027866D02*
X450191D01*
G01Y1035866D02*
Y1032666D01*
G01X443991Y1035866D02*
X450191D01*
G01X443991Y1032666D02*
Y1035866D01*
G01X450191Y1032666D02*
X443991D01*
G01X450191Y1028666D02*
X443991D01*
Y1031866D01*
X450191D01*
Y1028666D01*
G01X457269Y1041540D02*
X451069D01*
Y1044740D01*
X457269D01*
Y1041540D01*
G01X457192Y1045447D02*
X450992D01*
Y1048647D01*
X457192D01*
Y1045447D01*
G01X467546Y1056313D02*
X457860D01*
G01D02*
Y1078148D01*
G01X441944Y1056313D02*
X451630D01*
G01D02*
Y1078148D01*
G01X449244Y1096088D02*
Y1090088D01*
G01X457860Y1078148D02*
X462797Y1083085D01*
G01X451630Y1078148D02*
X446693Y1083085D01*
G01D02*
X441944D01*
G01X444396Y1107230D02*
Y1101030D01*
G01X445918Y1100426D02*
Y1097226D01*
G01X444983Y1107230D02*
X448183D01*
G01X444983Y1101030D02*
Y1107230D01*
G01X448183Y1101030D02*
X444983D01*
G01X448183Y1107230D02*
Y1101030D01*
G01X456260Y1103442D02*
Y1097242D01*
X453060D01*
Y1103442D01*
X456260D01*
G01X459487Y1136752D02*
X453489D01*
G01X448864Y1213533D02*
Y1177793D01*
G01X448865Y1176643D02*
X448861Y1178152D01*
G01X453489Y1174548D02*
X459487D01*
G01X450864Y1189471D02*
Y1201471D01*
G01X456864Y1189471D02*
X450864D01*
G01X456864Y1201471D02*
Y1189471D01*
G01X450864Y1201471D02*
X456864D01*
G01X458268Y1214277D02*
Y1204077D01*
X453668D01*
Y1214277D01*
X458268D01*
G01X453171Y1215076D02*
Y1228404D01*
G01X457625Y1222588D02*
Y1216388D01*
X454425D01*
Y1222588D01*
X457625D01*
G01X456720Y1229769D02*
X459820D01*
Y1231303D01*
G01Y1234096D02*
X456720D01*
X458942Y1232678D01*
Y1234594D01*
G01X459458Y1236084D02*
X459717Y1236353D01*
X459820Y1236659D01*
X459717Y1236966D01*
X459407Y1237234D01*
X458942Y1237426D01*
X458477Y1237503D01*
X457908D01*
X457443Y1237426D01*
X457030Y1237234D01*
X456823Y1237004D01*
X456720Y1236736D01*
X456823Y1236429D01*
X457030Y1236199D01*
X457340Y1236046D01*
X457753Y1235969D01*
X458115Y1236046D01*
X458477Y1236238D01*
X458683Y1236468D01*
X458735Y1236736D01*
X458632Y1237043D01*
X458373Y1237273D01*
X457908Y1237503D01*
G01X454463Y1239176D02*
Y1230276D01*
G01X454239Y1245217D02*
Y1249817D01*
G01X464439Y1245217D02*
X454239D01*
G01Y1249817D02*
X464439D01*
G01X453171Y1240638D02*
Y1254376D01*
G01X454019Y1250895D02*
Y1257095D01*
X457219D01*
Y1250895D01*
X454019D01*
G01X453292Y1257971D02*
Y1268171D01*
X457892D01*
Y1257971D01*
X453292D01*
G01X456953Y1422407D02*
X456393Y1422782D01*
X455740Y1423032D01*
X454993D01*
X454153Y1422657D01*
X453500Y1422032D01*
X453033Y1421282D01*
X452660Y1420032D01*
X452567Y1418907D01*
X452753Y1417782D01*
X453033Y1417032D01*
X453593Y1416282D01*
X454247Y1415782D01*
X454900Y1415532D01*
X455553D01*
X456207Y1415782D01*
X456767Y1416157D01*
X457233Y1416657D01*
G01X460533Y1415532D02*
Y1423032D01*
X462773D01*
X463520Y1422657D01*
X464080Y1421782D01*
X464267Y1420782D01*
X464080Y1419782D01*
X463613Y1419032D01*
X462773Y1418657D01*
X460533D01*
G01X467847Y1423032D02*
Y1417657D01*
X468220Y1416532D01*
X468967Y1415782D01*
X469900Y1415532D01*
X470833Y1415782D01*
X471580Y1416532D01*
X471953Y1417657D01*
Y1423032D01*
G01X474600Y1413032D02*
X480200D01*
G01X483127Y1415532D02*
Y1423032D01*
X486673D01*
G01X485367Y1419407D02*
X483127D01*
G01X451418Y1677520D02*
Y1441167D01*
G01Y1436969D02*
X540788D01*
G01X451418Y1647993D02*
X540788D01*
G01Y1677520D02*
X451418D01*
G01X465498Y-513835D02*
Y-505835D01*
X469298D01*
G01X467898Y-509702D02*
X465498D01*
G01X460987Y118151D02*
Y111951D01*
G01X472707Y109424D02*
X475907D01*
G01X472707Y103224D02*
Y109424D01*
G01X475907Y103224D02*
X472707D01*
G01X468707Y109424D02*
X471907D01*
G01X468707Y103224D02*
Y109424D01*
G01X471907Y103224D02*
X468707D01*
G01X471907Y109424D02*
Y103224D01*
G01X464707Y109424D02*
X467907D01*
G01X464707Y103224D02*
Y109424D01*
G01X467907Y103224D02*
X464707D01*
G01X467907Y109424D02*
Y103224D01*
G01X463161Y111734D02*
Y123508D01*
G01X472923Y111734D02*
X463161D01*
G01X472923Y123508D02*
Y111734D01*
G01X473932Y126223D02*
X470732D01*
G01X473932Y132423D02*
Y126223D01*
G01X470732Y132423D02*
X473932D01*
G01X470732Y126223D02*
Y132423D01*
G01X465932Y126223D02*
X462732D01*
G01X465932Y132423D02*
Y126223D01*
G01X462732Y132423D02*
X465932D01*
G01X462732Y126223D02*
Y132423D01*
G01X466732D02*
X469932D01*
G01X466732Y126223D02*
Y132423D01*
G01X469932Y126223D02*
X466732D01*
G01X469932Y132423D02*
Y126223D01*
G01X463161Y123508D02*
X472923D01*
G01X463121Y146229D02*
X459921D01*
G01X463121Y152429D02*
Y146229D01*
G01X459921D02*
Y152429D01*
G01X461611Y144395D02*
Y135095D01*
G01X472211Y144395D02*
X461611D01*
G01X472211Y134995D02*
Y144395D01*
G01X461611Y134995D02*
X472211D01*
G01X459921Y152429D02*
X463121D01*
G01X459921Y159540D02*
X463121D01*
G01X459921Y153340D02*
Y159540D01*
G01X463121Y153340D02*
X459921D01*
G01X463121Y159540D02*
Y153340D01*
G01X469834Y149950D02*
Y165304D01*
G01X482512Y149950D02*
X469834D01*
G01X470031Y165304D02*
X482512D01*
G01X466383Y179600D02*
Y182700D01*
X467303D01*
X467610Y182545D01*
X467840Y182183D01*
X467917Y181770D01*
X467840Y181357D01*
X467648Y181047D01*
X467303Y180892D01*
X466383D01*
G01X469407Y179600D02*
Y182700D01*
X470173D01*
X470480Y182545D01*
X470710Y182338D01*
X470902Y182028D01*
X471055Y181667D01*
X471093Y181150D01*
X471055Y180633D01*
X470902Y180272D01*
X470710Y179962D01*
X470480Y179755D01*
X470173Y179600D01*
X469407D01*
G01X472622Y180892D02*
X472890Y181253D01*
X473120Y181460D01*
X473427Y181563D01*
X473695Y181460D01*
X473887Y181253D01*
X474040Y180943D01*
X474078Y180582D01*
X474040Y180272D01*
X473887Y179962D01*
X473657Y179703D01*
X473388Y179600D01*
X473082Y179703D01*
X472813Y180013D01*
X472660Y180478D01*
X472622Y180995D01*
X472698Y181667D01*
X472813Y182028D01*
X473005Y182390D01*
X473273Y182648D01*
X473542Y182700D01*
X473810Y182597D01*
X474002Y182338D01*
G01X476450Y179600D02*
Y182700D01*
X475990Y182080D01*
G01Y179600D02*
X476910D01*
G01X462715Y189435D02*
X464955D01*
G01X463742Y191060D02*
Y187810D01*
G01X466356Y195583D02*
X495915D01*
G01X466356Y184087D02*
Y195583D01*
G01X495915Y184087D02*
X466356D01*
G01X485332Y197645D02*
X473332D01*
G01D02*
Y203645D01*
G01D02*
X485332D01*
G01X466509Y204506D02*
Y216506D01*
G01X472509Y204506D02*
X466509D01*
G01X472509Y216506D02*
Y204506D01*
G01X473309Y208306D02*
Y214506D01*
G01X476509Y208306D02*
X473309D01*
G01X466509Y216506D02*
X472509D01*
G01X473309Y214506D02*
X476509D01*
G01X473675Y245521D02*
Y254969D01*
G01X484511Y245521D02*
X473675D01*
G01X477251Y231334D02*
X474051D01*
G01Y237534D02*
X477251D01*
G01X474051Y231334D02*
Y237534D01*
G01X465307Y246771D02*
Y249971D01*
G01X471507Y246771D02*
X465307D01*
G01X471507Y249971D02*
Y246771D01*
G01X469277Y243678D02*
X475477D01*
G01X469277Y240478D02*
Y243678D01*
G01X475477Y240478D02*
X469277D01*
G01X473675Y254969D02*
X477093D01*
G01X465307Y249971D02*
X471507D01*
G01Y253971D02*
Y250771D01*
G01X465307Y253971D02*
X471507D01*
G01X465307Y250771D02*
Y253971D01*
G01X471507Y250771D02*
X465307D01*
G01X473707Y346395D02*
Y349595D01*
G01X479907Y346395D02*
X473707D01*
G01Y349595D02*
X479907D01*
G01X473707Y350895D02*
Y354095D01*
G01X479907Y350895D02*
X473707D01*
G01Y354095D02*
X479907D01*
G01X473810Y358489D02*
Y361689D01*
G01X480010Y358489D02*
X473810D01*
G01Y361689D02*
X480010D01*
G01X473810Y362989D02*
Y366189D01*
G01X480010Y362989D02*
X473810D01*
G01Y366189D02*
X480010D01*
G01X473810Y367489D02*
Y370689D01*
G01X480010Y367489D02*
X473810D01*
G01Y370689D02*
X480010D01*
G01X473810Y371989D02*
Y375189D01*
G01X480010Y371989D02*
X473810D01*
G01Y375189D02*
X480010D01*
G01X473810Y376489D02*
Y379689D01*
G01X480010Y376489D02*
X473810D01*
G01Y379689D02*
X480010D01*
G01X473810Y380989D02*
Y384189D01*
G01X480010Y380989D02*
X473810D01*
G01Y384189D02*
X480010D01*
G01X473810Y385489D02*
Y388689D01*
G01X480010Y385489D02*
X473810D01*
G01Y388689D02*
X480010D01*
G01X473810Y389989D02*
Y393189D01*
G01X480010Y389989D02*
X473810D01*
G01Y393189D02*
X480010D01*
G01X458219Y466409D02*
Y463209D01*
G01Y474409D02*
Y471209D01*
G01X466291Y460264D02*
Y463464D01*
G01X472491Y460264D02*
X466291D01*
G01X472491Y463464D02*
Y460264D01*
G01X466291Y463464D02*
X472491D01*
G01X458219Y470409D02*
Y467209D01*
G01X474183Y462600D02*
Y465700D01*
X475103D01*
X475410Y465545D01*
X475640Y465183D01*
X475717Y464770D01*
X475640Y464357D01*
X475448Y464047D01*
X475103Y463892D01*
X474183D01*
G01X477207Y465700D02*
Y463478D01*
X477360Y463013D01*
X477667Y462703D01*
X478050Y462600D01*
X478433Y462703D01*
X478740Y463013D01*
X478893Y463478D01*
Y465700D01*
G01X481073Y462600D02*
X481150Y463272D01*
X481265Y463840D01*
X481418Y464357D01*
X481610Y464925D01*
X481917Y465700D01*
X480383D01*
G01X484250D02*
X483943Y465597D01*
X483713Y465338D01*
X483560Y465028D01*
X483445Y464615D01*
X483407Y464150D01*
X483445Y463685D01*
X483560Y463272D01*
X483713Y462962D01*
X483943Y462703D01*
X484250Y462600D01*
X484557Y462703D01*
X484787Y462962D01*
X484940Y463272D01*
X485055Y463685D01*
X485093Y464150D01*
X485055Y464615D01*
X484940Y465028D01*
X484787Y465338D01*
X484557Y465597D01*
X484250Y465700D01*
G01X472708Y465638D02*
X460934D01*
G01X472708Y475400D02*
Y465638D01*
G01X460934D02*
Y475400D01*
G01X462270Y483801D02*
X474270D01*
G01X462270Y477801D02*
Y483801D01*
G01X474270Y477801D02*
X462270D01*
G01X461303Y490069D02*
Y493269D01*
G01X467503Y490069D02*
X461303D01*
G01X467503Y493269D02*
Y490069D01*
G01X460934Y475400D02*
X472708D01*
G01X461303Y493269D02*
X467503D01*
G01X461303Y506069D02*
Y509269D01*
G01X467503Y506069D02*
X461303D01*
G01X467503Y509269D02*
Y506069D01*
G01X461303Y498069D02*
Y501269D01*
G01X467503Y498069D02*
X461303D01*
G01X467503Y501269D02*
Y498069D01*
G01X461303Y501269D02*
X467503D01*
G01X461303Y502069D02*
Y505269D01*
G01X467503Y502069D02*
X461303D01*
G01X467503Y505269D02*
Y502069D01*
G01X461303Y505269D02*
X467503D01*
G01Y497269D02*
Y494069D01*
G01X461303Y497269D02*
X467503D01*
G01X461303Y494069D02*
Y497269D01*
G01X467503Y494069D02*
X461303D01*
G01Y509269D02*
X467503D01*
G01X461303Y511069D02*
Y514269D01*
G01X467503Y511069D02*
X461303D01*
G01X467503Y514269D02*
Y511069D01*
G01X461303Y514269D02*
X467503D01*
G01Y518209D02*
Y515009D01*
G01X461303Y518209D02*
X467503D01*
G01X461303Y515009D02*
Y518209D01*
G01X467503Y515009D02*
X461303D01*
G01X467236Y538497D02*
Y544697D01*
G01X470436Y538497D02*
X467236D01*
G01X470436Y544697D02*
Y538497D01*
G01X458531Y530263D02*
Y548917D01*
G01X467236Y544697D02*
X470436D01*
G01X461201Y617601D02*
Y559001D01*
G01X467242Y669338D02*
Y659652D01*
G01Y676738D02*
Y686424D01*
G01X462091Y999766D02*
Y993766D01*
G01X460885Y1003780D02*
Y1000580D01*
G01Y1008780D02*
Y1005580D01*
G01X464428Y1005823D02*
X461928D01*
X463720Y1004836D01*
Y1006170D01*
G01X461928Y1007703D02*
X462011Y1007490D01*
X462220Y1007330D01*
X462470Y1007223D01*
X462803Y1007143D01*
X463178Y1007116D01*
X463553Y1007143D01*
X463886Y1007223D01*
X464136Y1007330D01*
X464345Y1007490D01*
X464428Y1007703D01*
X464345Y1007916D01*
X464136Y1008076D01*
X463886Y1008183D01*
X463553Y1008263D01*
X463178Y1008290D01*
X462803Y1008263D01*
X462470Y1008183D01*
X462220Y1008076D01*
X462011Y1007916D01*
X461928Y1007703D01*
G01X465652Y1007460D02*
Y1009366D01*
G01X464195Y1010203D02*
X461195D01*
G01X467558Y1007460D02*
X465652D01*
G01X462691Y1023166D02*
X459491D01*
G01X462691Y1029366D02*
Y1023166D01*
G01X459491D02*
Y1029366D01*
G01X458385Y1013925D02*
Y1010725D01*
G01Y1017925D02*
Y1014725D01*
G01X462740Y1019265D02*
X463032Y1019425D01*
X463198Y1019639D01*
X463240Y1019879D01*
X463198Y1020092D01*
X462990Y1020305D01*
X462740Y1020439D01*
X462490Y1020465D01*
X462198Y1020412D01*
X461990Y1020225D01*
X461907Y1020039D01*
Y1019799D01*
G01Y1020039D02*
X461782Y1020199D01*
X461573Y1020332D01*
X461323Y1020385D01*
X461073Y1020332D01*
X460865Y1020199D01*
X460740Y1019959D01*
X460782Y1019719D01*
X460948Y1019479D01*
G01X463240Y1022052D02*
X460740D01*
X461240Y1021732D01*
G01X463240D02*
Y1022372D01*
G01X462745Y1018003D02*
X464245D01*
G01X465652Y1025240D02*
Y1027146D01*
G01X459491Y1029366D02*
X462691D01*
G01X463508Y1029370D02*
X463668Y1029078D01*
X463882Y1028912D01*
X464122Y1028870D01*
X464335Y1028912D01*
X464548Y1029120D01*
X464682Y1029370D01*
X464708Y1029620D01*
X464655Y1029912D01*
X464468Y1030120D01*
X464282Y1030203D01*
X464042D01*
G01X464282D02*
X464442Y1030328D01*
X464575Y1030537D01*
X464628Y1030787D01*
X464575Y1031037D01*
X464442Y1031245D01*
X464202Y1031370D01*
X463962Y1031328D01*
X463722Y1031162D01*
G01X466295Y1031370D02*
X466082Y1031287D01*
X465922Y1031078D01*
X465815Y1030828D01*
X465735Y1030495D01*
X465708Y1030120D01*
X465735Y1029745D01*
X465815Y1029412D01*
X465922Y1029162D01*
X466082Y1028953D01*
X466295Y1028870D01*
X466508Y1028953D01*
X466668Y1029162D01*
X466775Y1029412D01*
X466855Y1029745D01*
X466882Y1030120D01*
X466855Y1030495D01*
X466775Y1030828D01*
X466668Y1031078D01*
X466508Y1031287D01*
X466295Y1031370D01*
G01X468495Y1028603D02*
Y1031603D01*
G01X465652Y1027146D02*
X467558D01*
G01X473277Y1090068D02*
X461277D01*
G01X473277Y1096068D02*
Y1090068D01*
G01X461277D02*
Y1096068D01*
G01X462797Y1083085D02*
X467546D01*
G01X461277Y1096068D02*
X473277D01*
G01X473177Y1097226D02*
Y1100426D01*
G01X479377Y1097226D02*
X473177D01*
G01Y1100426D02*
X479377D01*
G01X458441Y1103442D02*
X461641D01*
G01X458441Y1097242D02*
Y1103442D01*
G01X461641Y1097242D02*
X458441D01*
G01X461641Y1103442D02*
Y1097242D01*
G01X465013Y1119296D02*
X461813D01*
G01X465013Y1125496D02*
Y1119296D01*
G01X461813D02*
Y1125496D01*
G01Y1114996D02*
X465013D01*
G01X461813Y1108796D02*
Y1114996D01*
G01X465013Y1108796D02*
X461813D01*
G01X465013Y1114996D02*
Y1108796D01*
G01X470346Y1118297D02*
X467146D01*
G01X470346Y1124497D02*
Y1118297D01*
G01X467146D02*
Y1124497D01*
G01X472955Y1109839D02*
Y1112030D01*
G01X473688Y1109839D02*
X472955D01*
G01X459182Y1124250D02*
Y1122552D01*
G01Y1109839D02*
X458174D01*
G01X459182Y1111693D02*
Y1109839D01*
G01X461813Y1125496D02*
X465013D01*
G01X467146Y1124497D02*
X470346D01*
G01X472955Y1133461D02*
X473748D01*
G01X472955Y1130861D02*
Y1133461D01*
G01X459182D02*
Y1130861D01*
G01X458389Y1133461D02*
X459182D01*
G01X478048Y1136752D02*
X472050D01*
G01D02*
Y1174548D01*
G01X459487D02*
Y1136752D01*
G01X467250Y1153659D02*
Y1159859D01*
G01X470450Y1153659D02*
X467250D01*
G01X470450Y1159859D02*
Y1153659D01*
G01X461087D02*
Y1159859D01*
G01X464287Y1153659D02*
X461087D01*
G01X464287Y1159859D02*
Y1153659D01*
G01X467250Y1159859D02*
X470450D01*
G01X461087D02*
X464287D01*
G01X475683Y1179424D02*
Y1181664D01*
G01X474058Y1180451D02*
X477308D01*
G01X472050Y1174548D02*
X478048D01*
G01X470206Y1189471D02*
Y1201471D01*
G01X476206Y1189471D02*
X470206D01*
G01Y1201471D02*
X476206D01*
G01X463619Y1214276D02*
Y1204076D01*
X459019D01*
Y1214276D01*
X463619D01*
G01X474178Y1215076D02*
X491880D01*
G01X474178Y1228188D02*
Y1215076D01*
G01X462919Y1222588D02*
Y1216388D01*
X459719D01*
Y1222588D01*
X462919D01*
G01X475970Y1210224D02*
Y1212650D01*
G01X467533Y1230497D02*
X470633D01*
Y1232031D01*
G01X468050Y1233636D02*
X467740Y1233866D01*
X467585Y1234134D01*
X467533Y1234441D01*
X467636Y1234824D01*
X467895Y1235092D01*
X468205Y1235169D01*
X468515Y1235131D01*
X468773Y1234977D01*
X469290Y1234211D01*
X469651Y1233866D01*
X470168Y1233636D01*
X470633Y1233559D01*
Y1235169D01*
G01Y1237464D02*
X470581Y1237732D01*
X470426Y1238039D01*
X470168Y1238231D01*
X469806Y1238307D01*
X469445Y1238231D01*
X469135Y1238001D01*
X468980Y1237656D01*
Y1237272D01*
X468876Y1237042D01*
X468618Y1236851D01*
X468256Y1236774D01*
X467895Y1236889D01*
X467636Y1237157D01*
X467533Y1237464D01*
X467636Y1237771D01*
X467895Y1238039D01*
X468256Y1238154D01*
X468618Y1238077D01*
X468876Y1237886D01*
X468980Y1237656D01*
Y1237272D01*
X469135Y1236927D01*
X469445Y1236697D01*
X469806Y1236621D01*
X470168Y1236697D01*
X470426Y1236889D01*
X470581Y1237196D01*
X470633Y1237464D01*
G01X472886Y1230276D02*
Y1239176D01*
G01X493172Y1230276D02*
X472886D01*
G01X464439Y1249817D02*
Y1245217D01*
G01X474178Y1254376D02*
Y1240854D01*
G01X458974Y1250896D02*
Y1257096D01*
X462174D01*
Y1250896D01*
X458974D01*
G01X472886Y1239176D02*
X493172D01*
G01X491880Y1254376D02*
X474178D01*
G01X458801Y1257971D02*
Y1268171D01*
X463401D01*
Y1257971D01*
X458801D01*
G01X484585Y96067D02*
Y99267D01*
G01X490785Y96067D02*
X484585D01*
G01Y99267D02*
X490785D01*
G01X481324Y122172D02*
Y110172D01*
G01X475324D02*
Y122172D01*
G01X481324Y110172D02*
X475324D01*
G01X486601Y108095D02*
Y104895D01*
G01X480401Y108095D02*
X486601D01*
G01X480401Y104895D02*
Y108095D01*
G01X486601Y104895D02*
X480401D01*
G01X475907Y109424D02*
Y103224D01*
G01X480401Y100895D02*
Y104095D01*
G01X486601Y100895D02*
X480401D01*
G01X486601Y104095D02*
Y100895D01*
G01X480401Y104095D02*
X486601D01*
G01X487458Y108086D02*
X490658D01*
G01X487458Y101886D02*
Y108086D01*
G01X490658Y101886D02*
X487458D01*
G01X475324Y122172D02*
X481324D01*
G01X477986Y126228D02*
X474786D01*
G01X477986Y132428D02*
Y126228D01*
G01X474786Y132428D02*
X477986D01*
G01X474786Y126228D02*
Y132428D01*
G01X478165Y141337D02*
X474965D01*
G01X478165Y147537D02*
Y141337D01*
G01X474965Y147537D02*
X478165D01*
G01X474965Y141337D02*
Y147537D01*
G01X481376Y148437D02*
X484576D01*
G01X481376Y142237D02*
Y148437D01*
G01X484576Y142237D02*
X481376D01*
G01X484576Y148437D02*
Y142237D01*
G01X474830Y133238D02*
Y136438D01*
G01X481030Y133238D02*
X474830D01*
G01X481030Y136438D02*
Y133238D01*
G01X474830Y136438D02*
X481030D01*
G01X474830Y137238D02*
Y140438D01*
G01X481030Y137238D02*
X474830D01*
G01X481030Y140438D02*
Y137238D01*
G01X474830Y140438D02*
X481030D01*
G01X483700Y153107D02*
X485922D01*
X486387Y153260D01*
X486697Y153567D01*
X486800Y153950D01*
X486697Y154333D01*
X486387Y154640D01*
X485922Y154793D01*
X483700D01*
G01X486180Y156207D02*
X486542Y156437D01*
X486748Y156743D01*
X486800Y157088D01*
X486748Y157395D01*
X486490Y157702D01*
X486180Y157893D01*
X485870Y157932D01*
X485508Y157855D01*
X485250Y157587D01*
X485147Y157318D01*
Y156973D01*
G01Y157318D02*
X484992Y157548D01*
X484733Y157740D01*
X484423Y157817D01*
X484113Y157740D01*
X483855Y157548D01*
X483700Y157203D01*
X483752Y156858D01*
X483958Y156513D01*
G01X485508Y159422D02*
X485147Y159690D01*
X484940Y159920D01*
X484837Y160227D01*
X484940Y160495D01*
X485147Y160687D01*
X485457Y160840D01*
X485818Y160878D01*
X486128Y160840D01*
X486438Y160687D01*
X486697Y160457D01*
X486800Y160188D01*
X486697Y159882D01*
X486387Y159613D01*
X485922Y159460D01*
X485405Y159422D01*
X484733Y159498D01*
X484372Y159613D01*
X484010Y159805D01*
X483752Y160073D01*
X483700Y160342D01*
X483803Y160610D01*
X484062Y160802D01*
G01X486800Y163173D02*
X486128Y163250D01*
X485560Y163365D01*
X485043Y163518D01*
X484475Y163710D01*
X483700Y164017D01*
Y162483D01*
G01X482512Y165304D02*
Y149950D01*
G01X485332Y203645D02*
Y197645D01*
G01X483285Y208464D02*
Y205264D01*
G01X477085Y208464D02*
X483285D01*
G01X477085Y205264D02*
Y208464D01*
G01X483285Y205264D02*
X477085D01*
G01X476509Y214506D02*
Y208306D01*
G01X478115Y226801D02*
X490319D01*
Y211497D01*
X478115D01*
Y226801D01*
G01X484511Y254969D02*
Y245521D01*
G01X482778Y231446D02*
X479578D01*
G01X482778Y237646D02*
Y231446D01*
G01X479578Y237646D02*
X482778D01*
G01X479578Y231446D02*
Y237646D01*
G01X477251Y237534D02*
Y231334D01*
G01X486653Y231434D02*
X483453D01*
G01X486653Y237634D02*
Y231434D01*
G01X483453Y237634D02*
X486653D01*
G01X483453Y231434D02*
Y237634D01*
G01X487688Y237659D02*
X490888D01*
G01X487688Y231459D02*
Y237659D01*
G01X490888Y231459D02*
X487688D01*
G01X486314Y240081D02*
Y243281D01*
G01X492514Y240081D02*
X486314D01*
G01Y243281D02*
X492514D01*
G01X482456Y243678D02*
Y240478D01*
G01X476256Y243678D02*
X482456D01*
G01X476256Y240478D02*
Y243678D01*
G01X482456Y240478D02*
X476256D01*
G01X475477Y243678D02*
Y240478D01*
G01X484750Y256000D02*
X484443Y256052D01*
X484175Y256258D01*
X483945Y256568D01*
X483792Y256930D01*
X483715Y257343D01*
Y257757D01*
X483792Y258170D01*
X483945Y258532D01*
X484175Y258842D01*
X484443Y259048D01*
X484750Y259100D01*
X485057Y259048D01*
X485325Y258842D01*
X485555Y258532D01*
X485708Y258170D01*
X485785Y257757D01*
Y257343D01*
X485708Y256930D01*
X485555Y256568D01*
X485325Y256258D01*
X485057Y256052D01*
X484750Y256000D01*
G01X485057Y256827D02*
X485517Y256000D01*
G01X487122Y258583D02*
X487352Y258893D01*
X487620Y259048D01*
X487927Y259100D01*
X488310Y258997D01*
X488578Y258738D01*
X488655Y258428D01*
X488617Y258118D01*
X488463Y257860D01*
X487697Y257343D01*
X487352Y256982D01*
X487122Y256465D01*
X487045Y256000D01*
X488655D01*
G01X490950Y259100D02*
X490643Y258997D01*
X490413Y258738D01*
X490260Y258428D01*
X490145Y258015D01*
X490107Y257550D01*
X490145Y257085D01*
X490260Y256672D01*
X490413Y256362D01*
X490643Y256103D01*
X490950Y256000D01*
X491257Y256103D01*
X491487Y256362D01*
X491640Y256672D01*
X491755Y257085D01*
X491793Y257550D01*
X491755Y258015D01*
X491640Y258428D01*
X491487Y258738D01*
X491257Y258997D01*
X490950Y259100D01*
G01X494050D02*
X493743Y258997D01*
X493513Y258738D01*
X493360Y258428D01*
X493245Y258015D01*
X493207Y257550D01*
X493245Y257085D01*
X493360Y256672D01*
X493513Y256362D01*
X493743Y256103D01*
X494050Y256000D01*
X494357Y256103D01*
X494587Y256362D01*
X494740Y256672D01*
X494855Y257085D01*
X494893Y257550D01*
X494855Y258015D01*
X494740Y258428D01*
X494587Y258738D01*
X494357Y258997D01*
X494050Y259100D01*
G01X481093Y254969D02*
X484511D01*
G01X479093Y253245D02*
X481093Y254969D01*
G01X477093D02*
X479093Y253245D01*
G01X485918Y252199D02*
X492118D01*
G01X485918Y248999D02*
Y252199D01*
G01X492118Y248999D02*
X485918D01*
G01X479907Y349595D02*
Y346395D01*
G01Y354095D02*
Y350895D01*
G01X480010Y361689D02*
Y358489D01*
G01X483707Y346395D02*
Y349595D01*
G01X489907Y346395D02*
X483707D01*
G01X489907Y349595D02*
Y346395D01*
G01X483707Y349595D02*
X489907D01*
G01X483707Y350895D02*
Y354095D01*
G01X489907Y350895D02*
X483707D01*
G01X489907Y354095D02*
Y350895D01*
G01X483707Y354095D02*
X489907D01*
G01X483810Y358489D02*
Y361689D01*
G01X490010Y358489D02*
X483810D01*
G01X490010Y361689D02*
Y358489D01*
G01X480010Y366189D02*
Y362989D01*
G01Y370689D02*
Y367489D01*
G01Y375189D02*
Y371989D01*
G01Y379689D02*
Y376489D01*
G01X483810Y361689D02*
X490010D01*
G01X483810Y376489D02*
Y379689D01*
G01X490010Y376489D02*
X483810D01*
G01X490010Y379689D02*
Y376489D01*
G01X483810Y362989D02*
Y366189D01*
G01X490010Y362989D02*
X483810D01*
G01X490010Y366189D02*
Y362989D01*
G01X483810Y366189D02*
X490010D01*
G01X483810Y367489D02*
Y370689D01*
G01X490010Y367489D02*
X483810D01*
G01X490010Y370689D02*
Y367489D01*
G01X483810Y370689D02*
X490010D01*
G01X483810Y371989D02*
Y375189D01*
G01X490010Y371989D02*
X483810D01*
G01X490010Y375189D02*
Y371989D01*
G01X483810Y375189D02*
X490010D01*
G01X480010Y384189D02*
Y380989D01*
G01Y388689D02*
Y385489D01*
G01Y393189D02*
Y389989D01*
G01X483810Y379689D02*
X490010D01*
G01Y388689D02*
Y385489D01*
G01X483810Y388689D02*
X490010D01*
G01X483810Y385489D02*
Y388689D01*
G01X490010Y385489D02*
X483810D01*
G01X490010Y393189D02*
Y389989D01*
G01X483810D02*
Y393189D01*
G01X490010Y389989D02*
X483810D01*
G01Y380989D02*
Y384189D01*
G01X490010Y380989D02*
X483810D01*
G01X490010Y384189D02*
Y380989D01*
G01X483810Y384189D02*
X490010D01*
G01X483810Y393189D02*
X490010D01*
G01X490209Y422917D02*
Y419499D01*
G01X488485Y424917D02*
X490209Y422917D01*
G01Y426917D02*
X488485Y424917D01*
G01X480761Y419499D02*
Y430335D01*
G01X490209Y419499D02*
X480761D01*
G01X490085Y410817D02*
X486885D01*
G01X490085Y417017D02*
Y410817D01*
G01X486885Y417017D02*
X490085D01*
G01X486885Y410817D02*
Y417017D01*
G01X490209Y430335D02*
Y426917D01*
G01X480761Y430335D02*
X490209D01*
G01X483085Y432817D02*
X479885D01*
G01X483085Y439017D02*
Y432817D01*
G01X479885Y439017D02*
X483085D01*
G01X479885Y432817D02*
Y439017D01*
G01X483885D02*
X487085D01*
G01X483885Y432817D02*
Y439017D01*
G01X487085Y432817D02*
X483885D01*
G01X487085Y439017D02*
Y432817D01*
G01X487885Y439017D02*
X491085D01*
G01X487885Y432817D02*
Y439017D01*
G01X491085Y432817D02*
X487885D01*
G01X475018Y467184D02*
Y470384D01*
G01X481218Y467184D02*
X475018D01*
G01X481218Y470384D02*
Y467184D01*
G01X475018Y470384D02*
X481218D01*
G01X475018Y471184D02*
Y474384D01*
G01X481218Y471184D02*
X475018D01*
G01X481218Y474384D02*
Y471184D01*
G01X474270Y483801D02*
Y477801D01*
G01X475018Y475184D02*
Y478384D01*
G01X481218Y475184D02*
X475018D01*
G01X481218Y478384D02*
Y475184D01*
G01X475018Y478384D02*
X481218D01*
G01X475018Y474384D02*
X481218D01*
G01X490160Y538326D02*
Y535126D01*
G01X483960Y538326D02*
X490160D01*
G01X483960Y535126D02*
Y538326D01*
G01X490160Y535126D02*
X483960D01*
G01X490160Y533326D02*
Y530126D01*
G01X483960Y533326D02*
X490160D01*
G01X483960Y530126D02*
Y533326D01*
G01X490160Y530126D02*
X483960D01*
G01Y526126D02*
Y529326D01*
G01X490160Y526126D02*
X483960D01*
G01X490160Y529326D02*
Y526126D01*
G01X483960Y529326D02*
X490160D01*
G01Y539126D02*
X483960D01*
Y542326D01*
X490160D01*
Y539126D01*
G01X483960Y547126D02*
Y550326D01*
G01X490160Y547126D02*
X483960D01*
G01X490160Y550326D02*
Y547126D01*
G01X483960Y550326D02*
X490160D01*
G01Y546326D02*
Y543126D01*
G01X483960Y546326D02*
X490160D01*
G01X483960Y543126D02*
Y546326D01*
G01X490160Y543126D02*
X483960D01*
G01X490160Y551126D02*
X483960D01*
Y554326D01*
X490160D01*
Y551126D01*
G01X480019Y585713D02*
X482259D01*
G01X481046Y587338D02*
Y584088D01*
G01X483660Y580365D02*
Y591861D01*
G01X513219Y580365D02*
X483660D01*
G01X489178Y604111D02*
X499378D01*
G01X489178Y599511D02*
Y604111D01*
G01X499378Y599511D02*
X489178D01*
G01X483829Y593480D02*
Y596580D01*
X484749D01*
X485056Y596425D01*
X485286Y596063D01*
X485363Y595650D01*
X485286Y595237D01*
X485094Y594927D01*
X484749Y594772D01*
X483829D01*
G01X486853Y593480D02*
Y596580D01*
X487619D01*
X487926Y596425D01*
X488156Y596218D01*
X488348Y595908D01*
X488501Y595547D01*
X488539Y595030D01*
X488501Y594513D01*
X488348Y594152D01*
X488156Y593842D01*
X487926Y593635D01*
X487619Y593480D01*
X486853D01*
G01X490796D02*
X491064Y593532D01*
X491371Y593687D01*
X491563Y593945D01*
X491639Y594307D01*
X491563Y594668D01*
X491333Y594978D01*
X490988Y595133D01*
X490604D01*
X490374Y595237D01*
X490183Y595495D01*
X490106Y595857D01*
X490221Y596218D01*
X490489Y596477D01*
X490796Y596580D01*
X491103Y596477D01*
X491371Y596218D01*
X491486Y595857D01*
X491409Y595495D01*
X491218Y595237D01*
X490988Y595133D01*
X490604D01*
X490259Y594978D01*
X490029Y594668D01*
X489953Y594307D01*
X490029Y593945D01*
X490221Y593687D01*
X490528Y593532D01*
X490796Y593480D01*
G01X493168Y596063D02*
X493398Y596373D01*
X493666Y596528D01*
X493973Y596580D01*
X494356Y596477D01*
X494624Y596218D01*
X494701Y595908D01*
X494663Y595598D01*
X494509Y595340D01*
X493743Y594823D01*
X493398Y594462D01*
X493168Y593945D01*
X493091Y593480D01*
X494701D01*
G01X483660Y591861D02*
X513219D01*
G01X489178Y605011D02*
Y609611D01*
G01X499378Y605011D02*
X489178D01*
G01Y609611D02*
X499378D01*
G01X485678Y619711D02*
Y622911D01*
G01X491878Y619711D02*
X485678D01*
G01X489478Y618411D02*
X492678D01*
G01X489478Y612211D02*
Y618411D01*
G01X492678Y612211D02*
X489478D01*
G01X481678Y618411D02*
X484878D01*
G01X481678Y612211D02*
Y618411D01*
G01X484878Y612211D02*
X481678D01*
G01X484878Y618411D02*
Y612211D01*
G01X485678Y618411D02*
X488878D01*
G01X485678Y612211D02*
Y618411D01*
G01X488878Y612211D02*
X485678D01*
G01X488878Y618411D02*
Y612211D01*
G01X485678Y622911D02*
X491878D01*
G01X485678Y630911D02*
X491878D01*
G01X485678Y627711D02*
Y630911D01*
G01X491878Y627711D02*
X485678D01*
G01Y626911D02*
X491878D01*
G01X485678Y623711D02*
Y626911D01*
G01X491878Y623711D02*
X485678D01*
G01X477306Y650568D02*
X483506D01*
Y647368D01*
X477306D01*
Y650568D01*
G01X483462Y651306D02*
X477262D01*
Y654506D01*
X483462D01*
Y651306D01*
G01X482163Y667085D02*
X484385D01*
X484850Y667238D01*
X485160Y667545D01*
X485263Y667928D01*
X485160Y668311D01*
X484850Y668618D01*
X484385Y668771D01*
X482163D01*
G01X485263Y671488D02*
X482163D01*
X484385Y670070D01*
Y671986D01*
G01X484643Y673285D02*
X485005Y673515D01*
X485211Y673821D01*
X485263Y674166D01*
X485211Y674473D01*
X484953Y674780D01*
X484643Y674971D01*
X484333Y675010D01*
X483971Y674933D01*
X483713Y674665D01*
X483610Y674396D01*
Y674051D01*
G01Y674396D02*
X483455Y674626D01*
X483196Y674818D01*
X482886Y674895D01*
X482576Y674818D01*
X482318Y674626D01*
X482163Y674281D01*
X482215Y673936D01*
X482421Y673591D01*
G01X485263Y677228D02*
X485211Y677496D01*
X485056Y677803D01*
X484798Y677995D01*
X484436Y678071D01*
X484075Y677995D01*
X483765Y677765D01*
X483610Y677420D01*
Y677036D01*
X483506Y676806D01*
X483248Y676615D01*
X482886Y676538D01*
X482525Y676653D01*
X482266Y676921D01*
X482163Y677228D01*
X482266Y677535D01*
X482525Y677803D01*
X482886Y677918D01*
X483248Y677841D01*
X483506Y677650D01*
X483610Y677420D01*
Y677036D01*
X483765Y676691D01*
X484075Y676461D01*
X484436Y676385D01*
X484798Y676461D01*
X485056Y676653D01*
X485211Y676960D01*
X485263Y677228D01*
G01X486924Y660463D02*
Y674063D01*
G01X495724Y660463D02*
X486924D01*
G01X489773Y653097D02*
Y659297D01*
X492973D01*
Y653097D01*
X489773D01*
G01X486924Y674063D02*
X495724D01*
G01X487145Y675817D02*
Y682017D01*
X490345D01*
Y675817D01*
X487145D01*
G01X485897Y857677D02*
Y917913D01*
G01X534972Y857677D02*
X485897D01*
G01Y917913D02*
X584047D01*
G01X486491Y990666D02*
Y996866D01*
X489691D01*
Y990666D01*
X486491D01*
G01X477465Y989920D02*
Y993020D01*
X478385D01*
X478692Y992865D01*
X478922Y992503D01*
X478999Y992090D01*
X478922Y991677D01*
X478730Y991367D01*
X478385Y991212D01*
X477465D01*
G01X480489Y993020D02*
Y990798D01*
X480642Y990333D01*
X480949Y990023D01*
X481332Y989920D01*
X481715Y990023D01*
X482022Y990333D01*
X482175Y990798D01*
Y993020D01*
G01X483704Y991212D02*
X483972Y991573D01*
X484202Y991780D01*
X484509Y991883D01*
X484777Y991780D01*
X484969Y991573D01*
X485122Y991263D01*
X485160Y990902D01*
X485122Y990592D01*
X484969Y990282D01*
X484739Y990023D01*
X484470Y989920D01*
X484164Y990023D01*
X483895Y990333D01*
X483742Y990798D01*
X483704Y991315D01*
X483780Y991987D01*
X483895Y992348D01*
X484087Y992710D01*
X484355Y992968D01*
X484624Y993020D01*
X484892Y992917D01*
X485084Y992658D01*
G01X489528Y1007408D02*
X487028D01*
X487528Y1007088D01*
G01X489528D02*
Y1007728D01*
G01Y1009608D02*
X487028D01*
X487528Y1009288D01*
G01X489528D02*
Y1009928D01*
G01X484695Y1003975D02*
Y1006475D01*
X484375Y1005975D01*
G01Y1003975D02*
X485015D01*
G01X486895Y1006475D02*
X486682Y1006392D01*
X486522Y1006183D01*
X486415Y1005933D01*
X486335Y1005600D01*
X486308Y1005225D01*
X486335Y1004850D01*
X486415Y1004517D01*
X486522Y1004267D01*
X486682Y1004058D01*
X486895Y1003975D01*
X487108Y1004058D01*
X487268Y1004267D01*
X487375Y1004517D01*
X487455Y1004850D01*
X487482Y1005225D01*
X487455Y1005600D01*
X487375Y1005933D01*
X487268Y1006183D01*
X487108Y1006392D01*
X486895Y1006475D01*
G01X474795Y1004453D02*
Y1005953D01*
G01X482595Y1002903D02*
Y1005903D01*
G01X485338Y1007460D02*
X483442D01*
G01X485338Y1009366D02*
Y1007460D01*
G01X487743Y1020015D02*
X487493Y1020175D01*
X487368Y1020362D01*
X487326Y1020575D01*
X487409Y1020842D01*
X487618Y1021029D01*
X487868Y1021082D01*
X488118Y1021055D01*
X488326Y1020949D01*
X488743Y1020415D01*
X489034Y1020175D01*
X489451Y1020015D01*
X489826Y1019962D01*
Y1021082D01*
G01X487326Y1022722D02*
X487409Y1022509D01*
X487618Y1022349D01*
X487868Y1022242D01*
X488201Y1022162D01*
X488576Y1022135D01*
X488951Y1022162D01*
X489284Y1022242D01*
X489534Y1022349D01*
X489743Y1022509D01*
X489826Y1022722D01*
X489743Y1022935D01*
X489534Y1023095D01*
X489284Y1023202D01*
X488951Y1023282D01*
X488576Y1023309D01*
X488201Y1023282D01*
X487868Y1023202D01*
X487618Y1023095D01*
X487409Y1022935D01*
X487326Y1022722D01*
G01X485845Y1028998D02*
X486005Y1029248D01*
X486192Y1029373D01*
X486405Y1029415D01*
X486672Y1029332D01*
X486859Y1029123D01*
X486912Y1028873D01*
X486885Y1028623D01*
X486779Y1028415D01*
X486245Y1027998D01*
X486005Y1027707D01*
X485845Y1027290D01*
X485792Y1026915D01*
X486912D01*
G01X488552D02*
Y1029415D01*
X488232Y1028915D01*
G01Y1026915D02*
X488872D01*
G01X486845Y1016503D02*
X488345D01*
G01X489795Y1024303D02*
X486795D01*
G01X485338Y1027146D02*
Y1025240D01*
G01X486885Y1033280D02*
Y1030080D01*
G01X480685Y1033280D02*
X486885D01*
G01X480685Y1030080D02*
Y1033280D01*
G01X486885Y1030080D02*
X480685D01*
G01X495885Y1030580D02*
X489685D01*
Y1033780D01*
X495885D01*
Y1030580D01*
G01X476295Y1028653D02*
Y1030153D01*
G01X483432Y1027146D02*
X485338D01*
G01X474946Y1056313D02*
X484632D01*
G01D02*
Y1078148D01*
G01X493648Y1062632D02*
X490240D01*
G01D02*
Y1080348D01*
G01D02*
X493648D01*
G01X484632Y1078148D02*
X479695Y1083085D01*
G01D02*
X474946D01*
G01X474655Y1107230D02*
X477855D01*
G01X474655Y1101030D02*
Y1107230D01*
G01X477855Y1101030D02*
X474655D01*
G01X477855Y1107230D02*
Y1101030D01*
G01X479377Y1100426D02*
Y1097226D01*
G01X478442Y1107230D02*
X481642D01*
G01X478442Y1101030D02*
Y1107230D01*
G01X481642Y1101030D02*
X478442D01*
G01X481642Y1107230D02*
Y1101030D01*
G01X489719Y1103442D02*
Y1097242D01*
X486519D01*
Y1103442D01*
X489719D01*
G01X495136Y1177793D02*
X478206D01*
G01D02*
Y1213533D01*
G01X478204Y1176593D02*
Y1177793D01*
G01Y1176593D02*
X495187Y1176599D01*
G01X478204Y1177193D02*
X495179Y1177189D01*
G01X478204Y1177793D02*
X495144Y1177790D01*
G01X476206Y1201471D02*
Y1189471D01*
G01X478206Y1213533D02*
X495136D01*
G01X495728Y57756D02*
Y111665D01*
G01X496024Y58150D02*
Y111665D01*
G01X493580Y58333D02*
X493890Y58525D01*
X494097Y58755D01*
X494200Y59023D01*
X494097Y59330D01*
X493890Y59560D01*
X493580Y59790D01*
X493167Y59867D01*
X491100D01*
G01X493580Y61357D02*
X493942Y61587D01*
X494148Y61893D01*
X494200Y62238D01*
X494148Y62545D01*
X493890Y62852D01*
X493580Y63043D01*
X493270Y63082D01*
X492908Y63005D01*
X492650Y62737D01*
X492547Y62468D01*
Y62123D01*
G01Y62468D02*
X492392Y62698D01*
X492133Y62890D01*
X491823Y62967D01*
X491513Y62890D01*
X491255Y62698D01*
X491100Y62353D01*
X491152Y62008D01*
X491358Y61663D01*
G01X494200Y65760D02*
X491100D01*
X493322Y64342D01*
Y66258D01*
G01X502109Y57756D02*
X495728D01*
G01X501704Y58150D02*
X496024D01*
G01X490785Y99267D02*
Y96067D01*
G01X496024Y118848D02*
Y114048D01*
G01X495728Y118848D02*
Y114048D01*
G01X490658Y108086D02*
Y101886D01*
G01X496024Y132607D02*
Y128340D01*
G01X495728Y132607D02*
Y128340D01*
G01Y125781D02*
Y121219D01*
G01X496024Y125781D02*
Y121219D01*
G01X495728Y153150D02*
Y135509D01*
G01X496024Y152756D02*
Y135509D01*
G01X495728Y153150D02*
X502109D01*
G01X496024Y152756D02*
X501704D01*
G01X499455Y189535D02*
X497029D01*
G01X495915Y195583D02*
Y184087D01*
G01X495883Y214543D02*
X492783D01*
Y215463D01*
X492938Y215770D01*
X493300Y216000D01*
X493713Y216077D01*
X494126Y216000D01*
X494436Y215808D01*
X494591Y215463D01*
Y214543D01*
G01X492783Y217567D02*
X495005D01*
X495470Y217720D01*
X495780Y218027D01*
X495883Y218410D01*
X495780Y218793D01*
X495470Y219100D01*
X495005Y219253D01*
X492783D01*
G01X495418Y220667D02*
X495676Y220897D01*
X495831Y221165D01*
X495883Y221510D01*
X495780Y221855D01*
X495573Y222123D01*
X495211Y222315D01*
X494798Y222353D01*
X494385Y222277D01*
X494126Y222085D01*
X493920Y221817D01*
X493868Y221548D01*
X493920Y221280D01*
X494126Y220935D01*
X492783Y221050D01*
Y222085D01*
G01X495418Y223767D02*
X495676Y223997D01*
X495831Y224265D01*
X495883Y224610D01*
X495780Y224955D01*
X495573Y225223D01*
X495211Y225415D01*
X494798Y225453D01*
X494385Y225377D01*
X494126Y225185D01*
X493920Y224917D01*
X493868Y224648D01*
X493920Y224380D01*
X494126Y224035D01*
X492783Y224150D01*
Y225185D01*
G01X494888Y231459D02*
X491688D01*
G01X494888Y237659D02*
Y231459D01*
G01X491688Y237659D02*
X494888D01*
G01X491688Y231459D02*
Y237659D01*
G01X490888D02*
Y231459D01*
G01X492514Y243281D02*
Y240081D01*
G01X492118Y252199D02*
Y248999D01*
G01X509600Y264183D02*
X506500D01*
Y265103D01*
X506655Y265410D01*
X507017Y265640D01*
X507430Y265717D01*
X507843Y265640D01*
X508153Y265448D01*
X508308Y265103D01*
Y264183D01*
G01X509600Y267207D02*
X506500D01*
Y267973D01*
X506655Y268280D01*
X506862Y268510D01*
X507172Y268702D01*
X507533Y268855D01*
X508050Y268893D01*
X508567Y268855D01*
X508928Y268702D01*
X509238Y268510D01*
X509445Y268280D01*
X509600Y267973D01*
Y267207D01*
G01Y271150D02*
X506500D01*
X507120Y270690D01*
G01X509600D02*
Y271610D01*
G01X506500Y274250D02*
X506603Y273943D01*
X506862Y273713D01*
X507172Y273560D01*
X507585Y273445D01*
X508050Y273407D01*
X508515Y273445D01*
X508928Y273560D01*
X509238Y273713D01*
X509497Y273943D01*
X509600Y274250D01*
X509497Y274557D01*
X509238Y274787D01*
X508928Y274940D01*
X508515Y275055D01*
X508050Y275093D01*
X507585Y275055D01*
X507172Y274940D01*
X506862Y274787D01*
X506603Y274557D01*
X506500Y274250D01*
G01X507017Y276622D02*
X506707Y276852D01*
X506552Y277120D01*
X506500Y277427D01*
X506603Y277810D01*
X506862Y278078D01*
X507172Y278155D01*
X507482Y278117D01*
X507740Y277963D01*
X508257Y277197D01*
X508618Y276852D01*
X509135Y276622D01*
X509600Y276545D01*
Y278155D01*
G01X505545Y355179D02*
X520145D01*
G01X505545Y386281D02*
Y355179D01*
G01X504552Y390497D02*
Y388275D01*
X504705Y387810D01*
X505012Y387500D01*
X505395Y387397D01*
X505778Y387500D01*
X506085Y387810D01*
X506238Y388275D01*
Y390497D01*
G01X508495Y387397D02*
Y390497D01*
X508035Y389877D01*
G01Y387397D02*
X508955D01*
G01X510867Y389980D02*
X511097Y390290D01*
X511365Y390445D01*
X511672Y390497D01*
X512055Y390394D01*
X512323Y390135D01*
X512400Y389825D01*
X512362Y389515D01*
X512208Y389257D01*
X511442Y388740D01*
X511097Y388379D01*
X510867Y387862D01*
X510790Y387397D01*
X512400D01*
G01X515155D02*
Y390497D01*
X513737Y388275D01*
X515653D01*
G01X507794Y386281D02*
X505545D01*
G01X494613Y418598D02*
X494561Y418291D01*
X494355Y418023D01*
X494045Y417793D01*
X493683Y417640D01*
X493270Y417563D01*
X492856D01*
X492443Y417640D01*
X492081Y417793D01*
X491771Y418023D01*
X491565Y418291D01*
X491513Y418598D01*
X491565Y418905D01*
X491771Y419173D01*
X492081Y419403D01*
X492443Y419556D01*
X492856Y419633D01*
X493270D01*
X493683Y419556D01*
X494045Y419403D01*
X494355Y419173D01*
X494561Y418905D01*
X494613Y418598D01*
G01X493786Y418905D02*
X494613Y419365D01*
G01Y421698D02*
X491513D01*
X492133Y421238D01*
G01X494613D02*
Y422158D01*
G01X492030Y424070D02*
X491720Y424300D01*
X491565Y424568D01*
X491513Y424875D01*
X491616Y425258D01*
X491875Y425526D01*
X492185Y425603D01*
X492495Y425565D01*
X492753Y425411D01*
X493270Y424645D01*
X493631Y424300D01*
X494148Y424070D01*
X494613Y423993D01*
Y425603D01*
G01X493321Y427170D02*
X492960Y427438D01*
X492753Y427668D01*
X492650Y427975D01*
X492753Y428243D01*
X492960Y428435D01*
X493270Y428588D01*
X493631Y428626D01*
X493941Y428588D01*
X494251Y428435D01*
X494510Y428205D01*
X494613Y427936D01*
X494510Y427630D01*
X494200Y427361D01*
X493735Y427208D01*
X493218Y427170D01*
X492546Y427246D01*
X492185Y427361D01*
X491823Y427553D01*
X491565Y427821D01*
X491513Y428090D01*
X491616Y428358D01*
X491875Y428550D01*
G01X491085Y439017D02*
Y432817D01*
G01X495085D02*
X491885D01*
G01X495085Y439017D02*
Y432817D01*
G01X491885Y439017D02*
X495085D01*
G01X491885Y432817D02*
Y439017D01*
G01X505329Y440819D02*
X502129D01*
G01X505329Y447019D02*
Y440819D01*
G01X502129D02*
Y447019D01*
G01X494800Y449550D02*
X494748Y449243D01*
X494542Y448975D01*
X494232Y448745D01*
X493870Y448592D01*
X493457Y448515D01*
X493043D01*
X492630Y448592D01*
X492268Y448745D01*
X491958Y448975D01*
X491752Y449243D01*
X491700Y449550D01*
X491752Y449857D01*
X491958Y450125D01*
X492268Y450355D01*
X492630Y450508D01*
X493043Y450585D01*
X493457D01*
X493870Y450508D01*
X494232Y450355D01*
X494542Y450125D01*
X494748Y449857D01*
X494800Y449550D01*
G01X493973Y449857D02*
X494800Y450317D01*
G01X492217Y451922D02*
X491907Y452152D01*
X491752Y452420D01*
X491700Y452727D01*
X491803Y453110D01*
X492062Y453378D01*
X492372Y453455D01*
X492682Y453417D01*
X492940Y453263D01*
X493457Y452497D01*
X493818Y452152D01*
X494335Y451922D01*
X494800Y451845D01*
Y453455D01*
G01Y455750D02*
X491700D01*
X492320Y455290D01*
G01X494800D02*
Y456210D01*
G01Y459310D02*
X491700D01*
X493922Y457892D01*
Y459808D01*
G01X505453Y452919D02*
Y449501D01*
G01X503729Y454919D02*
X505453Y452919D01*
G01Y456919D02*
X503729Y454919D01*
G01X505453Y460337D02*
Y456919D01*
G01X496005Y449501D02*
Y460337D01*
G01X505453Y449501D02*
X496005D01*
G01X502129Y447019D02*
X505329D01*
G01X496005Y460337D02*
X505453D01*
G01X498329Y462819D02*
X495129D01*
G01X498329Y469019D02*
Y462819D01*
G01X495129Y469019D02*
X498329D01*
G01X495129Y462819D02*
Y469019D01*
G01X499129D02*
X502329D01*
G01X499129Y462819D02*
Y469019D01*
G01X502329Y462819D02*
X499129D01*
G01X502329Y469019D02*
Y462819D01*
G01X503129Y469019D02*
X506329D01*
G01X503129Y462819D02*
Y469019D01*
G01X506329Y462819D02*
X503129D01*
G01X506329Y469019D02*
Y462819D01*
G01X499991Y480582D02*
Y477382D01*
G01X493791Y480582D02*
X499991D01*
G01X493791Y477382D02*
Y480582D01*
G01X499991Y477382D02*
X493791D01*
G01X499991Y485582D02*
Y482382D01*
G01X493791Y485582D02*
X499991D01*
G01X493791Y482382D02*
Y485582D01*
G01X499991Y482382D02*
X493791D01*
G01X499991Y493582D02*
Y490382D01*
G01X493791D02*
Y493582D01*
G01X499991Y490382D02*
X493791D01*
G01X499991Y486382D02*
X493791D01*
Y489582D01*
X499991D01*
Y486382D01*
G01X501398Y480076D02*
Y483176D01*
X502318D01*
X502625Y483021D01*
X502855Y482659D01*
X502932Y482246D01*
X502855Y481833D01*
X502663Y481523D01*
X502318Y481368D01*
X501398D01*
G01X504422Y483176D02*
Y480954D01*
X504575Y480489D01*
X504882Y480179D01*
X505265Y480076D01*
X505648Y480179D01*
X505955Y480489D01*
X506108Y480954D01*
Y483176D01*
G01X507522Y480541D02*
X507752Y480283D01*
X508020Y480128D01*
X508365Y480076D01*
X508710Y480179D01*
X508978Y480386D01*
X509170Y480748D01*
X509208Y481161D01*
X509132Y481574D01*
X508940Y481833D01*
X508672Y482039D01*
X508403Y482091D01*
X508135Y482039D01*
X507790Y481833D01*
X507905Y483176D01*
X508940D01*
G01X511465D02*
X511158Y483073D01*
X510928Y482814D01*
X510775Y482504D01*
X510660Y482091D01*
X510622Y481626D01*
X510660Y481161D01*
X510775Y480748D01*
X510928Y480438D01*
X511158Y480179D01*
X511465Y480076D01*
X511772Y480179D01*
X512002Y480438D01*
X512155Y480748D01*
X512270Y481161D01*
X512308Y481626D01*
X512270Y482091D01*
X512155Y482504D01*
X512002Y482814D01*
X511772Y483073D01*
X511465Y483176D01*
G01X503494Y486594D02*
Y498798D01*
X518798D01*
Y486594D01*
X503494D01*
G01X492444Y503265D02*
X523536D01*
G01X492444Y518777D02*
Y503265D01*
G01X499991Y501582D02*
Y498382D01*
G01X493791Y501582D02*
X499991D01*
G01X493791Y498382D02*
Y501582D01*
G01X499991Y498382D02*
X493791D01*
G01Y493582D02*
X499991D01*
G01X493791Y494382D02*
Y497582D01*
G01X499991Y494382D02*
X493791D01*
G01X499991Y497582D02*
Y494382D01*
G01X493791Y497582D02*
X499991D01*
G01X515979Y520969D02*
X503979D01*
G01D02*
Y526969D01*
G01X492983Y520200D02*
Y523300D01*
X493903D01*
X494210Y523145D01*
X494440Y522783D01*
X494517Y522370D01*
X494440Y521957D01*
X494248Y521647D01*
X493903Y521492D01*
X492983D01*
G01X496007Y520200D02*
Y523300D01*
X496773D01*
X497080Y523145D01*
X497310Y522938D01*
X497502Y522628D01*
X497655Y522267D01*
X497693Y521750D01*
X497655Y521233D01*
X497502Y520872D01*
X497310Y520562D01*
X497080Y520355D01*
X496773Y520200D01*
X496007D01*
G01X500410D02*
Y523300D01*
X498992Y521078D01*
X500908D01*
G01X523536Y518777D02*
X492444D01*
G01X503979Y526969D02*
X515979D01*
G01X505979Y527669D02*
Y530869D01*
G01X512179Y527669D02*
X505979D01*
G01Y530869D02*
X512179D01*
G01X491442Y526855D02*
Y529955D01*
X492362D01*
X492669Y529800D01*
X492899Y529438D01*
X492976Y529025D01*
X492899Y528612D01*
X492707Y528302D01*
X492362Y528147D01*
X491442D01*
G01X494466Y529955D02*
Y527733D01*
X494619Y527268D01*
X494926Y526958D01*
X495309Y526855D01*
X495692Y526958D01*
X495999Y527268D01*
X496152Y527733D01*
Y529955D01*
G01X497681Y529438D02*
X497911Y529748D01*
X498179Y529903D01*
X498486Y529955D01*
X498869Y529852D01*
X499137Y529593D01*
X499214Y529283D01*
X499176Y528973D01*
X499022Y528715D01*
X498256Y528198D01*
X497911Y527837D01*
X497681Y527320D01*
X497604Y526855D01*
X499214D01*
G01X500781Y528147D02*
X501049Y528508D01*
X501279Y528715D01*
X501586Y528818D01*
X501854Y528715D01*
X502046Y528508D01*
X502199Y528198D01*
X502237Y527837D01*
X502199Y527527D01*
X502046Y527217D01*
X501816Y526958D01*
X501547Y526855D01*
X501241Y526958D01*
X500972Y527268D01*
X500819Y527733D01*
X500781Y528250D01*
X500857Y528922D01*
X500972Y529283D01*
X501164Y529645D01*
X501432Y529903D01*
X501701Y529955D01*
X501969Y529852D01*
X502161Y529593D01*
G01X493663Y533338D02*
Y545542D01*
X508967D01*
Y533338D01*
X493663D01*
G01X504545Y556194D02*
X492545D01*
G01X504545Y562194D02*
Y556194D01*
G01X492545Y562194D02*
X504545D01*
G01X492545Y556194D02*
Y562194D01*
G01X504545Y564194D02*
X492545D01*
G01X504545Y570194D02*
Y564194D01*
G01X492545Y570194D02*
X504545D01*
G01X492545Y564194D02*
Y570194D01*
G01X504545Y572194D02*
X492545D01*
G01X504545Y578194D02*
Y572194D01*
G01X492545Y578194D02*
X504545D01*
G01X492545Y572194D02*
Y578194D01*
G01X499378Y604111D02*
Y599511D01*
G01X502285Y598993D02*
Y595793D01*
G01X496085Y598993D02*
X502285D01*
G01X496085Y595793D02*
Y598993D01*
G01X502285Y595793D02*
X496085D01*
G01X499378Y609611D02*
Y605011D01*
G01X491878Y622911D02*
Y619711D01*
G01X492678Y618411D02*
Y612211D01*
G01X493817Y613204D02*
X496317D01*
X495817Y613524D01*
G01X493817D02*
Y612884D01*
G01Y611004D02*
X496317D01*
X495817Y611324D01*
G01X493817D02*
Y610684D01*
G01X503222Y610586D02*
Y608086D01*
X503542Y608586D01*
G01Y610586D02*
X502902D01*
G01X501529Y608503D02*
X501369Y608253D01*
X501182Y608128D01*
X500969Y608086D01*
X500702Y608169D01*
X500515Y608378D01*
X500462Y608628D01*
X500489Y608878D01*
X500595Y609086D01*
X501129Y609503D01*
X501369Y609794D01*
X501529Y610211D01*
X501582Y610586D01*
X500462D01*
G01X496239Y620279D02*
Y618343D01*
G01Y613209D02*
X497404D01*
G01X496239Y616343D02*
Y613209D01*
G01X504878Y634711D02*
X501678D01*
G01X504878Y640911D02*
Y634711D01*
G01X501678D02*
Y640911D01*
G01X500878Y634711D02*
X497678D01*
G01X500878Y640911D02*
Y634711D01*
G01X497678D02*
Y640911D01*
G01X508878Y634711D02*
X505678D01*
G01D02*
Y640911D01*
G01X495378Y634711D02*
X492178D01*
G01X495378Y640911D02*
Y634711D01*
G01X492178D02*
Y640911D01*
G01X502740Y632812D02*
X508940D01*
G01X502740Y629612D02*
Y632812D01*
G01X508940Y629612D02*
X502740D01*
G01X491878Y630911D02*
Y627711D01*
G01Y626911D02*
Y623711D01*
G01X496531Y629352D02*
X496345Y629561D01*
X496131Y629644D01*
X495918Y629561D01*
X495731Y629311D01*
X495598Y628936D01*
X495545Y628561D01*
Y628102D01*
X495598Y627727D01*
X495731Y627394D01*
X495891Y627227D01*
X496078Y627144D01*
X496291Y627227D01*
X496451Y627394D01*
X496558Y627644D01*
X496611Y627977D01*
X496558Y628269D01*
X496425Y628561D01*
X496265Y628727D01*
X496078Y628769D01*
X495865Y628686D01*
X495705Y628477D01*
X495545Y628102D01*
G01X492821Y625968D02*
X495321D01*
X494821Y626288D01*
G01X492821D02*
Y625648D01*
G01X495321Y623768D02*
X495238Y623981D01*
X495029Y624141D01*
X494779Y624248D01*
X494446Y624328D01*
X494071Y624355D01*
X493696Y624328D01*
X493363Y624248D01*
X493113Y624141D01*
X492904Y623981D01*
X492821Y623768D01*
X492904Y623555D01*
X493113Y623395D01*
X493363Y623288D01*
X493696Y623208D01*
X494071Y623181D01*
X494446Y623208D01*
X494779Y623288D01*
X495029Y623395D01*
X495238Y623555D01*
X495321Y623768D01*
G01X496239Y625413D02*
Y622279D01*
G01X497404Y625413D02*
X496239D01*
G01X501678Y640911D02*
X504878D01*
G01X497678D02*
X500878D01*
G01X505678D02*
X508878D01*
G01X492178D02*
X495378D01*
G01X503864Y668553D02*
X506187D01*
G01X495724Y668263D02*
Y674063D01*
G01Y660463D02*
Y666263D01*
G01D02*
X494224Y667263D01*
X495724Y668263D01*
G01X503864Y668553D02*
Y674753D01*
G01X498080Y656749D02*
X504280D01*
Y653549D01*
X498080D01*
Y656749D01*
G01X504203Y658841D02*
X498003D01*
Y662041D01*
X504203D01*
Y658841D01*
G01X493834Y683406D02*
Y685583D01*
G01X500034Y683406D02*
Y685533D01*
G01X503864Y674753D02*
X505976D01*
G01X492314Y675835D02*
Y682035D01*
X495514D01*
Y675835D01*
X492314D01*
G01X500034Y683406D02*
X493834D01*
G01X500034Y698606D02*
Y696429D01*
G01Y691406D02*
Y693591D01*
G01X494704Y694606D02*
X499089D01*
G01X494704Y695406D02*
X499089D01*
G01X493834Y698606D02*
Y696488D01*
G01Y691406D02*
Y693621D01*
G01Y690606D02*
Y688490D01*
G01X499090Y687406D02*
X494605D01*
G01X499090Y686606D02*
X494605D01*
G01X500034Y690606D02*
Y688401D01*
G01X493834Y690606D02*
X500034D01*
G01X493834Y698606D02*
X500034D01*
G01Y691406D02*
X493834D01*
G01X505564Y715937D02*
Y713715D01*
X505717Y713250D01*
X506024Y712940D01*
X506407Y712837D01*
X506790Y712940D01*
X507097Y713250D01*
X507250Y713715D01*
Y715937D01*
G01X509507Y712837D02*
Y715937D01*
X509047Y715317D01*
G01Y712837D02*
X509967D01*
G01X512607D02*
Y715937D01*
X512147Y715317D01*
G01Y712837D02*
X513067D01*
G01X516167D02*
Y715937D01*
X514749Y713715D01*
X516665D01*
G01X501270Y779048D02*
Y776826D01*
X501423Y776361D01*
X501730Y776051D01*
X502113Y775948D01*
X502496Y776051D01*
X502803Y776361D01*
X502956Y776826D01*
Y779048D01*
G01X505673Y775948D02*
Y779048D01*
X504255Y776826D01*
X506171D01*
G01X508773Y775948D02*
Y779048D01*
X507355Y776826D01*
X509271D01*
G01X511413Y775948D02*
Y779048D01*
X510953Y778428D01*
G01Y775948D02*
X511873D01*
G01X504641Y843049D02*
Y846249D01*
G01X510841Y843049D02*
X504641D01*
G01Y846249D02*
X510841D01*
G01X506872Y868345D02*
X503772D01*
X504392Y867885D01*
G01X506872D02*
Y868805D01*
G01X505580Y870717D02*
X505219Y870985D01*
X505012Y871215D01*
X504909Y871522D01*
X505012Y871790D01*
X505219Y871982D01*
X505529Y872135D01*
X505890Y872173D01*
X506200Y872135D01*
X506510Y871982D01*
X506769Y871752D01*
X506872Y871483D01*
X506769Y871177D01*
X506459Y870908D01*
X505994Y870755D01*
X505477Y870717D01*
X504805Y870793D01*
X504444Y870908D01*
X504082Y871100D01*
X503824Y871368D01*
X503772Y871637D01*
X503875Y871905D01*
X504134Y872097D01*
G01X506410Y904693D02*
X506669Y904962D01*
X506772Y905268D01*
X506669Y905575D01*
X506359Y905843D01*
X505894Y906035D01*
X505429Y906112D01*
X504860D01*
X504395Y906035D01*
X503982Y905843D01*
X503775Y905613D01*
X503672Y905345D01*
X503775Y905038D01*
X503982Y904808D01*
X504292Y904655D01*
X504705Y904578D01*
X505067Y904655D01*
X505429Y904847D01*
X505635Y905077D01*
X505687Y905345D01*
X505584Y905652D01*
X505325Y905882D01*
X504860Y906112D01*
G01X490491Y990666D02*
Y996866D01*
X493691D01*
Y990666D01*
X490491D01*
G01X502682Y994281D02*
Y988081D01*
X499482D01*
Y994281D01*
X502682D01*
G01X509694Y987635D02*
X503494D01*
Y990835D01*
X509694D01*
Y987635D01*
G01X505691Y1006366D02*
Y1003166D01*
G01X499491Y1006366D02*
X505691D01*
G01X499491Y1003166D02*
Y1006366D01*
G01X505691Y1003166D02*
X499491D01*
G01Y999166D02*
Y1002366D01*
G01X505691Y999166D02*
X499491D01*
G01X505691Y1002366D02*
Y999166D01*
G01X499491Y1002366D02*
X505691D01*
G01Y998366D02*
Y995166D01*
G01X499491Y998366D02*
X505691D01*
G01X499491Y995166D02*
Y998366D01*
G01X505691Y995166D02*
X499491D01*
G01X505691Y1010366D02*
Y1007166D01*
G01X499491D02*
Y1010366D01*
G01X505691Y1007166D02*
X499491D01*
G01Y1014666D02*
Y1017866D01*
G01X505691Y1014666D02*
X499491D01*
G01X505691Y1017866D02*
Y1014666D01*
G01X499491Y1017866D02*
X505691D01*
G01X499491Y1010366D02*
X505691D01*
G01X499491Y1010666D02*
Y1013866D01*
G01X505691Y1010666D02*
X499491D01*
G01X505691Y1013866D02*
Y1010666D01*
G01X499491Y1013866D02*
X505691D01*
G01X505558Y1018658D02*
X499358D01*
Y1021858D01*
X505558D01*
Y1018658D01*
G01X505691Y1032366D02*
Y1029166D01*
G01X499491Y1032366D02*
X505691D01*
G01X499491Y1029166D02*
Y1032366D01*
G01X505691Y1029166D02*
X499491D01*
G01X504358Y1053406D02*
Y1059606D01*
G01X507558Y1053406D02*
X504358D01*
G01X493467Y1051560D02*
Y1054660D01*
X494387D01*
X494694Y1054505D01*
X494924Y1054143D01*
X495001Y1053730D01*
X494924Y1053317D01*
X494732Y1053007D01*
X494387Y1052852D01*
X493467D01*
G01X496567Y1054660D02*
Y1051560D01*
X498101D01*
G01X500434D02*
X500702Y1051612D01*
X501009Y1051767D01*
X501201Y1052025D01*
X501277Y1052387D01*
X501201Y1052748D01*
X500971Y1053058D01*
X500626Y1053213D01*
X500242D01*
X500012Y1053317D01*
X499821Y1053575D01*
X499744Y1053937D01*
X499859Y1054298D01*
X500127Y1054557D01*
X500434Y1054660D01*
X500741Y1054557D01*
X501009Y1054298D01*
X501124Y1053937D01*
X501047Y1053575D01*
X500856Y1053317D01*
X500626Y1053213D01*
X500242D01*
X499897Y1053058D01*
X499667Y1052748D01*
X499591Y1052387D01*
X499667Y1052025D01*
X499859Y1051767D01*
X500166Y1051612D01*
X500434Y1051560D01*
G01X504358Y1059606D02*
X507558D01*
G01X507956Y1062632D02*
X504548D01*
G01X502831Y1090088D02*
Y1096088D01*
G01X514831Y1090088D02*
X502831D01*
G01X514689Y1088890D02*
Y1082890D01*
X502689D01*
Y1088890D01*
X514689D01*
G01X504548Y1080348D02*
X507956D01*
G01X502831Y1096088D02*
X514831D01*
G01X491900Y1103442D02*
X495100D01*
G01X491900Y1097242D02*
Y1103442D01*
G01X495100Y1097242D02*
X491900D01*
G01X495100Y1103442D02*
Y1097242D01*
G01X505305Y1097226D02*
Y1100426D01*
G01X511505Y1097226D02*
X505305D01*
G01Y1100426D02*
X511505D01*
G01X495272Y1114996D02*
X498472D01*
G01X495272Y1108796D02*
Y1114996D01*
G01X498472Y1108796D02*
X495272D01*
G01X498472Y1114996D02*
Y1108796D01*
G01X502474Y1118297D02*
X499274D01*
G01X502474Y1124497D02*
Y1118297D01*
G01X499274D02*
Y1124497D01*
G01X498472Y1119296D02*
X495272D01*
G01X498472Y1125496D02*
Y1119296D01*
G01X495272D02*
Y1125496D01*
G01X505083Y1109839D02*
Y1112030D01*
G01X505816Y1109839D02*
X505083D01*
G01X492641D02*
X491633D01*
G01X492641Y1111693D02*
Y1109839D01*
G01Y1124250D02*
Y1122552D01*
G01X499274Y1124497D02*
X502474D01*
G01X495272Y1125496D02*
X498472D01*
G01X505083Y1133461D02*
X505876D01*
G01X505083Y1130861D02*
Y1133461D01*
G01X492641D02*
Y1130861D01*
G01X491848Y1133461D02*
X492641D01*
G01X505876Y1136752D02*
X499878D01*
G01D02*
Y1174548D01*
G01X497246Y1136752D02*
X491248D01*
G01X497246Y1174548D02*
Y1136752D01*
G01X502391Y1177643D02*
Y1179883D01*
G01X500766Y1178670D02*
X504016D01*
G01X522066Y1177793D02*
X505136D01*
G01D02*
Y1213533D01*
G01X505134Y1176593D02*
Y1177793D01*
G01Y1176593D02*
X522117Y1176599D01*
G01X505134Y1177193D02*
X522109Y1177189D01*
G01X505134Y1177793D02*
X522074Y1177790D01*
G01X495136Y1213533D02*
Y1177793D01*
G01X495137Y1176643D02*
X495133Y1178152D01*
G01X499878Y1174548D02*
X505876D01*
G01X491248D02*
X497246D01*
G01X497136Y1189471D02*
Y1201471D01*
G01X503136Y1189471D02*
X497136D01*
G01X503136Y1201471D02*
Y1189471D01*
G01X497136Y1201471D02*
X503136D01*
G01X501898Y1219551D02*
Y1209351D01*
X497298D01*
Y1219551D01*
X501898D01*
G01X491880Y1215076D02*
Y1228059D01*
G01X503642Y1210224D02*
Y1212650D01*
G01X505136Y1213533D02*
X522066D01*
G01X493172Y1239176D02*
Y1230276D01*
G01X493180Y1266904D02*
Y1249202D01*
G01D02*
X506455D01*
G01X491880Y1241114D02*
Y1254376D01*
G01X506282Y1266904D02*
X493180D01*
G01X520236Y58150D02*
Y104620D01*
G01X520532Y57756D02*
Y104620D01*
G01Y57756D02*
X514151D01*
G01X520236Y58150D02*
X514556D01*
G01X520532Y111507D02*
Y107060D01*
G01X520236Y111507D02*
Y107060D01*
G01Y118680D02*
Y114087D01*
G01X520532Y118680D02*
Y114087D01*
G01X520236Y132859D02*
Y128325D01*
G01X520532Y132859D02*
Y128325D01*
G01Y125844D02*
Y121329D01*
G01X520236Y125844D02*
Y121329D01*
G01Y152756D02*
Y135458D01*
G01X520532Y153150D02*
Y135458D01*
G01X509182Y156615D02*
X509929Y155990D01*
X510769Y155615D01*
X511515D01*
X512262Y155990D01*
X512822Y156615D01*
X513102Y157490D01*
X512915Y158365D01*
X512449Y159115D01*
X511609Y159615D01*
X510489Y159865D01*
X509835Y160365D01*
X509555Y161240D01*
X509742Y162115D01*
X510209Y162740D01*
X510862Y163115D01*
X511515D01*
X512169Y162865D01*
X512729Y162240D01*
G01X516682Y156615D02*
X517429Y155990D01*
X518269Y155615D01*
X519015D01*
X519762Y155990D01*
X520322Y156615D01*
X520602Y157490D01*
X520415Y158365D01*
X519949Y159115D01*
X519109Y159615D01*
X517989Y159865D01*
X517335Y160365D01*
X517055Y161240D01*
X517242Y162115D01*
X517709Y162740D01*
X518362Y163115D01*
X519015D01*
X519669Y162865D01*
X520229Y162240D01*
G01X524089Y155615D02*
Y163115D01*
X525955D01*
X526702Y162740D01*
X527262Y162240D01*
X527729Y161490D01*
X528102Y160615D01*
X528195Y159365D01*
X528102Y158115D01*
X527729Y157240D01*
X527262Y156490D01*
X526702Y155990D01*
X525955Y155615D01*
X524089D01*
G01X534762D02*
Y163115D01*
X531309Y157740D01*
X535975D01*
G01X512632Y164436D02*
X527432D01*
G01X512632Y195440D02*
Y164436D01*
G01X514151Y153150D02*
X520532D01*
G01X514556Y152756D02*
X520236D01*
G01X527432Y195440D02*
X512632D01*
G01X516635Y199912D02*
Y202338D01*
G01X510000Y204383D02*
X506900D01*
Y205303D01*
X507055Y205610D01*
X507417Y205840D01*
X507830Y205917D01*
X508243Y205840D01*
X508553Y205648D01*
X508708Y205303D01*
Y204383D01*
G01X510000Y207407D02*
X506900D01*
Y208173D01*
X507055Y208480D01*
X507262Y208710D01*
X507572Y208902D01*
X507933Y209055D01*
X508450Y209093D01*
X508967Y209055D01*
X509328Y208902D01*
X509638Y208710D01*
X509845Y208480D01*
X510000Y208173D01*
Y207407D01*
G01X507417Y210622D02*
X507107Y210852D01*
X506952Y211120D01*
X506900Y211427D01*
X507003Y211810D01*
X507262Y212078D01*
X507572Y212155D01*
X507882Y212117D01*
X508140Y211963D01*
X508657Y211197D01*
X509018Y210852D01*
X509535Y210622D01*
X510000Y210545D01*
Y212155D01*
G01X509380Y213607D02*
X509742Y213837D01*
X509948Y214143D01*
X510000Y214488D01*
X509948Y214795D01*
X509690Y215102D01*
X509380Y215293D01*
X509070Y215332D01*
X508708Y215255D01*
X508450Y214987D01*
X508347Y214718D01*
Y214373D01*
G01Y214718D02*
X508192Y214948D01*
X507933Y215140D01*
X507623Y215217D01*
X507313Y215140D01*
X507055Y214948D01*
X506900Y214603D01*
X506952Y214258D01*
X507158Y213913D01*
G01X522683Y203452D02*
X511187D01*
G01X522683Y233011D02*
Y203452D01*
G01X511187D02*
Y233011D01*
G01X516535Y236652D02*
Y234412D01*
G01X518160Y235625D02*
X514910D01*
G01X511187Y233011D02*
X522683D01*
G01X516404Y259204D02*
Y261630D01*
G01X522452Y262744D02*
X510956D01*
G01X522452Y292303D02*
Y262744D01*
G01X510956D02*
Y292303D01*
G01X516541Y298308D02*
Y296068D01*
G01X518166Y297281D02*
X514916D01*
G01X510956Y292303D02*
X522452D01*
G01X520145Y355179D02*
Y386281D01*
G01X517896D02*
X512845Y381230D01*
G01X520145Y386281D02*
X517896D01*
G01X512845Y381230D02*
X507794Y386281D01*
G01X519245Y441594D02*
X522445D01*
G01X519245Y435394D02*
Y441594D01*
G01X522445Y435394D02*
X519245D01*
G01X522445Y441594D02*
Y435394D01*
G01X515245Y441594D02*
X518445D01*
G01X515245Y435394D02*
Y441594D01*
G01X518445Y435394D02*
X515245D01*
G01X518445Y441594D02*
Y435394D01*
G01X511245Y441594D02*
X514445D01*
G01X511245Y435394D02*
Y441594D01*
G01X514445Y435394D02*
X511245D01*
G01X514445Y441594D02*
Y435394D01*
G01X510200Y431633D02*
X507100D01*
Y432553D01*
X507255Y432860D01*
X507617Y433090D01*
X508030Y433167D01*
X508443Y433090D01*
X508753Y432898D01*
X508908Y432553D01*
Y431633D01*
G01X507100Y434657D02*
X509322D01*
X509787Y434810D01*
X510097Y435117D01*
X510200Y435500D01*
X510097Y435883D01*
X509787Y436190D01*
X509322Y436343D01*
X507100D01*
G01X510200Y438600D02*
X507100D01*
X507720Y438140D01*
G01X510200D02*
Y439060D01*
G01X507100Y441700D02*
X507203Y441393D01*
X507462Y441163D01*
X507772Y441010D01*
X508185Y440895D01*
X508650Y440857D01*
X509115Y440895D01*
X509528Y441010D01*
X509838Y441163D01*
X510097Y441393D01*
X510200Y441700D01*
X510097Y442007D01*
X509838Y442237D01*
X509528Y442390D01*
X509115Y442505D01*
X508650Y442543D01*
X508185Y442505D01*
X507772Y442390D01*
X507462Y442237D01*
X507203Y442007D01*
X507100Y441700D01*
G01X510200Y444800D02*
X507100D01*
X507720Y444340D01*
G01X510200D02*
Y445260D01*
G01X508422Y453438D02*
X511622D01*
G01X508422Y447238D02*
Y453438D01*
G01X511622Y447238D02*
X508422D01*
G01X511622Y453438D02*
Y447238D01*
G01X513359Y446607D02*
Y458381D01*
G01X523121Y446607D02*
X513359D01*
G01X522910Y462959D02*
X519710D01*
G01X522910Y469159D02*
Y462959D01*
G01X519710Y469159D02*
X522910D01*
G01X519710Y462959D02*
Y469159D01*
G01X514910Y462959D02*
X511710D01*
G01X514910Y469159D02*
Y462959D01*
G01X511710Y469159D02*
X514910D01*
G01X511710Y462959D02*
Y469159D01*
G01X515710D02*
X518910D01*
G01X515710Y462959D02*
Y469159D01*
G01X518910Y462959D02*
X515710D01*
G01X518910Y469159D02*
Y462959D01*
G01X510329Y462819D02*
X507129D01*
G01X510329Y469019D02*
Y462819D01*
G01X507129Y469019D02*
X510329D01*
G01X507129Y462819D02*
Y469019D01*
G01X513359Y458381D02*
X523121D01*
G01X525789Y474988D02*
X513789D01*
G01Y480988D02*
X525789D01*
G01X513789Y474988D02*
Y480988D01*
G01X521831Y485564D02*
Y491764D01*
G01X525031Y485564D02*
X521831D01*
G01X515789Y481788D02*
Y484988D01*
G01X521989Y481788D02*
X515789D01*
G01X521989Y484988D02*
Y481788D01*
G01X515789Y484988D02*
X521989D01*
G01X521831Y491764D02*
X525031D01*
G01X515979Y526969D02*
Y520969D01*
G01X522819Y540555D02*
Y528555D01*
G01X516819D02*
Y540555D01*
G01X522819Y528555D02*
X516819D01*
G01X512000Y538508D02*
X515200D01*
G01X512000Y532308D02*
Y538508D01*
G01X515200Y532308D02*
X512000D01*
G01X515200Y538508D02*
Y532308D01*
G01X512179Y530869D02*
Y527669D01*
G01X516819Y540555D02*
X522819D01*
G01X517995Y568248D02*
Y553448D01*
G01D02*
X548999D01*
G01Y568248D02*
X517995D01*
G01X516759Y585813D02*
X514333D01*
G01X513219Y591861D02*
Y580365D01*
G01X519894Y580432D02*
X523094D01*
G01X519894Y574232D02*
Y580432D01*
G01X523094Y574232D02*
X519894D01*
G01X519170Y598125D02*
Y604325D01*
G01X522370Y598125D02*
X519170D01*
G01X522370Y604325D02*
Y598125D01*
G01X515170D02*
Y604325D01*
G01X518370Y598125D02*
X515170D01*
G01X518370Y604325D02*
Y598125D01*
G01X512678Y606711D02*
Y609911D01*
G01X518878Y606711D02*
X512678D01*
G01X518878Y609911D02*
Y606711D01*
G01X512678Y609911D02*
X518878D01*
G01X519170Y604325D02*
X522370D01*
G01X515170D02*
X518370D01*
G01X520758Y622573D02*
X521008Y622413D01*
X521133Y622226D01*
X521175Y622013D01*
X521092Y621746D01*
X520883Y621559D01*
X520633Y621506D01*
X520383Y621533D01*
X520175Y621639D01*
X519758Y622173D01*
X519467Y622413D01*
X519050Y622573D01*
X518675Y622626D01*
Y621506D01*
G01Y619866D02*
X521175D01*
X520675Y620186D01*
G01X518675D02*
Y619546D01*
G01X517842Y618466D02*
Y616866D01*
G01X520758Y615973D02*
X521008Y615813D01*
X521133Y615626D01*
X521175Y615413D01*
X521092Y615146D01*
X520883Y614959D01*
X520633Y614906D01*
X520383Y614933D01*
X520175Y615039D01*
X519758Y615573D01*
X519467Y615813D01*
X519050Y615973D01*
X518675Y616026D01*
Y614906D01*
G01X520758Y613773D02*
X521008Y613613D01*
X521133Y613426D01*
X521175Y613213D01*
X521092Y612946D01*
X520883Y612759D01*
X520633Y612706D01*
X520383Y612733D01*
X520175Y612839D01*
X519758Y613373D01*
X519467Y613613D01*
X519050Y613773D01*
X518675Y613826D01*
Y612706D01*
G01X523317Y609788D02*
X523157Y609538D01*
X522970Y609413D01*
X522757Y609371D01*
X522490Y609454D01*
X522303Y609663D01*
X522250Y609913D01*
X522277Y610163D01*
X522383Y610371D01*
X522917Y610788D01*
X523157Y611079D01*
X523317Y611496D01*
X523370Y611871D01*
X522250D01*
G01X520610Y609371D02*
X520823Y609454D01*
X520983Y609663D01*
X521090Y609913D01*
X521170Y610246D01*
X521197Y610621D01*
X521170Y610996D01*
X521090Y611329D01*
X520983Y611579D01*
X520823Y611788D01*
X520610Y611871D01*
X520397Y611788D01*
X520237Y611579D01*
X520130Y611329D01*
X520050Y610996D01*
X520023Y610621D01*
X520050Y610246D01*
X520130Y609913D01*
X520237Y609663D01*
X520397Y609454D01*
X520610Y609371D01*
G01X516317Y613209D02*
Y616350D01*
G01X515152Y613209D02*
X516317D01*
G01Y618361D02*
Y620261D01*
G01X512878Y634711D02*
X509678D01*
G01X512878Y640911D02*
Y634711D01*
G01X509678D02*
Y640911D01*
G01X516678Y634711D02*
Y640911D01*
G01X519878Y634711D02*
X516678D01*
G01X519878Y640911D02*
Y634711D01*
G01X522674Y623567D02*
X519474D01*
G01X522674Y629767D02*
Y623567D01*
G01X519474Y629767D02*
X522674D01*
G01X519474Y623567D02*
Y629767D01*
G01X513178Y634711D02*
Y640911D01*
G01X516378Y634711D02*
X513178D01*
G01X516378Y640911D02*
Y634711D01*
G01X520178D02*
Y640911D01*
G01X523378Y634711D02*
X520178D01*
G01X508878Y640911D02*
Y634711D01*
G01X508940Y632812D02*
Y629612D01*
G01X512783Y630600D02*
Y633700D01*
X513703D01*
X514010Y633545D01*
X514240Y633183D01*
X514317Y632770D01*
X514240Y632357D01*
X514048Y632047D01*
X513703Y631892D01*
X512783D01*
G01X515807Y633700D02*
Y631478D01*
X515960Y631013D01*
X516267Y630703D01*
X516650Y630600D01*
X517033Y630703D01*
X517340Y631013D01*
X517493Y631478D01*
Y633700D01*
G01X519673Y630600D02*
X519750Y631272D01*
X519865Y631840D01*
X520018Y632357D01*
X520210Y632925D01*
X520517Y633700D01*
X518983D01*
G01X522007Y631220D02*
X522237Y630858D01*
X522543Y630652D01*
X522888Y630600D01*
X523195Y630652D01*
X523502Y630910D01*
X523693Y631220D01*
X523732Y631530D01*
X523655Y631892D01*
X523387Y632150D01*
X523118Y632253D01*
X522773D01*
G01X523118D02*
X523348Y632408D01*
X523540Y632667D01*
X523617Y632977D01*
X523540Y633287D01*
X523348Y633545D01*
X523003Y633700D01*
X522658Y633648D01*
X522313Y633442D01*
G01X516317Y625413D02*
X515144D01*
G01X516317Y622272D02*
Y625413D01*
G01X509678Y640911D02*
X512878D01*
G01X516678D02*
X519878D01*
G01X513178D02*
X516378D01*
G01X520178D02*
X523378D01*
G01X519064Y668553D02*
X516801D01*
G01X511864D02*
X514132D01*
G01X511064D02*
X508757D01*
G01X519064Y674753D02*
Y668553D01*
G01X511864D02*
Y674753D01*
G01X511064D02*
Y668553D01*
G01X515064Y673964D02*
Y669390D01*
G01X515864Y673964D02*
Y669390D01*
G01X507064Y673846D02*
Y669396D01*
G01X507864Y673846D02*
Y669396D01*
G01X519064Y674753D02*
X516742D01*
G01X511864D02*
X514003D01*
G01X511064D02*
X508754D01*
G01X510516Y692221D02*
Y690872D01*
G01Y687403D02*
Y688272D01*
G01Y696162D02*
Y694781D01*
G01Y711419D02*
Y699020D01*
G01X519827Y687403D02*
X527170D01*
G01X515963D02*
X517312D01*
G01X510516D02*
X513279D01*
G01X521306Y711419D02*
X519827D01*
G01X510516D02*
X517436D01*
G01X517685Y730096D02*
X519777D01*
G01X524885D02*
X522665D01*
G01X521685Y724856D02*
Y729321D01*
G01X520885Y724856D02*
Y729321D01*
G01X516885Y730096D02*
X514777D01*
G01X509685D02*
X511781D01*
G01X512885Y724788D02*
Y729192D01*
G01X513685Y724788D02*
Y729192D01*
G01X517685Y723896D02*
X519947D01*
G01X524885D02*
X522705D01*
G01X516885D02*
X514708D01*
G01X509685D02*
X511969D01*
G01X517685D02*
Y730096D01*
G01X516885D02*
Y723896D01*
G01X509685D02*
Y730096D01*
G01X520307Y747843D02*
X514107D01*
Y751043D01*
X520307D01*
Y747843D01*
G01X512794Y766396D02*
Y779996D01*
G01X521594Y766396D02*
Y772196D01*
G01Y766396D02*
X512794D01*
G01X515812Y757307D02*
Y763507D01*
X519012D01*
Y757307D01*
X515812D01*
G01X510696Y760390D02*
Y754190D01*
X507496D01*
Y760390D01*
X510696D01*
G01X525919Y763481D02*
Y757281D01*
X522719D01*
Y763481D01*
X525919D01*
G01X515104Y763507D02*
Y757307D01*
X511904D01*
Y763507D01*
X515104D01*
G01X521594Y774196D02*
Y779996D01*
G01X512794D02*
X521594D01*
G01Y772196D02*
X520094Y773196D01*
X521594Y774196D01*
G01X512976Y784703D02*
Y790903D01*
X516176D01*
Y784703D01*
X512976D01*
G01X518163Y784630D02*
Y790830D01*
X521363D01*
Y784630D01*
X518163D01*
G01X510841Y846249D02*
Y843049D01*
G01X507629Y857677D02*
X534972D01*
G01X507629D02*
Y917913D01*
G01X519716Y867145D02*
X527007D01*
G01X519716Y908445D02*
Y867145D01*
G01X549598Y908445D02*
X519716D01*
G01X507629Y917913D02*
X562315D01*
G01X532120Y969804D02*
Y967854D01*
X522120D01*
G01D02*
Y979804D01*
G01X509170Y968333D02*
Y971533D01*
G01X515370Y968333D02*
X509170D01*
G01X515370Y971533D02*
Y968333D01*
G01X509170Y971533D02*
X515370D01*
G01X509122Y972285D02*
Y975485D01*
G01X515322Y972285D02*
X509122D01*
G01X515322Y975485D02*
Y972285D01*
G01X509122Y975485D02*
X515322D01*
G01X522120Y985904D02*
Y997854D01*
X532120D01*
Y995904D01*
G01X521903Y999421D02*
Y1002521D01*
X522823D01*
X523130Y1002366D01*
X523360Y1002004D01*
X523437Y1001591D01*
X523360Y1001178D01*
X523168Y1000868D01*
X522823Y1000713D01*
X521903D01*
G01X525003Y1000041D02*
X525195Y999731D01*
X525425Y999524D01*
X525693Y999421D01*
X526000Y999524D01*
X526230Y999731D01*
X526460Y1000041D01*
X526537Y1000454D01*
Y1002521D01*
G01X528103Y999421D02*
Y1002521D01*
X529023D01*
X529330Y1002366D01*
X529560Y1002004D01*
X529637Y1001591D01*
X529560Y1001178D01*
X529368Y1000868D01*
X529023Y1000713D01*
X528103D01*
G01X531970Y999421D02*
Y1002521D01*
X531510Y1001901D01*
G01Y999421D02*
X532430D01*
G01X513691Y1002366D02*
Y999166D01*
G01X507491Y1002366D02*
X513691D01*
G01X507491Y999166D02*
Y1002366D01*
G01X513691Y999166D02*
X507491D01*
G01X513691Y1003166D02*
X507491D01*
Y1006366D01*
X513691D01*
Y1003166D01*
G01Y995166D02*
X507491D01*
Y998366D01*
X513691D01*
Y995166D01*
G01Y1017866D02*
Y1014666D01*
G01X507491Y1017866D02*
X513691D01*
G01X507491Y1014666D02*
Y1017866D01*
G01X513691Y1014666D02*
X507491D01*
G01X513691Y1018666D02*
X507491D01*
Y1021866D01*
X513691D01*
Y1018666D01*
G01Y1029166D02*
X507491D01*
Y1032366D01*
X513691D01*
Y1029166D01*
G01X507558Y1059606D02*
Y1053406D01*
G01X507956Y1080348D02*
Y1062632D01*
G01X514831Y1096088D02*
Y1090088D01*
G01X506783Y1107230D02*
X509983D01*
G01X506783Y1101030D02*
Y1107230D01*
G01X509983Y1101030D02*
X506783D01*
G01X509983Y1107230D02*
Y1101030D01*
G01X511505Y1100426D02*
Y1097226D01*
G01X510570Y1107230D02*
X513770D01*
G01X510570Y1101030D02*
Y1107230D01*
G01X513770Y1101030D02*
X510570D01*
G01X513770Y1107230D02*
Y1101030D01*
G01X521847Y1103442D02*
Y1097242D01*
X518647D01*
Y1103442D01*
X521847D01*
G01X525074Y1136752D02*
X519076D01*
G01X522066Y1213533D02*
Y1177793D01*
G01X522067Y1176643D02*
X522063Y1178152D01*
G01X519076Y1174548D02*
X525074D01*
G01X518991Y1249202D02*
X532480D01*
G01X517280Y1247418D02*
X508380D01*
G01X517280Y1267704D02*
Y1247418D01*
G01X508380D02*
Y1267704D01*
G01X522140Y1271921D02*
Y1268821D01*
X523674D01*
G01X525279Y1271404D02*
X525509Y1271714D01*
X525777Y1271869D01*
X526084Y1271921D01*
X526467Y1271818D01*
X526735Y1271559D01*
X526812Y1271249D01*
X526774Y1270939D01*
X526620Y1270681D01*
X525854Y1270164D01*
X525509Y1269803D01*
X525279Y1269286D01*
X525202Y1268821D01*
X526812D01*
G01X528455Y1269183D02*
X528724Y1268924D01*
X529030Y1268821D01*
X529337Y1268924D01*
X529605Y1269234D01*
X529797Y1269699D01*
X529874Y1270164D01*
Y1270733D01*
X529797Y1271198D01*
X529605Y1271611D01*
X529375Y1271818D01*
X529107Y1271921D01*
X528800Y1271818D01*
X528570Y1271611D01*
X528417Y1271301D01*
X528340Y1270888D01*
X528417Y1270526D01*
X528609Y1270164D01*
X528839Y1269958D01*
X529107Y1269906D01*
X529414Y1270009D01*
X529644Y1270268D01*
X529874Y1270733D01*
G01X532480Y1266904D02*
X518948D01*
G01X508380Y1267704D02*
X517280D01*
G01X536457Y78540D02*
Y81740D01*
G01X542657Y78540D02*
X536457D01*
G01Y81740D02*
X542657D01*
G01X536457Y74540D02*
Y77740D01*
G01X542657Y74540D02*
X536457D01*
G01Y77740D02*
X542657D01*
G01X536457Y82540D02*
Y85740D01*
G01X542657Y82540D02*
X536457D01*
G01Y85740D02*
X542657D01*
G01X540077Y86929D02*
X536877D01*
G01Y93129D02*
X540077D01*
G01X536877Y86929D02*
Y93129D01*
G01X532068Y86929D02*
X528868D01*
G01X532068Y93129D02*
Y86929D01*
G01X528868Y93129D02*
X532068D01*
G01X528868Y86929D02*
Y93129D01*
G01X536068Y86929D02*
X532868D01*
G01X536068Y93129D02*
Y86929D01*
G01X532868Y93129D02*
X536068D01*
G01X532868Y86929D02*
Y93129D01*
G01X526064Y97026D02*
Y103226D01*
G01X529264Y97026D02*
X526064D01*
G01X529264Y103226D02*
Y97026D01*
G01X528068Y86929D02*
X524868D01*
G01X528068Y93129D02*
Y86929D01*
G01X524868Y93129D02*
X528068D01*
G01X524868Y86929D02*
Y93129D01*
G01X536147Y96673D02*
Y102873D01*
G01X539347Y96673D02*
X536147D01*
G01X532147D02*
Y102873D01*
G01X535347Y96673D02*
X532147D01*
G01X535347Y102873D02*
Y96673D01*
G01X526064Y103226D02*
X529264D01*
G01X536147Y102873D02*
X539347D01*
G01X532147D02*
X535347D01*
G01X538130Y144690D02*
Y154138D01*
G01X548966Y144690D02*
X538130D01*
G01X533732Y139647D02*
Y142847D01*
G01X539932Y139647D02*
X533732D01*
G01Y142847D02*
X539932D01*
G01X529762Y145940D02*
Y149140D01*
G01X535962Y145940D02*
X529762D01*
G01X535962Y149140D02*
Y145940D01*
G01X529762Y149140D02*
X535962D01*
G01X527432Y164436D02*
Y195440D01*
G01X538649Y155642D02*
X538342Y155694D01*
X538074Y155900D01*
X537844Y156210D01*
X537691Y156572D01*
X537614Y156985D01*
Y157399D01*
X537691Y157812D01*
X537844Y158174D01*
X538074Y158484D01*
X538342Y158690D01*
X538649Y158742D01*
X538956Y158690D01*
X539224Y158484D01*
X539454Y158174D01*
X539607Y157812D01*
X539684Y157399D01*
Y156985D01*
X539607Y156572D01*
X539454Y156210D01*
X539224Y155900D01*
X538956Y155694D01*
X538649Y155642D01*
G01X538956Y156469D02*
X539416Y155642D01*
G01X541021Y158225D02*
X541251Y158535D01*
X541519Y158690D01*
X541826Y158742D01*
X542209Y158639D01*
X542477Y158380D01*
X542554Y158070D01*
X542516Y157760D01*
X542362Y157502D01*
X541596Y156985D01*
X541251Y156624D01*
X541021Y156107D01*
X540944Y155642D01*
X542554D01*
G01X544121Y158225D02*
X544351Y158535D01*
X544619Y158690D01*
X544926Y158742D01*
X545309Y158639D01*
X545577Y158380D01*
X545654Y158070D01*
X545616Y157760D01*
X545462Y157502D01*
X544696Y156985D01*
X544351Y156624D01*
X544121Y156107D01*
X544044Y155642D01*
X545654D01*
G01X547949D02*
Y158742D01*
X547489Y158122D01*
G01Y155642D02*
X548409D01*
G01X538130Y154138D02*
X541548D01*
G01X535962Y153140D02*
Y149940D01*
G01X529762Y153140D02*
X535962D01*
G01X529762Y149940D02*
Y153140D01*
G01X535962Y149940D02*
X529762D01*
G01X536398Y171473D02*
X533198D01*
G01X536398Y177673D02*
Y171473D01*
G01X533198Y177673D02*
X536398D01*
G01X533198Y171473D02*
Y177673D01*
G01X532398Y171473D02*
X529198D01*
G01X532398Y177673D02*
Y171473D01*
G01X529198Y177673D02*
X532398D01*
G01X529198Y171473D02*
Y177673D01*
G01X533221Y170297D02*
X539421D01*
G01X533221Y167097D02*
Y170297D01*
G01X539421Y167097D02*
X533221D01*
G01X536625Y182730D02*
X533425D01*
G01X536625Y188930D02*
Y182730D01*
G01X533425Y188930D02*
X536625D01*
G01X533425Y182730D02*
Y188930D01*
G01X533416Y193541D02*
X539616D01*
G01X533416Y190341D02*
Y193541D01*
G01X539616Y190341D02*
X533416D01*
G01X524745Y213035D02*
Y225035D01*
G01X530745Y213035D02*
X524745D01*
G01X530745Y225035D02*
Y213035D01*
G01X553901Y220252D02*
Y208048D01*
X538597D01*
Y220252D01*
X553901D01*
G01X524745Y225035D02*
X530745D01*
G01X531585Y226621D02*
Y232621D01*
G01X543585Y226621D02*
X531585D01*
G01X535564Y215082D02*
X532364D01*
G01X535564Y221282D02*
Y215082D01*
G01X532364Y221282D02*
X535564D01*
G01X532364Y215082D02*
Y221282D01*
G01X535385Y225921D02*
X541585D01*
G01X535385Y222721D02*
Y225921D01*
G01X541585Y222721D02*
X535385D01*
G01X531585Y232621D02*
X543585D01*
G01X524028Y250325D02*
Y234813D01*
G01D02*
X555120D01*
G01X524207Y251936D02*
Y255036D01*
X525127D01*
X525434Y254881D01*
X525664Y254519D01*
X525741Y254106D01*
X525664Y253693D01*
X525472Y253383D01*
X525127Y253228D01*
X524207D01*
G01X527231Y251936D02*
Y255036D01*
X527997D01*
X528304Y254881D01*
X528534Y254674D01*
X528726Y254364D01*
X528879Y254003D01*
X528917Y253486D01*
X528879Y252969D01*
X528726Y252608D01*
X528534Y252298D01*
X528304Y252091D01*
X527997Y251936D01*
X527231D01*
G01X531174D02*
Y255036D01*
X530714Y254416D01*
G01Y251936D02*
X531634D01*
G01X533546Y253228D02*
X533814Y253589D01*
X534044Y253796D01*
X534351Y253899D01*
X534619Y253796D01*
X534811Y253589D01*
X534964Y253279D01*
X535002Y252918D01*
X534964Y252608D01*
X534811Y252298D01*
X534581Y252039D01*
X534312Y251936D01*
X534006Y252039D01*
X533737Y252349D01*
X533584Y252814D01*
X533546Y253331D01*
X533622Y254003D01*
X533737Y254364D01*
X533929Y254726D01*
X534197Y254984D01*
X534466Y255036D01*
X534734Y254933D01*
X534926Y254674D01*
G01X555120Y250325D02*
X524028D01*
G01X532253Y258010D02*
Y264210D01*
G01X535453Y258010D02*
X532253D01*
G01X535453Y264210D02*
Y258010D01*
G01X539453D02*
X536253D01*
G01D02*
Y264210D01*
G01X524323Y271655D02*
Y283655D01*
G01X530323Y271655D02*
X524323D01*
G01X530323Y283655D02*
Y271655D01*
G01X532253Y264210D02*
X535453D01*
G01X536253D02*
X539453D01*
G01X533212Y267653D02*
Y279427D01*
G01X542974Y267653D02*
X533212D01*
G01X524323Y283655D02*
X530323D01*
G01X534506Y283383D02*
X531306D01*
G01X534506Y289583D02*
Y283383D01*
G01X531306Y289583D02*
X534506D01*
G01X531306Y283383D02*
Y289583D01*
G01X538506Y283383D02*
X535306D01*
G01X538506Y289583D02*
Y283383D01*
G01X535306Y289583D02*
X538506D01*
G01X535306Y283383D02*
Y289583D01*
G01X533212Y279427D02*
X542974D01*
G01X534086Y344123D02*
Y347323D01*
G01X540286Y344123D02*
X534086D01*
G01Y347323D02*
X540286D01*
G01X534086Y357623D02*
Y360823D01*
G01X540286Y357623D02*
X534086D01*
G01Y356323D02*
X540286D01*
G01X534086Y353123D02*
Y356323D01*
G01X540286Y353123D02*
X534086D01*
G01Y351823D02*
X540286D01*
G01X534086Y348623D02*
Y351823D01*
G01X540286Y348623D02*
X534086D01*
G01Y360823D02*
X540286D01*
G01X534086Y365323D02*
X540286D01*
G01X534086Y362123D02*
Y365323D01*
G01X540286Y362123D02*
X534086D01*
G01Y375623D02*
Y378823D01*
G01X540286Y375623D02*
X534086D01*
G01Y374323D02*
X540286D01*
G01X534086Y371123D02*
Y374323D01*
G01X540286Y371123D02*
X534086D01*
G01Y369823D02*
X540286D01*
G01X534086Y366623D02*
Y369823D01*
G01X540286Y366623D02*
X534086D01*
G01X530467Y392709D02*
Y395909D01*
G01X536667Y392709D02*
X530467D01*
G01X536667Y395909D02*
Y392709D01*
G01X534086Y378823D02*
X540286D01*
G01X534086Y380123D02*
Y383323D01*
G01X540286Y380123D02*
X534086D01*
G01Y383323D02*
X540286D01*
G01X534086Y387823D02*
X540286D01*
G01X534086Y384623D02*
Y387823D01*
G01X540286Y384623D02*
X534086D01*
G01Y392323D02*
X540286D01*
G01X534086Y389123D02*
Y392323D01*
G01X540286Y389123D02*
X534086D01*
G01X530467Y395909D02*
X536667D01*
G01X530729Y455419D02*
Y443419D01*
G01X524729Y455419D02*
X530729D01*
G01X524729Y443419D02*
Y455419D01*
G01X530729Y443419D02*
X524729D01*
G01X523121Y458381D02*
Y446607D01*
G01X540860Y471194D02*
Y473434D01*
G01X539235Y472221D02*
X542485D01*
G01X534712Y474835D02*
Y504394D01*
G01X546208Y474835D02*
X534712D01*
G01X532650Y493811D02*
Y481811D01*
G01X526650D02*
Y493811D01*
G01X532650Y481811D02*
X526650D01*
G01X525789Y480988D02*
Y474988D01*
G01X525031Y491764D02*
Y485564D01*
G01X540760Y507934D02*
Y505508D01*
G01X534712Y504394D02*
X546208D01*
G01X523536Y503265D02*
Y518777D01*
G01X526650Y493811D02*
X532650D01*
G01X540600Y521183D02*
X537500D01*
Y522103D01*
X537655Y522410D01*
X538017Y522640D01*
X538430Y522717D01*
X538843Y522640D01*
X539153Y522448D01*
X539308Y522103D01*
Y521183D01*
G01X540600Y524207D02*
X537500D01*
Y524973D01*
X537655Y525280D01*
X537862Y525510D01*
X538172Y525702D01*
X538533Y525855D01*
X539050Y525893D01*
X539567Y525855D01*
X539928Y525702D01*
X540238Y525510D01*
X540445Y525280D01*
X540600Y524973D01*
Y524207D01*
G01Y528150D02*
X537500D01*
X538120Y527690D01*
G01X540600D02*
Y528610D01*
G01Y531710D02*
X537500D01*
X539722Y530292D01*
Y532208D01*
G01X531029Y516938D02*
Y519178D01*
G01X529404Y517965D02*
X532654D01*
G01X524881Y520579D02*
Y550138D01*
G01X536377Y520579D02*
X524881D01*
G01X536377Y550138D02*
Y520579D01*
G01X538383Y551278D02*
Y548852D01*
G01X524881Y550138D02*
X536377D01*
G01X535762Y570014D02*
Y573214D01*
G01X541962Y570014D02*
X535762D01*
G01X538500Y583857D02*
X540722D01*
X541187Y584010D01*
X541497Y584317D01*
X541600Y584700D01*
X541497Y585083D01*
X541187Y585390D01*
X540722Y585543D01*
X538500D01*
G01X541600Y587800D02*
X541548Y588068D01*
X541393Y588375D01*
X541135Y588567D01*
X540773Y588643D01*
X540412Y588567D01*
X540102Y588337D01*
X539947Y587992D01*
Y587608D01*
X539843Y587378D01*
X539585Y587187D01*
X539223Y587110D01*
X538862Y587225D01*
X538603Y587493D01*
X538500Y587800D01*
X538603Y588107D01*
X538862Y588375D01*
X539223Y588490D01*
X539585Y588413D01*
X539843Y588222D01*
X539947Y587992D01*
Y587608D01*
X540102Y587263D01*
X540412Y587033D01*
X540773Y586957D01*
X541135Y587033D01*
X541393Y587225D01*
X541548Y587532D01*
X541600Y587800D01*
G01Y590900D02*
X538500D01*
X539120Y590440D01*
G01X541600D02*
Y591360D01*
G01X524679Y581942D02*
Y583895D01*
G01X526632Y581942D02*
X524679D01*
G01X536491D02*
X534538D01*
G01X536491Y583895D02*
Y581942D01*
G01X535762Y577214D02*
X541962D01*
G01X535762Y574014D02*
Y577214D01*
G01X541962Y574014D02*
X535762D01*
G01X530705Y577441D02*
Y574241D01*
G01X524505Y577441D02*
X530705D01*
G01X524505Y574241D02*
Y577441D01*
G01X530705Y574241D02*
X524505D01*
G01X523094Y580432D02*
Y574232D01*
G01X535762Y573214D02*
X541962D01*
G01X524679Y593754D02*
X526632D01*
G01X524679Y591801D02*
Y593754D01*
G01X534538D02*
X536491D01*
G01D02*
Y591801D01*
G01X530370Y598125D02*
X527170D01*
G01X530370Y604325D02*
Y598125D01*
G01X527170D02*
Y604325D01*
G01X534370Y598125D02*
X531170D01*
G01X534370Y604325D02*
Y598125D01*
G01X531170D02*
Y604325D01*
G01X538370Y598125D02*
X535170D01*
G01X538370Y604325D02*
Y598125D01*
G01X535170D02*
Y604325D01*
G01X526370Y598125D02*
X523170D01*
G01X526370Y604325D02*
Y598125D01*
G01X523170D02*
Y604325D01*
G01X525022Y609615D02*
X540534D01*
G01X525022Y640707D02*
Y609615D01*
G01X527170Y604325D02*
X530370D01*
G01X531170D02*
X534370D01*
G01X535170D02*
X538370D01*
G01X523170D02*
X526370D01*
G01X523378Y640911D02*
Y634711D01*
G01X540534Y640707D02*
X525022D01*
G01X532364Y668553D02*
X534543D01*
G01X539564D02*
X537351D01*
G01X524364D02*
X526416D01*
G01X531564D02*
X529552D01*
G01X532364D02*
Y674753D01*
G01X531564D02*
Y668553D01*
G01X524364D02*
Y674753D01*
G01X535564Y673871D02*
Y669391D01*
G01X536364Y673871D02*
Y669391D01*
G01X527564Y673880D02*
Y669331D01*
G01X528364Y673880D02*
Y669331D01*
G01X539564Y674753D02*
X537371D01*
G01X532364D02*
X534514D01*
G01X531564D02*
X529422D01*
G01X524364D02*
X526485D01*
G01X534532Y700527D02*
Y704020D01*
G01Y696587D02*
Y698215D01*
G01Y692687D02*
Y694285D01*
G01Y687403D02*
Y690356D01*
G01X529721Y687403D02*
X531139D01*
G01X534532D02*
X533491D01*
G01X525265Y711419D02*
X523807D01*
G01X529234D02*
X527696D01*
G01X534532D02*
X531863D01*
G01X534532Y706451D02*
Y708087D01*
G01Y711419D02*
Y710370D01*
G01X540885Y730096D02*
X538691D01*
G01X533685D02*
X535773D01*
G01X536885Y724797D02*
Y729203D01*
G01X537685Y724797D02*
Y729203D01*
G01X532885Y730096D02*
X530563D01*
G01X525685D02*
X527914D01*
G01X528885Y724817D02*
Y729178D01*
G01X529685Y724817D02*
Y729178D01*
G01X540885Y723896D02*
X538759D01*
G01X533685D02*
X535921D01*
G01X532885D02*
X530772D01*
G01X525685D02*
X527895D01*
G01X533685D02*
Y730096D01*
G01X532885D02*
Y723896D01*
G01X525685D02*
Y730096D01*
G01X524885D02*
Y723896D01*
G01X538177Y743455D02*
Y741233D01*
X538330Y740768D01*
X538637Y740458D01*
X539020Y740355D01*
X539403Y740458D01*
X539710Y740768D01*
X539863Y741233D01*
Y743455D01*
G01X542580Y740355D02*
Y743455D01*
X541162Y741233D01*
X543078D01*
G01X545680Y740355D02*
Y743455D01*
X544262Y741233D01*
X546178D01*
G01X548320Y743455D02*
X548013Y743352D01*
X547783Y743093D01*
X547630Y742783D01*
X547515Y742370D01*
X547477Y741905D01*
X547515Y741440D01*
X547630Y741027D01*
X547783Y740717D01*
X548013Y740458D01*
X548320Y740355D01*
X548627Y740458D01*
X548857Y740717D01*
X549010Y741027D01*
X549125Y741440D01*
X549163Y741905D01*
X549125Y742370D01*
X549010Y742783D01*
X548857Y743093D01*
X548627Y743352D01*
X548320Y743455D01*
G01X534575Y757828D02*
Y770428D01*
G01X549975Y757828D02*
X534575D01*
G01X532424Y777189D02*
X542624D01*
G01X532424Y772589D02*
Y777189D01*
G01X542624Y772589D02*
X532424D01*
G01X537924Y778289D02*
Y781489D01*
G01X544124Y778289D02*
X537924D01*
G01Y781489D02*
X544124D01*
G01X537124D02*
Y778289D01*
G01X530924Y781489D02*
X537124D01*
G01X530924Y778289D02*
Y781489D01*
G01X537124Y778289D02*
X530924D01*
G01X534575Y770428D02*
X549975D01*
G01X523707Y790500D02*
Y788278D01*
X523860Y787813D01*
X524167Y787503D01*
X524550Y787400D01*
X524933Y787503D01*
X525240Y787813D01*
X525393Y788278D01*
Y790500D01*
G01X526998Y787762D02*
X527267Y787503D01*
X527573Y787400D01*
X527880Y787503D01*
X528148Y787813D01*
X528340Y788278D01*
X528417Y788743D01*
Y789312D01*
X528340Y789777D01*
X528148Y790190D01*
X527918Y790397D01*
X527650Y790500D01*
X527343Y790397D01*
X527113Y790190D01*
X526960Y789880D01*
X526883Y789467D01*
X526960Y789105D01*
X527152Y788743D01*
X527382Y788537D01*
X527650Y788485D01*
X527957Y788588D01*
X528187Y788847D01*
X528417Y789312D01*
G01X530750Y787400D02*
X531018Y787452D01*
X531325Y787607D01*
X531517Y787865D01*
X531593Y788227D01*
X531517Y788588D01*
X531287Y788898D01*
X530942Y789053D01*
X530558D01*
X530328Y789157D01*
X530137Y789415D01*
X530060Y789777D01*
X530175Y790138D01*
X530443Y790397D01*
X530750Y790500D01*
X531057Y790397D01*
X531325Y790138D01*
X531440Y789777D01*
X531363Y789415D01*
X531172Y789157D01*
X530942Y789053D01*
X530558D01*
X530213Y788898D01*
X529983Y788588D01*
X529907Y788227D01*
X529983Y787865D01*
X530175Y787607D01*
X530482Y787452D01*
X530750Y787400D01*
G01X529554Y791984D02*
X533536D01*
G01X529554Y795966D02*
Y791984D01*
G01Y831748D02*
Y827766D01*
G01X533786Y839100D02*
X527586D01*
Y842300D01*
X533786D01*
Y839100D01*
G01X533536Y831748D02*
X529554D01*
G01X584047Y857677D02*
X534972D01*
G01X562315D02*
X534972D01*
G01X528707Y856558D02*
Y854336D01*
X528860Y853871D01*
X529167Y853561D01*
X529550Y853458D01*
X529933Y853561D01*
X530240Y853871D01*
X530393Y854336D01*
Y856558D01*
G01X531807Y854078D02*
X532037Y853716D01*
X532343Y853510D01*
X532688Y853458D01*
X532995Y853510D01*
X533302Y853768D01*
X533493Y854078D01*
X533532Y854388D01*
X533455Y854750D01*
X533187Y855008D01*
X532918Y855111D01*
X532573D01*
G01X532918D02*
X533148Y855266D01*
X533340Y855525D01*
X533417Y855835D01*
X533340Y856145D01*
X533148Y856403D01*
X532803Y856558D01*
X532458Y856506D01*
X532113Y856300D01*
G01X535022Y856041D02*
X535252Y856351D01*
X535520Y856506D01*
X535827Y856558D01*
X536210Y856455D01*
X536478Y856196D01*
X536555Y855886D01*
X536517Y855576D01*
X536363Y855318D01*
X535597Y854801D01*
X535252Y854440D01*
X535022Y853923D01*
X534945Y853458D01*
X536555D01*
G01X538850Y856558D02*
X538543Y856455D01*
X538313Y856196D01*
X538160Y855886D01*
X538045Y855473D01*
X538007Y855008D01*
X538045Y854543D01*
X538160Y854130D01*
X538313Y853820D01*
X538543Y853561D01*
X538850Y853458D01*
X539157Y853561D01*
X539387Y853820D01*
X539540Y854130D01*
X539655Y854543D01*
X539693Y855008D01*
X539655Y855473D01*
X539540Y855886D01*
X539387Y856196D01*
X539157Y856455D01*
X538850Y856558D01*
G01X527007Y867145D02*
X534657Y874795D01*
G01D02*
X542307Y867145D01*
G01X532120Y989804D02*
Y975904D01*
G01X535115Y1004721D02*
Y1010921D01*
G01X538315Y1004721D02*
X535115D01*
G01X538315Y1010921D02*
Y1004721D01*
G01X527479Y1013844D02*
X527172Y1013896D01*
X526904Y1014102D01*
X526674Y1014412D01*
X526521Y1014774D01*
X526444Y1015187D01*
Y1015601D01*
X526521Y1016014D01*
X526674Y1016376D01*
X526904Y1016686D01*
X527172Y1016892D01*
X527479Y1016944D01*
X527786Y1016892D01*
X528054Y1016686D01*
X528284Y1016376D01*
X528437Y1016014D01*
X528514Y1015601D01*
Y1015187D01*
X528437Y1014774D01*
X528284Y1014412D01*
X528054Y1014102D01*
X527786Y1013896D01*
X527479Y1013844D01*
G01X527786Y1014671D02*
X528246Y1013844D01*
G01X530579D02*
Y1016944D01*
X530119Y1016324D01*
G01Y1013844D02*
X531039D01*
G01X534139D02*
Y1016944D01*
X532721Y1014722D01*
X534637D01*
G01X535115Y1010921D02*
X538315D01*
G01X536886Y1043789D02*
Y1046889D01*
G01X538496D02*
Y1043789D01*
G01Y1045339D02*
X536886D01*
G01X540791Y1043789D02*
X541059Y1043841D01*
X541366Y1043996D01*
X541558Y1044254D01*
X541634Y1044616D01*
X541558Y1044977D01*
X541328Y1045287D01*
X540983Y1045442D01*
X540599D01*
X540369Y1045546D01*
X540178Y1045804D01*
X540101Y1046166D01*
X540216Y1046527D01*
X540484Y1046786D01*
X540791Y1046889D01*
X541098Y1046786D01*
X541366Y1046527D01*
X541481Y1046166D01*
X541404Y1045804D01*
X541213Y1045546D01*
X540983Y1045442D01*
X540599D01*
X540254Y1045287D01*
X540024Y1044977D01*
X539948Y1044616D01*
X540024Y1044254D01*
X540216Y1043996D01*
X540523Y1043841D01*
X540791Y1043789D01*
G01X543239Y1044151D02*
X543508Y1043892D01*
X543814Y1043789D01*
X544121Y1043892D01*
X544389Y1044202D01*
X544581Y1044667D01*
X544658Y1045132D01*
Y1045701D01*
X544581Y1046166D01*
X544389Y1046579D01*
X544159Y1046786D01*
X543891Y1046889D01*
X543584Y1046786D01*
X543354Y1046579D01*
X543201Y1046269D01*
X543124Y1045856D01*
X543201Y1045494D01*
X543393Y1045132D01*
X543623Y1044926D01*
X543891Y1044874D01*
X544198Y1044977D01*
X544428Y1045236D01*
X544658Y1045701D01*
G01X523580Y1102117D02*
Y1105317D01*
G01X529780Y1102117D02*
X523580D01*
G01X529780Y1105317D02*
Y1102117D01*
G01X523580Y1105317D02*
X529780D01*
G01X534595Y1103367D02*
Y1106467D01*
G01X536205D02*
Y1103367D01*
G01Y1104917D02*
X534595D01*
G01X538500Y1103367D02*
Y1106467D01*
X538040Y1105847D01*
G01Y1103367D02*
X538960D01*
G01X540757Y1103987D02*
X540987Y1103625D01*
X541293Y1103419D01*
X541638Y1103367D01*
X541945Y1103419D01*
X542252Y1103677D01*
X542443Y1103987D01*
X542482Y1104297D01*
X542405Y1104659D01*
X542137Y1104917D01*
X541868Y1105020D01*
X541523D01*
G01X541868D02*
X542098Y1105175D01*
X542290Y1105434D01*
X542367Y1105744D01*
X542290Y1106054D01*
X542098Y1106312D01*
X541753Y1106467D01*
X541408Y1106415D01*
X541063Y1106209D01*
G01X543857Y1103832D02*
X544087Y1103574D01*
X544355Y1103419D01*
X544700Y1103367D01*
X545045Y1103470D01*
X545313Y1103677D01*
X545505Y1104039D01*
X545543Y1104452D01*
X545467Y1104865D01*
X545275Y1105124D01*
X545007Y1105330D01*
X544738Y1105382D01*
X544470Y1105330D01*
X544125Y1105124D01*
X544240Y1106467D01*
X545275D01*
G01X527400Y1114996D02*
X530600D01*
G01X527400Y1108796D02*
Y1114996D01*
G01X530600Y1108796D02*
X527400D01*
G01X530600Y1114996D02*
Y1108796D01*
G01Y1119296D02*
X527400D01*
G01X530600Y1125496D02*
Y1119296D01*
G01X527400D02*
Y1125496D01*
G01X524769Y1109839D02*
X523761D01*
G01X524769Y1111693D02*
Y1109839D01*
G01Y1124250D02*
Y1122552D01*
G01X537649Y1111688D02*
X534549D01*
Y1112608D01*
X534704Y1112915D01*
X535066Y1113145D01*
X535479Y1113222D01*
X535892Y1113145D01*
X536202Y1112953D01*
X536357Y1112608D01*
Y1111688D01*
G01X534549Y1114712D02*
X536771D01*
X537236Y1114865D01*
X537546Y1115172D01*
X537649Y1115555D01*
X537546Y1115938D01*
X537236Y1116245D01*
X536771Y1116398D01*
X534549D01*
G01X537649Y1118578D02*
X536977Y1118655D01*
X536409Y1118770D01*
X535892Y1118923D01*
X535324Y1119115D01*
X534549Y1119422D01*
Y1117888D01*
G01X527400Y1125496D02*
X530600D01*
G01X524769Y1133461D02*
Y1130861D01*
G01X523976Y1133461D02*
X524769D01*
G01X525074Y1174548D02*
Y1136752D01*
G01X540539Y1139259D02*
X537439D01*
Y1140179D01*
X537594Y1140486D01*
X537956Y1140716D01*
X538369Y1140793D01*
X538782Y1140716D01*
X539092Y1140524D01*
X539247Y1140179D01*
Y1139259D01*
G01X537439Y1142359D02*
X540539D01*
Y1143893D01*
G01Y1146149D02*
X539867Y1146226D01*
X539299Y1146341D01*
X538782Y1146494D01*
X538214Y1146686D01*
X537439Y1146993D01*
Y1145459D01*
G01X534785Y1139110D02*
X531685D01*
Y1140030D01*
X531840Y1140337D01*
X532202Y1140567D01*
X532615Y1140644D01*
X533028Y1140567D01*
X533338Y1140375D01*
X533493Y1140030D01*
Y1139110D01*
G01X531685Y1142210D02*
X534785D01*
Y1143744D01*
G01X533493Y1145349D02*
X533132Y1145617D01*
X532925Y1145847D01*
X532822Y1146154D01*
X532925Y1146422D01*
X533132Y1146614D01*
X533442Y1146767D01*
X533803Y1146805D01*
X534113Y1146767D01*
X534423Y1146614D01*
X534682Y1146384D01*
X534785Y1146115D01*
X534682Y1145809D01*
X534372Y1145540D01*
X533907Y1145387D01*
X533390Y1145349D01*
X532718Y1145425D01*
X532357Y1145540D01*
X531995Y1145732D01*
X531737Y1146000D01*
X531685Y1146269D01*
X531788Y1146537D01*
X532047Y1146729D01*
G01X526674Y1153659D02*
Y1159859D01*
G01X529874Y1153659D02*
X526674D01*
G01X529874Y1159859D02*
Y1153659D01*
G01X526674Y1159859D02*
X529874D01*
G01X524066Y1189471D02*
Y1201471D01*
G01X530066Y1189471D02*
X524066D01*
G01X530066Y1201471D02*
Y1189471D01*
G01X524066Y1201471D02*
X530066D01*
G01X528420Y1220253D02*
Y1210053D01*
X523820D01*
Y1220253D01*
X528420D01*
G01X532480Y1249202D02*
Y1266904D01*
G01X553323Y70181D02*
Y66981D01*
G01X547123D02*
Y70181D01*
G01X553323Y66981D02*
X547123D01*
G01X542657Y81740D02*
Y78540D01*
G01Y77740D02*
Y74540D01*
G01Y85740D02*
Y82540D01*
G01X547123Y70181D02*
X553323D01*
G01Y82181D02*
Y78981D01*
G01X547123Y82181D02*
X553323D01*
G01X547123Y78981D02*
Y82181D01*
G01X553323Y78981D02*
X547123D01*
G01X547168Y74987D02*
Y78187D01*
G01X553368Y74987D02*
X547168D01*
G01X553368Y78187D02*
Y74987D01*
G01X547168Y78187D02*
X553368D01*
G01X547168Y70987D02*
Y74187D01*
G01X553368Y70987D02*
X547168D01*
G01X553368Y74187D02*
Y70987D01*
G01X547168Y74187D02*
X553368D01*
G01X540077Y93129D02*
Y86929D01*
G01X554158Y93476D02*
X557358D01*
G01X554158Y87276D02*
Y93476D01*
G01X557358Y87276D02*
X554158D01*
G01X539347Y102873D02*
Y96673D01*
G01X541651Y95950D02*
Y102150D01*
G01X544851Y95950D02*
X541651D01*
G01X544851Y102150D02*
Y95950D01*
G01X546315Y95913D02*
Y111267D01*
G01X558796Y95913D02*
X546315D01*
G01X552666Y116088D02*
X558866D01*
G01X552666Y112888D02*
Y116088D01*
G01X558866Y112888D02*
X552666D01*
G01X541651Y109762D02*
X544851D01*
G01X541651Y103562D02*
Y109762D01*
G01X544851Y103562D02*
X541651D01*
G01X544851Y109762D02*
Y103562D01*
G01X541651Y102150D02*
X544851D01*
G01X546315Y111267D02*
X558993D01*
G01X548966Y154138D02*
Y144690D01*
G01X540711Y139647D02*
Y142847D01*
G01X546911Y139647D02*
X540711D01*
G01X546911Y142847D02*
Y139647D01*
G01X540711Y142847D02*
X546911D01*
G01X550373Y148168D02*
Y151368D01*
G01X556573Y148168D02*
X550373D01*
G01Y144168D02*
Y147368D01*
G01X556573Y144168D02*
X550373D01*
G01Y147368D02*
X556573D01*
G01X539932Y142847D02*
Y139647D01*
G01X545548Y154138D02*
X548966D01*
G01X543548Y152414D02*
X545548Y154138D01*
G01X541548D02*
X543548Y152414D01*
G01X550373Y151368D02*
X556573D01*
G01X543257Y175100D02*
Y172878D01*
X543410Y172413D01*
X543717Y172103D01*
X544100Y172000D01*
X544483Y172103D01*
X544790Y172413D01*
X544943Y172878D01*
Y175100D01*
G01X546357Y172465D02*
X546587Y172207D01*
X546855Y172052D01*
X547200Y172000D01*
X547545Y172103D01*
X547813Y172310D01*
X548005Y172672D01*
X548043Y173085D01*
X547967Y173498D01*
X547775Y173757D01*
X547507Y173963D01*
X547238Y174015D01*
X546970Y173963D01*
X546625Y173757D01*
X546740Y175100D01*
X547775D01*
G01X549648Y172362D02*
X549917Y172103D01*
X550223Y172000D01*
X550530Y172103D01*
X550798Y172413D01*
X550990Y172878D01*
X551067Y173343D01*
Y173912D01*
X550990Y174377D01*
X550798Y174790D01*
X550568Y174997D01*
X550300Y175100D01*
X549993Y174997D01*
X549763Y174790D01*
X549610Y174480D01*
X549533Y174067D01*
X549610Y173705D01*
X549802Y173343D01*
X550032Y173137D01*
X550300Y173085D01*
X550607Y173188D01*
X550837Y173447D01*
X551067Y173912D01*
G01X552938Y178897D02*
Y176944D01*
G01X541126D02*
Y178897D01*
G01X543079Y176944D02*
X541126D01*
G01X552938D02*
X550985D01*
G01X539421Y170297D02*
Y167097D01*
G01X541126Y188756D02*
X543079D01*
G01X541126Y186803D02*
Y188756D01*
G01X552938D02*
Y186803D01*
G01X550985Y188756D02*
X552938D01*
G01X539616Y193541D02*
Y190341D01*
G01X540921Y200895D02*
Y203995D01*
X541841D01*
X542148Y203840D01*
X542378Y203478D01*
X542455Y203065D01*
X542378Y202652D01*
X542186Y202342D01*
X541841Y202187D01*
X540921D01*
G01X543945Y203995D02*
Y201773D01*
X544098Y201308D01*
X544405Y200998D01*
X544788Y200895D01*
X545171Y200998D01*
X545478Y201308D01*
X545631Y201773D01*
Y203995D01*
G01X547045Y201515D02*
X547275Y201153D01*
X547581Y200947D01*
X547926Y200895D01*
X548233Y200947D01*
X548540Y201205D01*
X548731Y201515D01*
X548770Y201825D01*
X548693Y202187D01*
X548425Y202445D01*
X548156Y202548D01*
X547811D01*
G01X548156D02*
X548386Y202703D01*
X548578Y202962D01*
X548655Y203272D01*
X548578Y203582D01*
X548386Y203840D01*
X548041Y203995D01*
X547696Y203943D01*
X547351Y203737D01*
G01X550988Y200895D02*
Y203995D01*
X550528Y203375D01*
G01Y200895D02*
X551448D01*
G01X543585Y232621D02*
Y226621D01*
G01X541585Y225921D02*
Y222721D01*
G01X555120Y234813D02*
Y250325D01*
G01X540253Y258010D02*
Y264210D01*
G01X543453Y258010D02*
X540253D01*
G01X543453Y264210D02*
Y258010D01*
G01X539453Y264210D02*
Y258010D01*
G01X550164Y264635D02*
X565676D01*
G01X550164Y295727D02*
Y264635D01*
G01X548532Y273701D02*
X545332D01*
G01X548532Y279901D02*
Y273701D01*
G01X545332D02*
Y279901D01*
G01X540253Y264210D02*
X543453D01*
G01X542974Y279427D02*
Y267653D01*
G01X545332Y279901D02*
X548532D01*
G01X539306Y283383D02*
Y289583D01*
X542506D01*
Y283383D01*
X539306D01*
G01X547000Y282633D02*
X543900D01*
Y283553D01*
X544055Y283860D01*
X544417Y284090D01*
X544830Y284167D01*
X545243Y284090D01*
X545553Y283898D01*
X545708Y283553D01*
Y282633D01*
G01X543900Y285657D02*
X546122D01*
X546587Y285810D01*
X546897Y286117D01*
X547000Y286500D01*
X546897Y286883D01*
X546587Y287190D01*
X546122Y287343D01*
X543900D01*
G01X547000Y289600D02*
X543900D01*
X544520Y289140D01*
G01X547000D02*
Y290060D01*
G01X543900Y292700D02*
X544003Y292393D01*
X544262Y292163D01*
X544572Y292010D01*
X544985Y291895D01*
X545450Y291857D01*
X545915Y291895D01*
X546328Y292010D01*
X546638Y292163D01*
X546897Y292393D01*
X547000Y292700D01*
X546897Y293007D01*
X546638Y293237D01*
X546328Y293390D01*
X545915Y293505D01*
X545450Y293543D01*
X544985Y293505D01*
X544572Y293390D01*
X544262Y293237D01*
X544003Y293007D01*
X543900Y292700D01*
G01X547000Y295723D02*
X546328Y295800D01*
X545760Y295915D01*
X545243Y296068D01*
X544675Y296260D01*
X543900Y296567D01*
Y295033D01*
G01X565676Y295727D02*
X550164D01*
G01X550286Y347323D02*
Y344123D01*
G01X544086D02*
Y347323D01*
G01X550286Y344123D02*
X544086D01*
G01X540286Y347323D02*
Y344123D01*
G01X544086Y347323D02*
X550286D01*
G01Y351823D02*
Y348623D01*
G01X544086Y351823D02*
X550286D01*
G01X544086Y348623D02*
Y351823D01*
G01X550286Y348623D02*
X544086D01*
G01X550286Y360823D02*
Y357623D01*
G01X544086D02*
Y360823D01*
G01X550286Y357623D02*
X544086D01*
G01X550286Y356323D02*
Y353123D01*
G01X544086Y356323D02*
X550286D01*
G01X544086Y353123D02*
Y356323D01*
G01X550286Y353123D02*
X544086D01*
G01X540286Y360823D02*
Y357623D01*
G01Y356323D02*
Y353123D01*
G01Y351823D02*
Y348623D01*
G01X544086Y360823D02*
X550286D01*
G01Y378823D02*
Y375623D01*
G01X544086D02*
Y378823D01*
G01X550286Y375623D02*
X544086D01*
G01X550286Y374323D02*
Y371123D01*
G01X544086Y374323D02*
X550286D01*
G01X544086Y371123D02*
Y374323D01*
G01X550286Y371123D02*
X544086D01*
G01X550286Y369823D02*
Y366623D01*
G01X544086Y369823D02*
X550286D01*
G01X544086Y366623D02*
Y369823D01*
G01X550286Y366623D02*
X544086D01*
G01X550286Y365323D02*
Y362123D01*
G01X544086Y365323D02*
X550286D01*
G01X544086Y362123D02*
Y365323D01*
G01X550286Y362123D02*
X544086D01*
G01X540286Y365323D02*
Y362123D01*
G01Y378823D02*
Y375623D01*
G01Y374323D02*
Y371123D01*
G01Y369823D02*
Y366623D01*
G01X544086Y378823D02*
X550286D01*
G01Y383323D02*
Y380123D01*
G01X544086Y383323D02*
X550286D01*
G01X544086Y380123D02*
Y383323D01*
G01X550286Y380123D02*
X544086D01*
G01Y384623D02*
Y387823D01*
G01X550286Y384623D02*
X544086D01*
G01X550286Y387823D02*
Y384623D01*
G01X544086Y387823D02*
X550286D01*
G01X544086Y389123D02*
Y392323D01*
G01X550286Y389123D02*
X544086D01*
G01X550286Y392323D02*
Y389123D01*
G01X544086Y392323D02*
X550286D01*
G01X540286Y383323D02*
Y380123D01*
G01Y387823D02*
Y384623D01*
G01Y392323D02*
Y389123D01*
G01X551109Y475256D02*
X548009D01*
Y476176D01*
X548164Y476483D01*
X548526Y476713D01*
X548939Y476790D01*
X549352Y476713D01*
X549662Y476521D01*
X549817Y476176D01*
Y475256D01*
G01X551109Y478280D02*
X548009D01*
Y479046D01*
X548164Y479353D01*
X548371Y479583D01*
X548681Y479775D01*
X549042Y479928D01*
X549559Y479966D01*
X550076Y479928D01*
X550437Y479775D01*
X550747Y479583D01*
X550954Y479353D01*
X551109Y479046D01*
Y478280D01*
G01X550644Y481380D02*
X550902Y481610D01*
X551057Y481878D01*
X551109Y482223D01*
X551006Y482568D01*
X550799Y482836D01*
X550437Y483028D01*
X550024Y483066D01*
X549611Y482990D01*
X549352Y482798D01*
X549146Y482530D01*
X549094Y482261D01*
X549146Y481993D01*
X549352Y481648D01*
X548009Y481763D01*
Y482798D01*
G01X549817Y484595D02*
X549456Y484863D01*
X549249Y485093D01*
X549146Y485400D01*
X549249Y485668D01*
X549456Y485860D01*
X549766Y486013D01*
X550127Y486051D01*
X550437Y486013D01*
X550747Y485860D01*
X551006Y485630D01*
X551109Y485361D01*
X551006Y485055D01*
X550696Y484786D01*
X550231Y484633D01*
X549714Y484595D01*
X549042Y484671D01*
X548681Y484786D01*
X548319Y484978D01*
X548061Y485246D01*
X548009Y485515D01*
X548112Y485783D01*
X548371Y485975D01*
G01X546208Y504394D02*
Y474835D01*
G01X569798Y543227D02*
X554198D01*
X569798Y552197D01*
X554198D01*
G01Y563272D02*
Y567952D01*
G01Y565612D02*
X569798D01*
G01Y563272D02*
Y567952D01*
G01X555498Y587802D02*
X554718Y586632D01*
X554198Y585267D01*
Y583707D01*
X554978Y581952D01*
X556278Y580587D01*
X557838Y579612D01*
X560438Y578832D01*
X562778Y578637D01*
X565118Y579027D01*
X566678Y579612D01*
X568238Y580782D01*
X569278Y582147D01*
X569798Y583512D01*
Y584877D01*
X569278Y586242D01*
X568498Y587412D01*
X567458Y588387D01*
G01X556798Y597707D02*
X555238Y598877D01*
X554458Y600242D01*
X554198Y601802D01*
X554718Y603752D01*
X556018Y605117D01*
X557578Y605507D01*
X559138Y605312D01*
X560438Y604532D01*
X563038Y600632D01*
X564858Y598877D01*
X567458Y597707D01*
X569798Y597317D01*
Y605507D01*
G01X548999Y553448D02*
Y568248D01*
G01X541962Y573214D02*
Y570014D01*
G01Y577214D02*
Y574014D01*
G01X543138Y580237D02*
X546338D01*
G01X543138Y574037D02*
Y580237D01*
G01X546338Y574037D02*
X543138D01*
G01X546338Y580237D02*
Y574037D01*
G01X546370Y598125D02*
X543170D01*
G01X546370Y604325D02*
Y598125D01*
G01X543170D02*
Y604325D01*
G01X542370Y598125D02*
X539170D01*
G01X542370Y604325D02*
Y598125D01*
G01X539170D02*
Y604325D01*
G01X545000Y609783D02*
X541900D01*
Y610703D01*
X542055Y611010D01*
X542417Y611240D01*
X542830Y611317D01*
X543243Y611240D01*
X543553Y611048D01*
X543708Y610703D01*
Y609783D01*
G01X545000Y612807D02*
X541900D01*
Y613573D01*
X542055Y613880D01*
X542262Y614110D01*
X542572Y614302D01*
X542933Y614455D01*
X543450Y614493D01*
X543967Y614455D01*
X544328Y614302D01*
X544638Y614110D01*
X544845Y613880D01*
X545000Y613573D01*
Y612807D01*
G01Y616750D02*
X544948Y617018D01*
X544793Y617325D01*
X544535Y617517D01*
X544173Y617593D01*
X543812Y617517D01*
X543502Y617287D01*
X543347Y616942D01*
Y616558D01*
X543243Y616328D01*
X542985Y616137D01*
X542623Y616060D01*
X542262Y616175D01*
X542003Y616443D01*
X541900Y616750D01*
X542003Y617057D01*
X542262Y617325D01*
X542623Y617440D01*
X542985Y617363D01*
X543243Y617172D01*
X543347Y616942D01*
Y616558D01*
X543502Y616213D01*
X543812Y615983D01*
X544173Y615907D01*
X544535Y615983D01*
X544793Y616175D01*
X544948Y616482D01*
X545000Y616750D01*
G01Y619850D02*
X541900D01*
X542520Y619390D01*
G01X545000D02*
Y620310D01*
G01X540534Y609615D02*
Y640707D01*
G01X543170Y604325D02*
X546370D01*
G01X539170D02*
X542370D01*
G01X539564Y674753D02*
Y668553D01*
G01X554573Y682909D02*
Y685019D01*
G01X548373Y682909D02*
Y685077D01*
G01X554573Y682909D02*
X548373D01*
G01X554573Y690109D02*
Y687817D01*
G01X549238Y686909D02*
X553790D01*
G01X549238Y686109D02*
X553790D01*
G01X554573Y690909D02*
Y692946D01*
G01Y698109D02*
Y695794D01*
G01X549199Y694909D02*
X553809D01*
G01X549199Y694109D02*
X553809D01*
G01X554573Y698909D02*
Y701022D01*
G01X548373Y698909D02*
Y701062D01*
G01Y690909D02*
Y693045D01*
G01Y698109D02*
Y696082D01*
G01Y690109D02*
Y688026D01*
G01X554573Y698909D02*
X548373D01*
G01Y690109D02*
X554573D01*
G01Y690909D02*
X548373D01*
G01Y698109D02*
X554573D01*
G01Y706109D02*
Y703846D01*
G01X549169Y702909D02*
X553794D01*
G01X549169Y702109D02*
X553794D01*
G01X554573Y706909D02*
Y709109D01*
G01Y714109D02*
Y711798D01*
G01X549187Y710909D02*
X553793D01*
G01X549187Y710109D02*
X553793D01*
G01X554573Y714909D02*
Y716999D01*
G01X548373Y714909D02*
Y717137D01*
G01Y706909D02*
Y709100D01*
G01Y714109D02*
Y712018D01*
G01Y706109D02*
Y704009D01*
G01Y706109D02*
X554573D01*
G01Y706909D02*
X548373D01*
G01Y714109D02*
X554573D01*
G01Y714909D02*
X548373D01*
G01X554573Y722109D02*
Y719847D01*
G01X549188Y718109D02*
X553723D01*
G01X549188Y718909D02*
X553723D01*
G01X548373Y722109D02*
Y720014D01*
G01Y722109D02*
X554573D01*
G01X540885Y730096D02*
Y723896D01*
G01X564695Y742758D02*
X551095D01*
G01D02*
Y751558D01*
G01X551081Y740158D02*
X557281D01*
Y736958D01*
X551081D01*
Y740158D01*
G01X543102Y748114D02*
X549302D01*
Y744914D01*
X543102D01*
Y748114D01*
G01X556895Y751558D02*
X551095D01*
G01X543350Y753200D02*
Y754595D01*
X542583Y756300D01*
G01X544117D02*
X543350Y754595D01*
G01X546910Y753200D02*
Y756300D01*
X545492Y754078D01*
X547408D01*
G01X549975Y770428D02*
Y757828D01*
G01X542624Y777189D02*
Y772589D01*
G01X544124Y781489D02*
Y778289D01*
G01X547104Y844089D02*
Y848689D01*
G01X557304Y844089D02*
X547104D01*
G01X551026Y842988D02*
X557226D01*
G01X551026Y839788D02*
Y842988D01*
G01X557226Y839788D02*
X551026D01*
G01X540800Y843214D02*
Y849414D01*
X544000D01*
Y843214D01*
X540800D01*
G01X547104Y848689D02*
X557304D01*
G01X549598Y867145D02*
Y908445D01*
G01X542307Y867145D02*
X549598D01*
G01X543333Y972011D02*
X543695Y972241D01*
X543901Y972547D01*
X543953Y972892D01*
X543901Y973199D01*
X543643Y973506D01*
X543333Y973697D01*
X543023Y973736D01*
X542661Y973659D01*
X542403Y973391D01*
X542300Y973122D01*
Y972777D01*
G01Y973122D02*
X542145Y973352D01*
X541886Y973544D01*
X541576Y973621D01*
X541266Y973544D01*
X541008Y973352D01*
X540853Y973007D01*
X540905Y972662D01*
X541111Y972317D01*
G01X551323Y987631D02*
X554523D01*
G01X551323Y981431D02*
Y987631D01*
G01X554523Y981431D02*
X551323D01*
G01X554523Y987631D02*
Y981431D01*
G01X551323Y990431D02*
Y996631D01*
G01X554523Y990431D02*
X551323D01*
G01X554523Y996631D02*
Y990431D01*
G01X555323Y987631D02*
X558523D01*
G01X555323Y981431D02*
Y987631D01*
G01X558523Y981431D02*
X555323D01*
G01Y990431D02*
Y996631D01*
G01X558523Y990431D02*
X555323D01*
G01X539891Y1007489D02*
Y1016937D01*
G01X550727Y1007489D02*
X539891D01*
G01X550727Y1016937D02*
Y1007489D01*
G01X545114Y995164D02*
Y998264D01*
X545880D01*
X546187Y998109D01*
X546417Y997902D01*
X546609Y997592D01*
X546762Y997231D01*
X546800Y996714D01*
X546762Y996197D01*
X546609Y995836D01*
X546417Y995526D01*
X546187Y995319D01*
X545880Y995164D01*
X545114D01*
G01X548329Y997747D02*
X548559Y998057D01*
X548827Y998212D01*
X549134Y998264D01*
X549517Y998161D01*
X549785Y997902D01*
X549862Y997592D01*
X549824Y997282D01*
X549670Y997024D01*
X548904Y996507D01*
X548559Y996146D01*
X548329Y995629D01*
X548252Y995164D01*
X549862D01*
G01X553185Y1005249D02*
Y1001499D01*
G01X546045Y1005249D02*
X553185D01*
G01X546045Y1001449D02*
Y1005249D01*
G01X553135Y1001449D02*
X546045D01*
G01X545545Y1005249D02*
X552735D01*
G01X545545Y1001449D02*
Y1005249D01*
G01X552735Y1001449D02*
X545545D01*
G01X545045Y1005249D02*
X552135D01*
G01X545045Y1001449D02*
Y1005249D01*
G01X552135Y1001449D02*
X545045D01*
G01X551323Y996631D02*
X554523D01*
G01X555323D02*
X558523D01*
G01X553096Y1009297D02*
Y1015497D01*
G01X556296Y1009297D02*
X553096D01*
G01X547309Y1016937D02*
X550727D01*
G01X545309Y1015213D02*
X547309Y1016937D01*
G01X543309D02*
X545309Y1015213D01*
G01X539891Y1016937D02*
X543309D01*
G01X551758Y1025363D02*
Y1029963D01*
G01X561958Y1025363D02*
X551758D01*
G01X553096Y1015497D02*
X556296D01*
G01X546998Y1019577D02*
Y1022777D01*
G01X553198Y1019577D02*
X546998D01*
G01X553198Y1022777D02*
Y1019577D01*
G01X546998Y1022777D02*
X553198D01*
G01X549744Y1023702D02*
X546544D01*
G01X549744Y1029902D02*
Y1023702D01*
G01X546544D02*
Y1029902D01*
G01X539703Y1019448D02*
Y1022648D01*
G01X545903Y1019448D02*
X539703D01*
G01X545903Y1022648D02*
Y1019448D01*
G01X539703Y1022648D02*
X545903D01*
G01X551758Y1029963D02*
X561958D01*
G01X546544Y1029902D02*
X549744D01*
G01X543084Y1073409D02*
G03X605314Y1066535I30735J-6873D01*
G01X596395Y1088496D02*
G03X550521Y1087728I-22576J-21960D01*
G01X552650Y1111650D02*
X549550D01*
Y1112570D01*
X549705Y1112877D01*
X550067Y1113107D01*
X550480Y1113184D01*
X550893Y1113107D01*
X551203Y1112915D01*
X551358Y1112570D01*
Y1111650D01*
G01X549550Y1114674D02*
X551772D01*
X552237Y1114827D01*
X552547Y1115134D01*
X552650Y1115517D01*
X552547Y1115900D01*
X552237Y1116207D01*
X551772Y1116360D01*
X549550D01*
G01X552650Y1118617D02*
X549550D01*
X550170Y1118157D01*
G01X552650D02*
Y1119077D01*
G01X549550Y1121717D02*
X549653Y1121410D01*
X549912Y1121180D01*
X550222Y1121027D01*
X550635Y1120912D01*
X551100Y1120874D01*
X551565Y1120912D01*
X551978Y1121027D01*
X552288Y1121180D01*
X552547Y1121410D01*
X552650Y1121717D01*
X552547Y1122024D01*
X552288Y1122254D01*
X551978Y1122407D01*
X551565Y1122522D01*
X551100Y1122560D01*
X550635Y1122522D01*
X550222Y1122407D01*
X549912Y1122254D01*
X549653Y1122024D01*
X549550Y1121717D01*
G01X547110Y1111611D02*
X544010D01*
Y1112531D01*
X544165Y1112838D01*
X544527Y1113068D01*
X544940Y1113145D01*
X545353Y1113068D01*
X545663Y1112876D01*
X545818Y1112531D01*
Y1111611D01*
G01X544010Y1114635D02*
X546232D01*
X546697Y1114788D01*
X547007Y1115095D01*
X547110Y1115478D01*
X547007Y1115861D01*
X546697Y1116168D01*
X546232Y1116321D01*
X544010D01*
G01X546748Y1117926D02*
X547007Y1118195D01*
X547110Y1118501D01*
X547007Y1118808D01*
X546697Y1119076D01*
X546232Y1119268D01*
X545767Y1119345D01*
X545198D01*
X544733Y1119268D01*
X544320Y1119076D01*
X544113Y1118846D01*
X544010Y1118578D01*
X544113Y1118271D01*
X544320Y1118041D01*
X544630Y1117888D01*
X545043Y1117811D01*
X545405Y1117888D01*
X545767Y1118080D01*
X545973Y1118310D01*
X546025Y1118578D01*
X545922Y1118885D01*
X545663Y1119115D01*
X545198Y1119345D01*
G01X542323Y1111615D02*
X539223D01*
Y1112535D01*
X539378Y1112842D01*
X539740Y1113072D01*
X540153Y1113149D01*
X540566Y1113072D01*
X540876Y1112880D01*
X541031Y1112535D01*
Y1111615D01*
G01X539223Y1114639D02*
X541445D01*
X541910Y1114792D01*
X542220Y1115099D01*
X542323Y1115482D01*
X542220Y1115865D01*
X541910Y1116172D01*
X541445Y1116325D01*
X539223D01*
G01X542323Y1118582D02*
X542271Y1118850D01*
X542116Y1119157D01*
X541858Y1119349D01*
X541496Y1119425D01*
X541135Y1119349D01*
X540825Y1119119D01*
X540670Y1118774D01*
Y1118390D01*
X540566Y1118160D01*
X540308Y1117969D01*
X539946Y1117892D01*
X539585Y1118007D01*
X539326Y1118275D01*
X539223Y1118582D01*
X539326Y1118889D01*
X539585Y1119157D01*
X539946Y1119272D01*
X540308Y1119195D01*
X540566Y1119004D01*
X540670Y1118774D01*
Y1118390D01*
X540825Y1118045D01*
X541135Y1117815D01*
X541496Y1117739D01*
X541858Y1117815D01*
X542116Y1118007D01*
X542271Y1118314D01*
X542323Y1118582D01*
G01X553911Y1139152D02*
X550811D01*
Y1140072D01*
X550966Y1140379D01*
X551328Y1140609D01*
X551741Y1140686D01*
X552154Y1140609D01*
X552464Y1140417D01*
X552619Y1140072D01*
Y1139152D01*
G01X550811Y1142252D02*
X553911D01*
Y1143786D01*
G01Y1146119D02*
X550811D01*
X551431Y1145659D01*
G01X553911D02*
Y1146579D01*
G01X550811Y1149219D02*
X550914Y1148912D01*
X551173Y1148682D01*
X551483Y1148529D01*
X551896Y1148414D01*
X552361Y1148376D01*
X552826Y1148414D01*
X553239Y1148529D01*
X553549Y1148682D01*
X553808Y1148912D01*
X553911Y1149219D01*
X553808Y1149526D01*
X553549Y1149756D01*
X553239Y1149909D01*
X552826Y1150024D01*
X552361Y1150062D01*
X551896Y1150024D01*
X551483Y1149909D01*
X551173Y1149756D01*
X550914Y1149526D01*
X550811Y1149219D01*
G01X547060Y1139259D02*
X543960D01*
Y1140179D01*
X544115Y1140486D01*
X544477Y1140716D01*
X544890Y1140793D01*
X545303Y1140716D01*
X545613Y1140524D01*
X545768Y1140179D01*
Y1139259D01*
G01X543960Y1142359D02*
X547060D01*
Y1143893D01*
G01X546698Y1145574D02*
X546957Y1145843D01*
X547060Y1146149D01*
X546957Y1146456D01*
X546647Y1146724D01*
X546182Y1146916D01*
X545717Y1146993D01*
X545148D01*
X544683Y1146916D01*
X544270Y1146724D01*
X544063Y1146494D01*
X543960Y1146226D01*
X544063Y1145919D01*
X544270Y1145689D01*
X544580Y1145536D01*
X544993Y1145459D01*
X545355Y1145536D01*
X545717Y1145728D01*
X545923Y1145958D01*
X545975Y1146226D01*
X545872Y1146533D01*
X545613Y1146763D01*
X545148Y1146993D01*
G01X605314Y1263386D02*
G03X594782Y1239881I-31496J0D01*
G01X548682Y1291095D02*
Y1294195D01*
G01X550292D02*
Y1291095D01*
G01Y1292645D02*
X548682D01*
G01X551935Y1291457D02*
X552204Y1291198D01*
X552510Y1291095D01*
X552817Y1291198D01*
X553085Y1291508D01*
X553277Y1291973D01*
X553354Y1292438D01*
Y1293007D01*
X553277Y1293472D01*
X553085Y1293885D01*
X552855Y1294092D01*
X552587Y1294195D01*
X552280Y1294092D01*
X552050Y1293885D01*
X551897Y1293575D01*
X551820Y1293162D01*
X551897Y1292800D01*
X552089Y1292438D01*
X552319Y1292232D01*
X552587Y1292180D01*
X552894Y1292283D01*
X553124Y1292542D01*
X553354Y1293007D01*
G01X554959Y1293678D02*
X555189Y1293988D01*
X555457Y1294143D01*
X555764Y1294195D01*
X556147Y1294092D01*
X556415Y1293833D01*
X556492Y1293523D01*
X556454Y1293213D01*
X556300Y1292955D01*
X555534Y1292438D01*
X555189Y1292077D01*
X554959Y1291560D01*
X554882Y1291095D01*
X556492D01*
G01X552599Y1436123D02*
Y1425158D01*
G01Y1689331D02*
Y1441312D01*
G01X540788Y1441038D02*
Y1677520D01*
G01X551308Y1453654D02*
X543808D01*
Y1455894D01*
X544183Y1456641D01*
X545058Y1457201D01*
X546058Y1457388D01*
X547058Y1457201D01*
X547808Y1456734D01*
X548183Y1455894D01*
Y1453654D01*
G01X551308Y1461154D02*
X543808D01*
Y1463488D01*
X544183Y1464234D01*
X544683Y1464701D01*
X545683Y1464888D01*
X546683Y1464701D01*
X547308Y1464141D01*
X547683Y1463488D01*
Y1461154D01*
G01Y1463488D02*
X551308Y1464888D01*
G01Y1472388D02*
Y1468654D01*
X543808D01*
Y1472388D01*
G01X547433Y1470894D02*
Y1468654D01*
G01X550308Y1476061D02*
X550933Y1476808D01*
X551308Y1477648D01*
Y1478394D01*
X550933Y1479141D01*
X550308Y1479701D01*
X549433Y1479981D01*
X548558Y1479794D01*
X547808Y1479328D01*
X547308Y1478488D01*
X547058Y1477368D01*
X546558Y1476714D01*
X545683Y1476434D01*
X544808Y1476621D01*
X544183Y1477088D01*
X543808Y1477741D01*
Y1478394D01*
X544058Y1479048D01*
X544683Y1479608D01*
G01X550308Y1483561D02*
X550933Y1484308D01*
X551308Y1485148D01*
Y1485894D01*
X550933Y1486641D01*
X550308Y1487201D01*
X549433Y1487481D01*
X548558Y1487294D01*
X547808Y1486828D01*
X547308Y1485988D01*
X547058Y1484868D01*
X546558Y1484214D01*
X545683Y1483934D01*
X544808Y1484121D01*
X544183Y1484588D01*
X543808Y1485241D01*
Y1485894D01*
X544058Y1486548D01*
X544683Y1487108D01*
G01X548808Y1491808D02*
Y1494234D01*
G01X551308Y1498748D02*
X543808D01*
Y1502294D01*
G01X547433Y1500988D02*
Y1498748D01*
G01X543808Y1506901D02*
Y1509141D01*
G01Y1508021D02*
X551308D01*
G01Y1506901D02*
Y1509141D01*
G01X543808Y1515521D02*
X551308D01*
G01X543808Y1513374D02*
Y1517668D01*
G01X561337Y1604823D02*
X562137Y1605323D01*
X562670Y1605923D01*
X562937Y1606623D01*
X562670Y1607423D01*
X562137Y1608023D01*
X561337Y1608623D01*
X560270Y1608823D01*
X554937D01*
G01X562937Y1614823D02*
X554937D01*
X556537Y1613623D01*
G01X562937D02*
Y1616023D01*
G01X556270Y1620923D02*
X555470Y1621523D01*
X555070Y1622223D01*
X554937Y1623023D01*
X555204Y1624023D01*
X555870Y1624723D01*
X556670Y1624923D01*
X557471Y1624823D01*
X558137Y1624423D01*
X559470Y1622423D01*
X560404Y1621523D01*
X561737Y1620923D01*
X562937Y1620723D01*
Y1624923D01*
G01X569100Y67707D02*
X571322D01*
X571787Y67860D01*
X572097Y68167D01*
X572200Y68550D01*
X572097Y68933D01*
X571787Y69240D01*
X571322Y69393D01*
X569100D01*
G01X572200Y71650D02*
X569100D01*
X569720Y71190D01*
G01X572200D02*
Y72110D01*
G01X571580Y73907D02*
X571942Y74137D01*
X572148Y74443D01*
X572200Y74788D01*
X572148Y75095D01*
X571890Y75402D01*
X571580Y75593D01*
X571270Y75632D01*
X570908Y75555D01*
X570650Y75287D01*
X570547Y75018D01*
Y74673D01*
G01Y75018D02*
X570392Y75248D01*
X570133Y75440D01*
X569823Y75517D01*
X569513Y75440D01*
X569255Y75248D01*
X569100Y74903D01*
X569152Y74558D01*
X569358Y74213D01*
G01X569100Y77850D02*
X569203Y77543D01*
X569462Y77313D01*
X569772Y77160D01*
X570185Y77045D01*
X570650Y77007D01*
X571115Y77045D01*
X571528Y77160D01*
X571838Y77313D01*
X572097Y77543D01*
X572200Y77850D01*
X572097Y78157D01*
X571838Y78387D01*
X571528Y78540D01*
X571115Y78655D01*
X570650Y78693D01*
X570185Y78655D01*
X569772Y78540D01*
X569462Y78387D01*
X569203Y78157D01*
X569100Y77850D01*
G01X567955Y67523D02*
X555751D01*
G01X567955Y79047D02*
Y67523D01*
G01X555751D02*
Y70183D01*
G01X562648Y59613D02*
Y56413D01*
G01X556448Y59613D02*
X562648D01*
G01X556448Y56413D02*
Y59613D01*
G01X562648Y56413D02*
X556448D01*
G01X555751Y79047D02*
X567955D01*
G01X555751Y76285D02*
Y79047D01*
G01X558853Y73285D02*
X555751Y76285D01*
G01Y70183D02*
X558853Y73285D01*
G01X557358Y93476D02*
Y87276D01*
G01X570714Y87299D02*
X567514D01*
G01X570714Y93499D02*
Y87299D01*
G01X567514Y93499D02*
X570714D01*
G01X567514Y87299D02*
Y93499D01*
G01X566807Y87204D02*
X563607D01*
G01X566807Y93404D02*
Y87204D01*
G01X563607Y93404D02*
X566807D01*
G01X563607Y87204D02*
Y93404D01*
G01X562858Y87276D02*
X559658D01*
G01X562858Y93476D02*
Y87276D01*
G01X559658Y93476D02*
X562858D01*
G01X559658Y87276D02*
Y93476D01*
G01X560100Y98507D02*
X562322D01*
X562787Y98660D01*
X563097Y98967D01*
X563200Y99350D01*
X563097Y99733D01*
X562787Y100040D01*
X562322Y100193D01*
X560100D01*
G01X563200Y102910D02*
X560100D01*
X562322Y101492D01*
Y103408D01*
G01X560100Y105550D02*
X560203Y105243D01*
X560462Y105013D01*
X560772Y104860D01*
X561185Y104745D01*
X561650Y104707D01*
X562115Y104745D01*
X562528Y104860D01*
X562838Y105013D01*
X563097Y105243D01*
X563200Y105550D01*
X563097Y105857D01*
X562838Y106087D01*
X562528Y106240D01*
X562115Y106355D01*
X561650Y106393D01*
X561185Y106355D01*
X560772Y106240D01*
X560462Y106087D01*
X560203Y105857D01*
X560100Y105550D01*
G01X560617Y107922D02*
X560307Y108152D01*
X560152Y108420D01*
X560100Y108727D01*
X560203Y109110D01*
X560462Y109378D01*
X560772Y109455D01*
X561082Y109417D01*
X561340Y109263D01*
X561857Y108497D01*
X562218Y108152D01*
X562735Y107922D01*
X563200Y107845D01*
Y109455D01*
G01X558993Y111267D02*
Y95913D01*
G01X560149Y111951D02*
Y118151D01*
G01X563349Y111951D02*
X560149D01*
G01X563349Y118151D02*
Y111951D01*
G01X558866Y116088D02*
Y112888D01*
G01X571069Y109424D02*
X574269D01*
G01X571069Y103224D02*
Y109424D01*
G01X574269Y103224D02*
X571069D01*
G01X567069Y109424D02*
X570269D01*
G01X567069Y103224D02*
Y109424D01*
G01X570269Y103224D02*
X567069D01*
G01X570269Y109424D02*
Y103224D01*
G01X565523Y111734D02*
Y123508D01*
G01X575285Y111734D02*
X565523D01*
G01X560149Y118151D02*
X563349D01*
G01X566294Y126223D02*
X563094D01*
G01X566294Y132423D02*
Y126223D01*
G01X563094Y132423D02*
X566294D01*
G01X563094Y126223D02*
Y132423D01*
G01X569094D02*
X572294D01*
G01X569094Y126223D02*
Y132423D01*
G01X572294Y126223D02*
X569094D01*
G01X559453Y119007D02*
X556353D01*
Y119927D01*
X556508Y120234D01*
X556870Y120464D01*
X557283Y120541D01*
X557696Y120464D01*
X558006Y120272D01*
X558161Y119927D01*
Y119007D01*
G01X556353Y122031D02*
X558575D01*
X559040Y122184D01*
X559350Y122491D01*
X559453Y122874D01*
X559350Y123257D01*
X559040Y123564D01*
X558575Y123717D01*
X556353D01*
G01X559453Y125974D02*
X556353D01*
X556973Y125514D01*
G01X559453D02*
Y126434D01*
G01X556870Y128346D02*
X556560Y128576D01*
X556405Y128844D01*
X556353Y129151D01*
X556456Y129534D01*
X556715Y129802D01*
X557025Y129879D01*
X557335Y129841D01*
X557593Y129687D01*
X558110Y128921D01*
X558471Y128576D01*
X558988Y128346D01*
X559453Y128269D01*
Y129879D01*
G01Y132634D02*
X556353D01*
X558575Y131216D01*
Y133132D01*
G01X565523Y123508D02*
X575285D01*
G01X556573Y151368D02*
Y148168D01*
G01Y147368D02*
Y144168D01*
G01X565483Y146229D02*
X562283D01*
G01X565483Y152429D02*
Y146229D01*
G01X562283D02*
Y152429D01*
G01X557700Y134307D02*
X559922D01*
X560387Y134460D01*
X560697Y134767D01*
X560800Y135150D01*
X560697Y135533D01*
X560387Y135840D01*
X559922Y135993D01*
X557700D01*
G01X560180Y137407D02*
X560542Y137637D01*
X560748Y137943D01*
X560800Y138288D01*
X560748Y138595D01*
X560490Y138902D01*
X560180Y139093D01*
X559870Y139132D01*
X559508Y139055D01*
X559250Y138787D01*
X559147Y138518D01*
Y138173D01*
G01Y138518D02*
X558992Y138748D01*
X558733Y138940D01*
X558423Y139017D01*
X558113Y138940D01*
X557855Y138748D01*
X557700Y138403D01*
X557752Y138058D01*
X557958Y137713D01*
G01X560800Y141350D02*
X560748Y141618D01*
X560593Y141925D01*
X560335Y142117D01*
X559973Y142193D01*
X559612Y142117D01*
X559302Y141887D01*
X559147Y141542D01*
Y141158D01*
X559043Y140928D01*
X558785Y140737D01*
X558423Y140660D01*
X558062Y140775D01*
X557803Y141043D01*
X557700Y141350D01*
X557803Y141657D01*
X558062Y141925D01*
X558423Y142040D01*
X558785Y141963D01*
X559043Y141772D01*
X559147Y141542D01*
Y141158D01*
X559302Y140813D01*
X559612Y140583D01*
X559973Y140507D01*
X560335Y140583D01*
X560593Y140775D01*
X560748Y141082D01*
X560800Y141350D01*
G01X559508Y143722D02*
X559147Y143990D01*
X558940Y144220D01*
X558837Y144527D01*
X558940Y144795D01*
X559147Y144987D01*
X559457Y145140D01*
X559818Y145178D01*
X560128Y145140D01*
X560438Y144987D01*
X560697Y144757D01*
X560800Y144488D01*
X560697Y144182D01*
X560387Y143913D01*
X559922Y143760D01*
X559405Y143722D01*
X558733Y143798D01*
X558372Y143913D01*
X558010Y144105D01*
X557752Y144373D01*
X557700Y144642D01*
X557803Y144910D01*
X558062Y145102D01*
G01X563973Y144395D02*
Y135095D01*
G01X574573Y144395D02*
X563973D01*
G01Y134995D02*
X574573D01*
G01X562283Y152429D02*
X565483D01*
G01X562283Y159540D02*
X565483D01*
G01X562283Y153340D02*
Y159540D01*
G01X565483Y153340D02*
X562283D01*
G01X565483Y159540D02*
Y153340D01*
G01X569383Y179800D02*
Y182900D01*
X570303D01*
X570610Y182745D01*
X570840Y182383D01*
X570917Y181970D01*
X570840Y181557D01*
X570648Y181247D01*
X570303Y181092D01*
X569383D01*
G01X572407Y179800D02*
Y182900D01*
X573173D01*
X573480Y182745D01*
X573710Y182538D01*
X573902Y182228D01*
X574055Y181867D01*
X574093Y181350D01*
X574055Y180833D01*
X573902Y180472D01*
X573710Y180162D01*
X573480Y179955D01*
X573173Y179800D01*
X572407D01*
G01X575622Y181092D02*
X575890Y181453D01*
X576120Y181660D01*
X576427Y181763D01*
X576695Y181660D01*
X576887Y181453D01*
X577040Y181143D01*
X577078Y180782D01*
X577040Y180472D01*
X576887Y180162D01*
X576657Y179903D01*
X576388Y179800D01*
X576082Y179903D01*
X575813Y180213D01*
X575660Y180678D01*
X575622Y181195D01*
X575698Y181867D01*
X575813Y182228D01*
X576005Y182590D01*
X576273Y182848D01*
X576542Y182900D01*
X576810Y182797D01*
X577002Y182538D01*
G01X578607Y180420D02*
X578837Y180058D01*
X579143Y179852D01*
X579488Y179800D01*
X579795Y179852D01*
X580102Y180110D01*
X580293Y180420D01*
X580332Y180730D01*
X580255Y181092D01*
X579987Y181350D01*
X579718Y181453D01*
X579373D01*
G01X579718D02*
X579948Y181608D01*
X580140Y181867D01*
X580217Y182177D01*
X580140Y182487D01*
X579948Y182745D01*
X579603Y182900D01*
X579258Y182848D01*
X578913Y182642D01*
G01X557309Y179065D02*
Y182265D01*
G01X563509Y179065D02*
X557309D01*
G01X563509Y182265D02*
Y179065D01*
G01X557309Y171065D02*
Y174265D01*
G01X563509Y171065D02*
X557309D01*
G01X563509Y174265D02*
Y171065D01*
G01X557309Y174265D02*
X563509D01*
G01X557309Y175065D02*
Y178265D01*
G01X563509Y175065D02*
X557309D01*
G01X563509Y178265D02*
Y175065D01*
G01X557309Y178265D02*
X563509D01*
G01X557309Y167065D02*
Y170265D01*
G01X563509Y167065D02*
X557309D01*
G01X563509Y170265D02*
Y167065D01*
G01X557309Y170265D02*
X563509D01*
G01X565077Y189435D02*
X567317D01*
G01X566104Y191060D02*
Y187810D01*
G01X568718Y195583D02*
X598277D01*
G01X568718Y184087D02*
Y195583D01*
G01X598277Y184087D02*
X568718D01*
G01X557309Y182265D02*
X563509D01*
G01X557309Y183065D02*
Y186265D01*
G01X563509Y183065D02*
X557309D01*
G01X563509Y186265D02*
Y183065D01*
G01X557309Y186265D02*
X563509D01*
G01X557309Y187065D02*
Y190265D01*
G01X563509Y187065D02*
X557309D01*
G01X563509Y190265D02*
Y187065D01*
G01X557309Y190265D02*
X563509D01*
G01Y194265D02*
Y191065D01*
G01X557309Y194265D02*
X563509D01*
G01X557309Y191065D02*
Y194265D01*
G01X563509Y191065D02*
X557309D01*
G01X563509Y198265D02*
Y195065D01*
G01X557309D02*
Y198265D01*
G01X563509Y195065D02*
X557309D01*
G01X568871Y204506D02*
Y216506D01*
G01X574871Y204506D02*
X568871D01*
G01X557309Y198265D02*
X563509D01*
G01X557404Y207264D02*
Y210464D01*
G01X563604Y207264D02*
X557404D01*
G01X563604Y210464D02*
Y207264D01*
G01X557404Y210464D02*
X563604D01*
G01Y206464D02*
Y203264D01*
G01X557404Y206464D02*
X563604D01*
G01X557404Y203264D02*
Y206464D01*
G01X563604Y203264D02*
X557404D01*
G01Y214464D02*
X563604D01*
Y211264D01*
X557404D01*
Y214464D01*
G01Y202464D02*
X563604D01*
Y199264D01*
X557404D01*
Y202464D01*
G01X568871Y216506D02*
X574871D01*
G01X557404Y215264D02*
Y218464D01*
G01X563604Y215264D02*
X557404D01*
G01X563604Y218464D02*
Y215264D01*
G01X557404Y218464D02*
X563604D01*
G01X557404Y220264D02*
Y223464D01*
G01X563604Y220264D02*
X557404D01*
G01X563604Y223464D02*
Y220264D01*
G01X557404Y223464D02*
X563604D01*
G01X557401Y227319D02*
X563601D01*
Y224119D01*
X557401D01*
Y227319D01*
G01X571639Y243678D02*
X577839D01*
G01X571639Y240478D02*
Y243678D01*
G01X577839Y240478D02*
X571639D01*
G01X567669Y246771D02*
Y249971D01*
G01X573869Y246771D02*
X567669D01*
G01Y249971D02*
X573869D01*
G01X567669Y253971D02*
X573869D01*
G01X567669Y250771D02*
Y253971D01*
G01X573869Y250771D02*
X567669D01*
G01X570200Y264983D02*
X567100D01*
Y265903D01*
X567255Y266210D01*
X567617Y266440D01*
X568030Y266517D01*
X568443Y266440D01*
X568753Y266248D01*
X568908Y265903D01*
Y264983D01*
G01X570200Y268007D02*
X567100D01*
Y268773D01*
X567255Y269080D01*
X567462Y269310D01*
X567772Y269502D01*
X568133Y269655D01*
X568650Y269693D01*
X569167Y269655D01*
X569528Y269502D01*
X569838Y269310D01*
X570045Y269080D01*
X570200Y268773D01*
Y268007D01*
G01Y271950D02*
X567100D01*
X567720Y271490D01*
G01X570200D02*
Y272410D01*
G01X567100Y275050D02*
X567203Y274743D01*
X567462Y274513D01*
X567772Y274360D01*
X568185Y274245D01*
X568650Y274207D01*
X569115Y274245D01*
X569528Y274360D01*
X569838Y274513D01*
X570097Y274743D01*
X570200Y275050D01*
X570097Y275357D01*
X569838Y275587D01*
X569528Y275740D01*
X569115Y275855D01*
X568650Y275893D01*
X568185Y275855D01*
X567772Y275740D01*
X567462Y275587D01*
X567203Y275357D01*
X567100Y275050D01*
G01X569735Y277307D02*
X569993Y277537D01*
X570148Y277805D01*
X570200Y278150D01*
X570097Y278495D01*
X569890Y278763D01*
X569528Y278955D01*
X569115Y278993D01*
X568702Y278917D01*
X568443Y278725D01*
X568237Y278457D01*
X568185Y278188D01*
X568237Y277920D01*
X568443Y277575D01*
X567100Y277690D01*
Y278725D01*
G01X565676Y264635D02*
Y295727D01*
G01X564695Y751558D02*
Y742758D01*
G01X558895Y751558D02*
X557895Y750058D01*
X556895Y751558D01*
G01X572103Y745479D02*
X565903D01*
Y748679D01*
X572103D01*
Y745479D01*
G01X565920Y744722D02*
X572120D01*
Y741522D01*
X565920D01*
Y744722D01*
G01X564695Y751558D02*
X558895D01*
G01X570064Y759574D02*
Y753374D01*
X566864D01*
Y759574D01*
X570064D01*
G01X559687Y756592D02*
X565887D01*
Y753392D01*
X559687D01*
Y756592D01*
G01X558656Y780774D02*
X561856D01*
G01X558656Y774574D02*
Y780774D01*
G01X561856Y774574D02*
X558656D01*
G01X561856Y780774D02*
Y774574D01*
G01X570514Y778300D02*
X576714D01*
Y775100D01*
X570514D01*
Y778300D01*
G01Y782300D02*
X576714D01*
Y779100D01*
X570514D01*
Y782300D01*
G01X569318Y791984D02*
Y795966D01*
G01X565336Y791984D02*
X569318D01*
G01Y827766D02*
Y831748D01*
G01X557304Y848689D02*
Y844089D01*
G01X557226Y842988D02*
Y839788D01*
G01X569318Y831748D02*
X565336D01*
G01X570364Y853682D02*
X570556Y853372D01*
X570786Y853165D01*
X571054Y853062D01*
X571361Y853165D01*
X571591Y853372D01*
X571821Y853682D01*
X571898Y854095D01*
Y856162D01*
G01X573464Y853062D02*
Y856162D01*
X574384D01*
X574691Y856007D01*
X574921Y855645D01*
X574998Y855232D01*
X574921Y854819D01*
X574729Y854509D01*
X574384Y854354D01*
X573464D01*
G01X578098Y853062D02*
X576564D01*
Y856162D01*
X578098D01*
G01X577484Y854664D02*
X576564D01*
G01X579626Y853062D02*
X581236Y856162D01*
G01X579626D02*
X581236Y853062D01*
G01X583531D02*
Y856162D01*
X583071Y855542D01*
G01Y853062D02*
X583991D01*
G01X562315Y857677D02*
Y917913D01*
G01X566972Y905545D02*
X566920Y905813D01*
X566765Y906120D01*
X566507Y906312D01*
X566145Y906388D01*
X565784Y906312D01*
X565474Y906082D01*
X565319Y905737D01*
Y905353D01*
X565215Y905123D01*
X564957Y904932D01*
X564595Y904855D01*
X564234Y904970D01*
X563975Y905238D01*
X563872Y905545D01*
X563975Y905852D01*
X564234Y906120D01*
X564595Y906235D01*
X564957Y906158D01*
X565215Y905967D01*
X565319Y905737D01*
Y905353D01*
X565474Y905008D01*
X565784Y904778D01*
X566145Y904702D01*
X566507Y904778D01*
X566765Y904970D01*
X566920Y905277D01*
X566972Y905545D01*
G01X569003Y938307D02*
X563003D01*
Y950307D01*
X569003D01*
Y938307D01*
G01X574803Y939997D02*
Y933797D01*
X571603D01*
Y939997D01*
X574803D01*
G01X558523Y987631D02*
Y981431D01*
G01Y996631D02*
Y990431D01*
G01X567323Y987631D02*
X570523D01*
G01X567323Y981431D02*
Y987631D01*
G01X570523Y981431D02*
X567323D01*
G01X570523Y987631D02*
Y981431D01*
G01X559323Y987631D02*
X562523D01*
G01X559323Y981431D02*
Y987631D01*
G01X562523Y981431D02*
X559323D01*
G01X562523Y987631D02*
Y981431D01*
G01X563323Y987631D02*
X566523D01*
G01X563323Y981431D02*
Y987631D01*
G01X566523Y981431D02*
X563323D01*
G01X566523Y987631D02*
Y981431D01*
G01X567323Y990431D02*
Y996631D01*
G01X570523Y990431D02*
X567323D01*
G01X570523Y996631D02*
Y990431D01*
G01X559323D02*
Y996631D01*
G01X562523Y990431D02*
X559323D01*
G01X562523Y996631D02*
Y990431D01*
G01X563323D02*
Y996631D01*
G01X566523Y990431D02*
X563323D01*
G01X566523Y996631D02*
Y990431D01*
G01X571323Y987631D02*
X574523D01*
G01X571323Y981431D02*
Y987631D01*
G01X574523Y981431D02*
X571323D01*
G01Y990431D02*
Y996631D01*
G01X574523Y990431D02*
X571323D01*
G01X558251Y1003053D02*
Y1007653D01*
G01X568451Y1003053D02*
X558251D01*
G01X568451Y1007653D02*
Y1003053D01*
G01X558251Y1007653D02*
X568451D01*
G01X556296Y1015497D02*
Y1009297D01*
G01X567323Y996631D02*
X570523D01*
G01X559323D02*
X562523D01*
G01X563323D02*
X566523D01*
G01X571323D02*
X574523D01*
G01X561958Y1029963D02*
Y1025363D01*
G01X565045Y1022862D02*
X569645D01*
G01X565045Y1012662D02*
Y1022862D01*
G01X569645Y1012662D02*
X565045D01*
G01X569645Y1022862D02*
Y1012662D01*
G01X557845Y1011603D02*
Y1024483D01*
G01X564245D02*
Y1011603D01*
G01X557845Y1024483D02*
X564245D01*
G01X557845Y1011603D02*
X564245D01*
G01X563245Y1025333D02*
Y1028533D01*
G01X569445Y1025333D02*
X563245D01*
G01X569445Y1028533D02*
Y1025333D01*
G01X563245Y1028533D02*
X569445D01*
G01X570420Y1105408D02*
X580620D01*
G01X570420Y1100808D02*
Y1105408D01*
G01X580620Y1100808D02*
X570420D01*
G01X569361Y1112608D02*
Y1106208D01*
G01X582241D02*
X569361D01*
G01X560811Y1102002D02*
Y1112202D01*
G01X565411Y1102002D02*
X560811D01*
G01X565411Y1112202D02*
Y1102002D01*
G01X570420Y1118008D02*
X580620D01*
G01X570420Y1113408D02*
Y1118008D01*
G01X580620Y1113408D02*
X570420D01*
G01X569361Y1112608D02*
X582241D01*
G01X569361Y1125208D02*
Y1118808D01*
G01X582241D02*
X569361D01*
G01X560811Y1112202D02*
X565411D01*
G01X560811Y1114602D02*
Y1124802D01*
G01X565411Y1114602D02*
X560811D01*
G01X565411Y1124802D02*
Y1114602D01*
G01X570420Y1130608D02*
X580620D01*
G01X570420Y1126008D02*
Y1130608D01*
G01X580620Y1126008D02*
X570420D01*
G01Y1138608D02*
Y1143208D01*
G01X580620Y1138608D02*
X570420D01*
G01X569361Y1125208D02*
X582241D01*
G01X569361Y1137808D02*
Y1131408D01*
G01X582241D02*
X569361D01*
G01Y1137808D02*
X582241D01*
G01X560811Y1124802D02*
X565411D01*
G01X560811Y1137402D02*
X565411D01*
G01X560811Y1127202D02*
Y1137402D01*
G01X565411Y1127202D02*
X560811D01*
G01X565411Y1137402D02*
Y1127202D01*
G01X560811Y1139802D02*
Y1150002D01*
G01X565411Y1139802D02*
X560811D01*
G01X565411Y1150002D02*
Y1139802D01*
G01X570420Y1143208D02*
X580620D01*
G01X570420Y1155808D02*
X580620D01*
G01X570420Y1151208D02*
Y1155808D01*
G01X580620Y1151208D02*
X570420D01*
G01X569361Y1150408D02*
Y1144008D01*
G01X582241D02*
X569361D01*
G01Y1150408D02*
X582241D01*
G01X560811Y1150002D02*
X565411D01*
G01X560811Y1152402D02*
Y1162602D01*
G01X565411Y1152402D02*
X560811D01*
G01X565411Y1162602D02*
Y1152402D01*
G01X570420Y1168408D02*
X580620D01*
G01X570420Y1163808D02*
Y1168408D01*
G01X580620Y1163808D02*
X570420D01*
G01X569361Y1163008D02*
Y1156608D01*
G01X582241D02*
X569361D01*
G01Y1163008D02*
X582241D01*
G01X569361Y1175608D02*
Y1169208D01*
G01X582241D02*
X569361D01*
G01X560811Y1162602D02*
X565411D01*
G01X560811Y1165002D02*
Y1175202D01*
G01X565411Y1165002D02*
X560811D01*
G01X565411Y1175202D02*
Y1165002D01*
G01X570420Y1181008D02*
X580620D01*
G01X570420Y1176408D02*
Y1181008D01*
G01X580620Y1176408D02*
X570420D01*
G01X569361Y1175608D02*
X582241D01*
G01X569361Y1188208D02*
Y1181808D01*
G01X582241D02*
X569361D01*
G01Y1188208D02*
X582241D01*
G01X560811Y1175202D02*
X565411D01*
G01X560811Y1187802D02*
X565411D01*
G01X560811Y1177602D02*
Y1187802D01*
G01X565411Y1177602D02*
X560811D01*
G01X565411Y1187802D02*
Y1177602D01*
G01X570071Y1202278D02*
X574455Y1206662D01*
G01X572333Y1200016D02*
X570071Y1202278D01*
G01X569505Y1202844D02*
X567243Y1205106D01*
G01X573889Y1207228D02*
X569505Y1202844D01*
G01X567243Y1205106D02*
X571627Y1209490D01*
G01X566676Y1205673D02*
X564414Y1207935D01*
G01X571060Y1210057D02*
X566676Y1205673D01*
G01X568798Y1212319D02*
X571060Y1210057D01*
G01X564414Y1207935D02*
X568798Y1212319D01*
G01X571627Y1209490D02*
X573889Y1207228D01*
G01X560666Y1211683D02*
X558404Y1213945D01*
G01X565050Y1216067D02*
X560666Y1211683D01*
G01X562788Y1218329D02*
X565050Y1216067D01*
G01X558404Y1213945D02*
X562788Y1218329D01*
G01X565970Y1215147D02*
X568232Y1212885D01*
G01X561586Y1210763D02*
X565970Y1215147D01*
G01X563848Y1208501D02*
X561586Y1210763D01*
G01X568232Y1212885D02*
X563848Y1208501D01*
G01X561088Y1228126D02*
X564288D01*
G01X561088Y1221926D02*
Y1228126D01*
G01X564288Y1221926D02*
X561088D01*
G01X564288Y1228126D02*
Y1221926D01*
G01X565088Y1228126D02*
X568288D01*
G01X565088Y1221926D02*
Y1228126D01*
G01X568288Y1221926D02*
X565088D01*
G01X568288Y1228126D02*
Y1221926D01*
G01X572340Y1223943D02*
X570078Y1226205D01*
G01D02*
X574462Y1230589D01*
G01X565842Y1529785D02*
Y1523585D01*
X562642D01*
Y1529785D01*
X565842D01*
G01X570657Y1524624D02*
Y1527824D01*
G01X576857Y1524624D02*
X570657D01*
G01Y1527824D02*
X576857D01*
G01X573542Y1548885D02*
Y1542685D01*
X570342D01*
Y1548885D01*
X573542D01*
G01X566358Y1530715D02*
Y1536915D01*
X569558D01*
Y1530715D01*
X566358D01*
G01X570209Y1540101D02*
X573409D01*
G01X570209Y1533901D02*
Y1540101D01*
G01X573409Y1533901D02*
X570209D01*
G01X564386Y1539209D02*
Y1533009D01*
G01D02*
X561186D01*
G01D02*
Y1539209D01*
G01D02*
X564386D01*
G01X560386D02*
Y1533009D01*
G01D02*
X557186D01*
G01D02*
Y1539209D01*
G01D02*
X560386D01*
G01X568012Y1564843D02*
X595768D01*
G01X568012Y1690040D02*
Y1564843D01*
G01X595768Y1647992D02*
X568012D01*
G01X595768Y1690040D02*
X568012D01*
G01X586947Y96067D02*
Y99267D01*
G01X593147Y96067D02*
X586947D01*
G01Y99267D02*
X593147D01*
G01X583686Y122172D02*
Y110172D01*
G01X577686D02*
Y122172D01*
G01X583686Y110172D02*
X577686D01*
G01X582763Y108095D02*
X588963D01*
G01X582763Y104895D02*
Y108095D01*
G01X588963Y104895D02*
X582763D01*
G01X575069Y109424D02*
X578269D01*
G01X575069Y103224D02*
Y109424D01*
G01X578269Y103224D02*
X575069D01*
G01X578269Y109424D02*
Y103224D01*
G01X574269Y109424D02*
Y103224D01*
G01X582763Y100895D02*
Y104095D01*
G01X588963Y100895D02*
X582763D01*
G01Y104095D02*
X588963D01*
G01X575285Y123508D02*
Y111734D01*
G01X577686Y122172D02*
X583686D01*
G01X576294Y126223D02*
X573094D01*
G01X576294Y132423D02*
Y126223D01*
G01X573094Y132423D02*
X576294D01*
G01X573094Y126223D02*
Y132423D01*
G01X572294D02*
Y126223D01*
G01X580348Y126228D02*
X577148D01*
G01X580348Y132428D02*
Y126228D01*
G01X577148Y132428D02*
X580348D01*
G01X577148Y126228D02*
Y132428D01*
G01X580527Y141337D02*
X577327D01*
G01X580527Y147537D02*
Y141337D01*
G01X577327Y147537D02*
X580527D01*
G01X577327Y141337D02*
Y147537D01*
G01X577192Y133238D02*
Y136438D01*
G01X583392Y133238D02*
X577192D01*
G01X583392Y136438D02*
Y133238D01*
G01X577192Y136438D02*
X583392D01*
G01X583738Y148437D02*
X586938D01*
G01X583738Y142237D02*
Y148437D01*
G01X586938Y142237D02*
X583738D01*
G01X586938Y148437D02*
Y142237D01*
G01X577192Y137238D02*
Y140438D01*
G01X583392Y137238D02*
X577192D01*
G01X583392Y140438D02*
Y137238D01*
G01X577192Y140438D02*
X583392D01*
G01X574573Y134995D02*
Y144395D01*
G01X586300Y153107D02*
X588522D01*
X588987Y153260D01*
X589297Y153567D01*
X589400Y153950D01*
X589297Y154333D01*
X588987Y154640D01*
X588522Y154793D01*
X586300D01*
G01X588780Y156207D02*
X589142Y156437D01*
X589348Y156743D01*
X589400Y157088D01*
X589348Y157395D01*
X589090Y157702D01*
X588780Y157893D01*
X588470Y157932D01*
X588108Y157855D01*
X587850Y157587D01*
X587747Y157318D01*
Y156973D01*
G01Y157318D02*
X587592Y157548D01*
X587333Y157740D01*
X587023Y157817D01*
X586713Y157740D01*
X586455Y157548D01*
X586300Y157203D01*
X586352Y156858D01*
X586558Y156513D01*
G01X588108Y159422D02*
X587747Y159690D01*
X587540Y159920D01*
X587437Y160227D01*
X587540Y160495D01*
X587747Y160687D01*
X588057Y160840D01*
X588418Y160878D01*
X588728Y160840D01*
X589038Y160687D01*
X589297Y160457D01*
X589400Y160188D01*
X589297Y159882D01*
X588987Y159613D01*
X588522Y159460D01*
X588005Y159422D01*
X587333Y159498D01*
X586972Y159613D01*
X586610Y159805D01*
X586352Y160073D01*
X586300Y160342D01*
X586403Y160610D01*
X586662Y160802D01*
G01X589400Y163250D02*
X589348Y163518D01*
X589193Y163825D01*
X588935Y164017D01*
X588573Y164093D01*
X588212Y164017D01*
X587902Y163787D01*
X587747Y163442D01*
Y163058D01*
X587643Y162828D01*
X587385Y162637D01*
X587023Y162560D01*
X586662Y162675D01*
X586403Y162943D01*
X586300Y163250D01*
X586403Y163557D01*
X586662Y163825D01*
X587023Y163940D01*
X587385Y163863D01*
X587643Y163672D01*
X587747Y163442D01*
Y163058D01*
X587902Y162713D01*
X588212Y162483D01*
X588573Y162407D01*
X588935Y162483D01*
X589193Y162675D01*
X589348Y162982D01*
X589400Y163250D01*
G01X572196Y149950D02*
Y165304D01*
G01X584874Y149950D02*
X572196D01*
G01X584874Y165304D02*
Y149950D01*
G01X572393Y165304D02*
X584874D01*
G01X587694Y197645D02*
X575694D01*
G01X587694Y203645D02*
Y197645D01*
G01X575694D02*
Y203645D01*
G01X574871Y216506D02*
Y204506D01*
G01X575694Y203645D02*
X587694D01*
G01X585647Y208464D02*
Y205264D01*
G01X579447Y208464D02*
X585647D01*
G01X579447Y205264D02*
Y208464D01*
G01X585647Y205264D02*
X579447D01*
G01X575671Y208306D02*
Y214506D01*
G01X578871Y208306D02*
X575671D01*
G01X578871Y214506D02*
Y208306D01*
G01X580477Y226801D02*
X592681D01*
Y211497D01*
X580477D01*
Y226801D01*
G01X575671Y214506D02*
X578871D01*
G01X576037Y245521D02*
Y254969D01*
G01X586873Y245521D02*
X576037D01*
G01X586873Y254969D02*
Y245521D01*
G01X579613Y231334D02*
X576413D01*
G01X579613Y237534D02*
Y231334D01*
G01X576413Y237534D02*
X579613D01*
G01X576413Y231334D02*
Y237534D01*
G01X585140Y231446D02*
X581940D01*
G01X585140Y237646D02*
Y231446D01*
G01X581940Y237646D02*
X585140D01*
G01X581940Y231446D02*
Y237646D01*
G01X584818Y243678D02*
Y240478D01*
G01X578618Y243678D02*
X584818D01*
G01X578618Y240478D02*
Y243678D01*
G01X584818Y240478D02*
X578618D01*
G01X577839Y243678D02*
Y240478D01*
G01X573869Y249971D02*
Y246771D01*
G01X589015Y231434D02*
X585815D01*
G01Y237634D02*
X589015D01*
G01X585815Y231434D02*
Y237634D01*
G01X576631Y259673D02*
X576324Y259725D01*
X576056Y259931D01*
X575826Y260241D01*
X575673Y260603D01*
X575596Y261016D01*
Y261430D01*
X575673Y261843D01*
X575826Y262205D01*
X576056Y262515D01*
X576324Y262721D01*
X576631Y262773D01*
X576938Y262721D01*
X577206Y262515D01*
X577436Y262205D01*
X577589Y261843D01*
X577666Y261430D01*
Y261016D01*
X577589Y260603D01*
X577436Y260241D01*
X577206Y259931D01*
X576938Y259725D01*
X576631Y259673D01*
G01X576938Y260500D02*
X577398Y259673D01*
G01X579003Y262256D02*
X579233Y262566D01*
X579501Y262721D01*
X579808Y262773D01*
X580191Y262670D01*
X580459Y262411D01*
X580536Y262101D01*
X580498Y261791D01*
X580344Y261533D01*
X579578Y261016D01*
X579233Y260655D01*
X579003Y260138D01*
X578926Y259673D01*
X580536D01*
G01X582831Y262773D02*
X582524Y262670D01*
X582294Y262411D01*
X582141Y262101D01*
X582026Y261688D01*
X581988Y261223D01*
X582026Y260758D01*
X582141Y260345D01*
X582294Y260035D01*
X582524Y259776D01*
X582831Y259673D01*
X583138Y259776D01*
X583368Y260035D01*
X583521Y260345D01*
X583636Y260758D01*
X583674Y261223D01*
X583636Y261688D01*
X583521Y262101D01*
X583368Y262411D01*
X583138Y262670D01*
X582831Y262773D01*
G01X585931Y259673D02*
Y262773D01*
X585471Y262153D01*
G01Y259673D02*
X586391D01*
G01X583455Y254969D02*
X586873D01*
G01X581455Y253245D02*
X583455Y254969D01*
G01X579455D02*
X581455Y253245D01*
G01X576037Y254969D02*
X579455D01*
G01X573869Y253971D02*
Y250771D01*
G01X582721Y450181D02*
X585921D01*
G01X582721Y443981D02*
Y450181D01*
G01X585921Y443981D02*
X582721D01*
G01X585921Y450181D02*
Y443981D01*
G01Y450981D02*
X582721D01*
G01X585921Y457181D02*
Y450981D01*
G01X582721Y457181D02*
X585921D01*
G01X582721Y450981D02*
Y457181D01*
G01X587582Y447404D02*
Y462758D01*
G01X600260Y447404D02*
X587582D01*
G01X587779Y462758D02*
X600260D01*
G01X579300Y551781D02*
X578520Y550611D01*
X578000Y549246D01*
Y547686D01*
X578780Y545931D01*
X580080Y544566D01*
X581640Y543591D01*
X584240Y542811D01*
X586580Y542616D01*
X588920Y543006D01*
X590480Y543591D01*
X592040Y544761D01*
X593080Y546126D01*
X593600Y547491D01*
Y548856D01*
X593080Y550221D01*
X592300Y551391D01*
X591260Y552366D01*
G01X585280Y566951D02*
X584500Y567731D01*
X583200Y568316D01*
X581380Y568706D01*
X579820Y568316D01*
X578780Y567536D01*
X578000Y566171D01*
Y560906D01*
X593600D01*
Y567341D01*
X592560Y568706D01*
X591000Y569486D01*
X589180Y569876D01*
X587360Y569486D01*
X585800Y568316D01*
X585280Y566951D01*
Y560906D01*
G01X578000Y579391D02*
X593600D01*
Y587191D01*
G01X598800Y595341D02*
Y607041D01*
G01X578000Y619091D02*
X593600D01*
G01X578000Y614606D02*
Y623576D01*
G01X593600Y636991D02*
X593340Y635431D01*
X592300Y634066D01*
X590740Y632896D01*
X588920Y632116D01*
X586840Y631726D01*
X584760D01*
X582680Y632116D01*
X580860Y632896D01*
X579300Y634066D01*
X578260Y635431D01*
X578000Y636991D01*
X578260Y638551D01*
X579300Y639916D01*
X580860Y641086D01*
X582680Y641866D01*
X584760Y642256D01*
X586840D01*
X588920Y641866D01*
X590740Y641086D01*
X592300Y639916D01*
X593340Y638551D01*
X593600Y636991D01*
G01Y650991D02*
X578000D01*
Y655671D01*
X578780Y657231D01*
X580600Y658401D01*
X582680Y658791D01*
X584760Y658401D01*
X586320Y657426D01*
X587100Y655671D01*
Y650991D01*
G01X572904Y748784D02*
Y754984D01*
X576104D01*
Y748784D01*
X572904D01*
G01X584047Y917913D02*
Y857677D01*
G01X577703Y933707D02*
Y939707D01*
X589703D01*
Y933707D01*
X577703D01*
G01X573599Y941699D02*
X585607D01*
G01X583003D02*
X585607D01*
G01X573599Y942503D02*
Y941699D01*
X575903D01*
G01X585607D02*
Y942503D01*
G01X571703Y958807D02*
X577903D01*
Y955607D01*
X571703D01*
Y958807D01*
G01X590389Y955607D02*
X584189D01*
Y958807D01*
X590389D01*
Y955607D01*
G01X577903Y960207D02*
X571703D01*
Y963407D01*
X577903D01*
Y960207D01*
G01X573599Y953707D02*
X585607D01*
G01X575703D02*
X573599D01*
Y952903D01*
G01X585607D02*
Y953707D01*
X583103D01*
G01X575323Y987631D02*
X578523D01*
G01X575323Y981431D02*
Y987631D01*
G01X578523Y981431D02*
X575323D01*
G01X578523Y987631D02*
Y981431D01*
G01X579323Y987631D02*
X582523D01*
G01X579323Y981431D02*
Y987631D01*
G01X582523Y981431D02*
X579323D01*
G01X582523Y987631D02*
Y981431D01*
G01X583323Y987631D02*
X586523D01*
G01X583323Y981431D02*
Y987631D01*
G01X586523Y981431D02*
X583323D01*
G01X586523Y987631D02*
Y981431D01*
G01X575323Y990431D02*
Y996631D01*
G01X578523Y990431D02*
X575323D01*
G01X578523Y996631D02*
Y990431D01*
G01X579323D02*
Y996631D01*
G01X582523Y990431D02*
X579323D01*
G01X582523Y996631D02*
Y990431D01*
G01X583323D02*
Y996631D01*
G01X586523Y990431D02*
X583323D01*
G01X586523Y996631D02*
Y990431D01*
G01X587323Y987631D02*
X590523D01*
G01X587323Y981431D02*
Y987631D01*
G01X590523Y981431D02*
X587323D01*
G01Y990431D02*
Y996631D01*
G01X590523Y990431D02*
X587323D01*
G01X574523Y987631D02*
Y981431D01*
G01Y996631D02*
Y990431D01*
G01X582066Y1008071D02*
Y1012671D01*
G01X592266Y1008071D02*
X582066D01*
G01X572457Y1009265D02*
Y1019465D01*
G01X577057Y1009265D02*
X572457D01*
G01X577057Y1019465D02*
Y1009265D01*
G01X575323Y996631D02*
X578523D01*
G01X579323D02*
X582523D01*
G01X583323D02*
X586523D01*
G01X587323D02*
X590523D01*
G01X582066Y1012671D02*
X592266D01*
G01X582066Y1025271D02*
X592266D01*
G01X582066Y1020671D02*
Y1025271D01*
G01X592266Y1020671D02*
X582066D01*
G01X593887Y1026071D02*
X581007D01*
G01Y1032471D02*
Y1026071D01*
G01Y1019871D02*
X593887D01*
G01Y1013471D02*
X581007D01*
G01Y1019871D02*
Y1013471D01*
G01X572457Y1021865D02*
Y1032065D01*
G01X577057Y1021865D02*
X572457D01*
G01X577057Y1032065D02*
Y1021865D01*
G01X572457Y1019465D02*
X577057D01*
G01X581007Y1032471D02*
X593887D01*
G01X572457Y1032065D02*
X577057D01*
G01X580620Y1105408D02*
Y1100808D01*
G01X582241Y1112608D02*
Y1106208D01*
G01X583091Y1107208D02*
X586291D01*
G01X583091Y1101008D02*
Y1107208D01*
G01X586291Y1101008D02*
X583091D01*
G01X586291Y1107208D02*
Y1101008D01*
G01X580620Y1118008D02*
Y1113408D01*
G01X583041Y1108008D02*
Y1112608D01*
G01X593241Y1108008D02*
X583041D01*
G01Y1112608D02*
X593241D01*
G01X583041Y1120608D02*
Y1125208D01*
G01X593241Y1120608D02*
X583041D01*
G01X582241Y1125208D02*
Y1118808D01*
G01X583091Y1119808D02*
X586291D01*
G01X583091Y1113608D02*
Y1119808D01*
G01X586291Y1113608D02*
X583091D01*
G01X586291Y1119808D02*
Y1113608D01*
G01X583041Y1133208D02*
Y1137808D01*
G01X593241Y1133208D02*
X583041D01*
G01Y1137808D02*
X593241D01*
G01X580620Y1130608D02*
Y1126008D01*
G01Y1143208D02*
Y1138608D01*
G01X583041Y1125208D02*
X593241D01*
G01X582241Y1137808D02*
Y1131408D01*
G01X583091Y1138808D02*
Y1145008D01*
G01X586291Y1138808D02*
X583091D01*
G01X586291Y1145008D02*
Y1138808D01*
G01X583091Y1132408D02*
X586291D01*
G01X583091Y1126208D02*
Y1132408D01*
G01X586291Y1126208D02*
X583091D01*
G01X586291Y1132408D02*
Y1126208D01*
G01X583041Y1145808D02*
Y1150408D01*
G01X593241Y1145808D02*
X583041D01*
G01Y1150408D02*
X593241D01*
G01X580620Y1155808D02*
Y1151208D01*
G01X582241Y1150408D02*
Y1144008D01*
G01X583091Y1145008D02*
X586291D01*
G01X583091Y1151408D02*
Y1157608D01*
G01X586291Y1151408D02*
X583091D01*
G01X586291Y1157608D02*
Y1151408D01*
G01X583041Y1158408D02*
Y1163008D01*
G01X593241Y1158408D02*
X583041D01*
G01Y1163008D02*
X593241D01*
G01X583041Y1171008D02*
Y1175608D01*
G01X593241Y1171008D02*
X583041D01*
G01X580620Y1168408D02*
Y1163808D01*
G01X582241Y1163008D02*
Y1156608D01*
G01Y1175608D02*
Y1169208D01*
G01X583091Y1157608D02*
X586291D01*
G01X583091Y1170208D02*
X586291D01*
G01X583091Y1164008D02*
Y1170208D01*
G01X586291Y1164008D02*
X583091D01*
G01X586291Y1170208D02*
Y1164008D01*
G01X583041Y1175608D02*
X593241D01*
G01X583041Y1183608D02*
Y1188208D01*
G01X593241Y1183608D02*
X583041D01*
G01Y1188208D02*
X593241D01*
G01X580620Y1181008D02*
Y1176408D01*
G01X582241Y1188208D02*
Y1181808D01*
G01X583091Y1182808D02*
X586291D01*
G01X583091Y1176608D02*
Y1182808D01*
G01X586291Y1176608D02*
X583091D01*
G01X586291Y1182808D02*
Y1176608D01*
G01X574455Y1206662D02*
X576717Y1204400D01*
G01D02*
X572333Y1200016D01*
G01X584219Y1212064D02*
X588603Y1216448D01*
G01X586481Y1209802D02*
X584219Y1212064D01*
G01X590865Y1214186D02*
X586481Y1209802D01*
G01X580824Y1215459D02*
X578562Y1217721D01*
G01X585208Y1219843D02*
X580824Y1215459D01*
G01X582946Y1222105D02*
X585208Y1219843D01*
G01X578562Y1217721D02*
X582946Y1222105D01*
G01X589310Y1206974D02*
X587048Y1209236D01*
G01D02*
X591432Y1213620D01*
G01X585774Y1219276D02*
X588036Y1217014D01*
G01X581390Y1214892D02*
X585774Y1219276D01*
G01X583652Y1212630D02*
X581390Y1214892D01*
G01X588036Y1217014D02*
X583652Y1212630D01*
G01X575732Y1220549D02*
X580116Y1224933D01*
G01X577994Y1218287D02*
X575732Y1220549D01*
G01X582378Y1222671D02*
X577994Y1218287D01*
G01X575167Y1221115D02*
X572905Y1223377D01*
G01X579551Y1225499D02*
X575167Y1221115D01*
G01X580116Y1224933D02*
X582378Y1222671D01*
G01X576724Y1228327D02*
X572340Y1223943D01*
G01X574462Y1230589D02*
X576724Y1228327D01*
G01X577289Y1227761D02*
X579551Y1225499D01*
G01X572905Y1223377D02*
X577289Y1227761D01*
G01X583832Y1496087D02*
Y1499287D01*
G01X590032Y1496087D02*
X583832D01*
G01Y1492087D02*
Y1495287D01*
G01X590032Y1492087D02*
X583832D01*
G01Y1495287D02*
X590032D01*
G01X580615Y1515642D02*
X586815D01*
Y1512442D01*
X580615D01*
Y1515642D01*
G01X583832Y1499287D02*
X590032D01*
G01X583832Y1500087D02*
Y1503287D01*
G01X590032Y1500087D02*
X583832D01*
G01Y1503287D02*
X590032D01*
G01X583832Y1511287D02*
X590032D01*
G01X583832Y1508087D02*
Y1511287D01*
G01X590032Y1508087D02*
X583832D01*
G01X579866Y1507324D02*
X586066D01*
Y1504124D01*
X579866D01*
Y1507324D01*
G01X586258Y1519215D02*
Y1525415D01*
X589458D01*
Y1519215D01*
X586258D01*
G01X578158Y1519115D02*
Y1525315D01*
X581358D01*
Y1519115D01*
X578158D01*
G01X576857Y1527824D02*
Y1524624D01*
G01X585342Y1549385D02*
Y1543185D01*
X582142D01*
Y1549385D01*
X585342D01*
G01X577409Y1533901D02*
X574209D01*
G01X577409Y1540101D02*
Y1533901D01*
G01X574209Y1540101D02*
X577409D01*
G01X574209Y1533901D02*
Y1540101D01*
G01X586209D02*
X589409D01*
G01X586209Y1533901D02*
Y1540101D01*
G01X589409Y1533901D02*
X586209D01*
G01X585409D02*
X582209D01*
G01X585409Y1540101D02*
Y1533901D01*
G01X582209Y1540101D02*
X585409D01*
G01X582209Y1533901D02*
Y1540101D01*
G01X578209D02*
X581409D01*
G01X578209Y1533901D02*
Y1540101D01*
G01X581409Y1533901D02*
X578209D01*
G01X581409Y1540101D02*
Y1533901D01*
G01X573409Y1540101D02*
Y1533901D01*
G01X575700Y1558475D02*
X575892Y1558165D01*
X576122Y1557958D01*
X576390Y1557855D01*
X576697Y1557958D01*
X576927Y1558165D01*
X577157Y1558475D01*
X577234Y1558888D01*
Y1560955D01*
G01X578839Y1559147D02*
X579107Y1559508D01*
X579337Y1559715D01*
X579644Y1559818D01*
X579912Y1559715D01*
X580104Y1559508D01*
X580257Y1559198D01*
X580295Y1558837D01*
X580257Y1558527D01*
X580104Y1558217D01*
X579874Y1557958D01*
X579605Y1557855D01*
X579299Y1557958D01*
X579030Y1558268D01*
X578877Y1558733D01*
X578839Y1559250D01*
X578915Y1559922D01*
X579030Y1560283D01*
X579222Y1560645D01*
X579490Y1560903D01*
X579759Y1560955D01*
X580027Y1560852D01*
X580219Y1560593D01*
G01X583127Y1557855D02*
Y1560955D01*
X581709Y1558733D01*
X583625D01*
G01X598090Y57756D02*
Y111695D01*
G01X598386Y58150D02*
Y111695D01*
G01X593956Y56429D02*
X594266Y56621D01*
X594473Y56851D01*
X594576Y57119D01*
X594473Y57426D01*
X594266Y57656D01*
X593956Y57886D01*
X593543Y57963D01*
X591476D01*
G01X593956Y59453D02*
X594318Y59683D01*
X594524Y59989D01*
X594576Y60334D01*
X594524Y60641D01*
X594266Y60948D01*
X593956Y61139D01*
X593646Y61178D01*
X593284Y61101D01*
X593026Y60833D01*
X592923Y60564D01*
Y60219D01*
G01Y60564D02*
X592768Y60794D01*
X592509Y60986D01*
X592199Y61063D01*
X591889Y60986D01*
X591631Y60794D01*
X591476Y60449D01*
X591528Y60104D01*
X591734Y59759D01*
G01X594111Y62553D02*
X594369Y62783D01*
X594524Y63051D01*
X594576Y63396D01*
X594473Y63741D01*
X594266Y64009D01*
X593904Y64201D01*
X593491Y64239D01*
X593078Y64163D01*
X592819Y63971D01*
X592613Y63703D01*
X592561Y63434D01*
X592613Y63166D01*
X592819Y62821D01*
X591476Y62936D01*
Y63971D01*
G01X604471Y57756D02*
X598090D01*
G01X604066Y58150D02*
X598386D01*
G01X593147Y99267D02*
Y96067D01*
G01X598386Y118848D02*
Y114048D01*
G01X598090Y118848D02*
Y114048D01*
G01X588963Y108095D02*
Y104895D01*
G01X589820Y108086D02*
X593020D01*
G01X589820Y101886D02*
Y108086D01*
G01X593020Y101886D02*
X589820D01*
G01X593020Y108086D02*
Y101886D01*
G01X588963Y104095D02*
Y100895D01*
G01X598386Y132607D02*
Y128340D01*
G01X598090Y132607D02*
Y128340D01*
G01Y125781D02*
Y121219D01*
G01X598386Y125781D02*
Y121219D01*
G01Y152756D02*
Y135369D01*
G01X598090Y153150D02*
Y135369D01*
G01Y153150D02*
X604471D01*
G01X598386Y152756D02*
X604066D01*
G01X601817Y189535D02*
X599391D01*
G01X598277Y195583D02*
Y184087D01*
G01X599544Y214543D02*
X596444D01*
Y215463D01*
X596599Y215770D01*
X596961Y216000D01*
X597374Y216077D01*
X597787Y216000D01*
X598097Y215808D01*
X598252Y215463D01*
Y214543D01*
G01X596444Y217567D02*
X598666D01*
X599131Y217720D01*
X599441Y218027D01*
X599544Y218410D01*
X599441Y218793D01*
X599131Y219100D01*
X598666Y219253D01*
X596444D01*
G01X599079Y220667D02*
X599337Y220897D01*
X599492Y221165D01*
X599544Y221510D01*
X599441Y221855D01*
X599234Y222123D01*
X598872Y222315D01*
X598459Y222353D01*
X598046Y222277D01*
X597787Y222085D01*
X597581Y221817D01*
X597529Y221548D01*
X597581Y221280D01*
X597787Y220935D01*
X596444Y221050D01*
Y222085D01*
G01X599544Y224533D02*
X598872Y224610D01*
X598304Y224725D01*
X597787Y224878D01*
X597219Y225070D01*
X596444Y225377D01*
Y223843D01*
G01X597250Y231459D02*
X594050D01*
G01X597250Y237659D02*
Y231459D01*
G01X594050Y237659D02*
X597250D01*
G01X594050Y231459D02*
Y237659D01*
G01X588676Y240081D02*
Y243281D01*
G01X594876Y240081D02*
X588676D01*
G01X594876Y243281D02*
Y240081D01*
G01X588676Y243281D02*
X594876D01*
G01X590050Y237659D02*
X593250D01*
G01X590050Y231459D02*
Y237659D01*
G01X593250Y231459D02*
X590050D01*
G01X593250Y237659D02*
Y231459D01*
G01X589015Y237634D02*
Y231434D01*
G01X594480Y252199D02*
Y248999D01*
G01X588280Y252199D02*
X594480D01*
G01X588280Y248999D02*
Y252199D01*
G01X594480Y248999D02*
X588280D01*
G01X605086Y450700D02*
X601886D01*
G01Y456900D02*
X605086D01*
G01X601886Y450700D02*
Y456900D01*
G01X600260Y462758D02*
Y447404D01*
G01X589257Y466700D02*
Y464478D01*
X589410Y464013D01*
X589717Y463703D01*
X590100Y463600D01*
X590483Y463703D01*
X590790Y464013D01*
X590943Y464478D01*
Y466700D01*
G01X593200Y463600D02*
Y466700D01*
X592740Y466080D01*
G01Y463600D02*
X593660D01*
G01X595648Y463962D02*
X595917Y463703D01*
X596223Y463600D01*
X596530Y463703D01*
X596798Y464013D01*
X596990Y464478D01*
X597067Y464943D01*
Y465512D01*
X596990Y465977D01*
X596798Y466390D01*
X596568Y466597D01*
X596300Y466700D01*
X595993Y466597D01*
X595763Y466390D01*
X595610Y466080D01*
X595533Y465667D01*
X595610Y465305D01*
X595802Y464943D01*
X596032Y464737D01*
X596300Y464685D01*
X596607Y464788D01*
X596837Y465047D01*
X597067Y465512D01*
G01X598447Y537250D02*
Y543450D01*
G01X601647Y537250D02*
X598447D01*
G01X601647Y543450D02*
Y537250D01*
G01X594457Y537291D02*
Y543491D01*
G01X597657Y537291D02*
X594457D01*
G01X597657Y543491D02*
Y537291D01*
G01X598447Y543450D02*
X601647D01*
G01X594457Y543491D02*
X597657D01*
G01X599674Y552955D02*
Y556155D01*
G01X605874Y552955D02*
X599674D01*
G01Y556155D02*
X605874D01*
G01X599674Y560155D02*
X605874D01*
G01X599674Y556955D02*
Y560155D01*
G01X605874Y556955D02*
X599674D01*
G01Y564155D02*
X605874D01*
G01X599674Y560955D02*
Y564155D01*
G01X605874Y560955D02*
X599674D01*
G01X599968Y576556D02*
Y588556D01*
G01X605968Y576556D02*
X599968D01*
G01Y588556D02*
X605968D01*
G01X602551Y844369D02*
Y851869D01*
X604791D01*
X605538Y851494D01*
X606098Y850619D01*
X606285Y849619D01*
X606098Y848619D01*
X605631Y847869D01*
X604791Y847494D01*
X602551D01*
G01X610238Y844119D02*
X613598Y851869D01*
G01X617271Y844369D02*
Y851869D01*
X621565Y844369D01*
Y851869D01*
G01X626918Y844119D02*
X626731Y844244D01*
Y844494D01*
X626918Y844619D01*
X627105Y844494D01*
Y844244D01*
X626918Y844119D01*
G01Y847494D02*
X626731Y847619D01*
Y847869D01*
X626918Y847994D01*
X627105Y847869D01*
Y847619D01*
X626918Y847494D01*
G01X632365Y844369D02*
Y851869D01*
X634231D01*
X634978Y851494D01*
X635538Y850994D01*
X636005Y850244D01*
X636378Y849369D01*
X636471Y848119D01*
X636378Y846869D01*
X636005Y845994D01*
X635538Y845244D01*
X634978Y844744D01*
X634231Y844369D01*
X632365D01*
G01X639585D02*
X641918Y851869D01*
X644251Y844369D01*
G01X643411Y846994D02*
X640425D01*
G01X649418Y851869D02*
X648671Y851619D01*
X648111Y850994D01*
X647738Y850244D01*
X647458Y849244D01*
X647365Y848119D01*
X647458Y846994D01*
X647738Y845994D01*
X648111Y845244D01*
X648671Y844619D01*
X649418Y844369D01*
X650165Y844619D01*
X650725Y845244D01*
X651098Y845994D01*
X651378Y846994D01*
X651471Y848119D01*
X651378Y849244D01*
X651098Y850244D01*
X650725Y850994D01*
X650165Y851619D01*
X649418Y851869D01*
G01X655145Y844369D02*
Y851869D01*
X658691D01*
G01X657385Y848244D02*
X655145D01*
G01X664418Y851869D02*
X663671Y851619D01*
X663111Y850994D01*
X662738Y850244D01*
X662458Y849244D01*
X662365Y848119D01*
X662458Y846994D01*
X662738Y845994D01*
X663111Y845244D01*
X663671Y844619D01*
X664418Y844369D01*
X665165Y844619D01*
X665725Y845244D01*
X666098Y845994D01*
X666378Y846994D01*
X666471Y848119D01*
X666378Y849244D01*
X666098Y850244D01*
X665725Y850994D01*
X665165Y851619D01*
X664418Y851869D01*
G01X671918D02*
Y844369D01*
G01X669771Y851869D02*
X674065D01*
G01X681285Y844369D02*
X677551D01*
Y851869D01*
X681285D01*
G01X679791Y848244D02*
X677551D01*
G01X687665Y848369D02*
X688038Y848744D01*
X688318Y849369D01*
X688505Y850244D01*
X688318Y850994D01*
X687945Y851494D01*
X687291Y851869D01*
X684771D01*
Y844369D01*
X687851D01*
X688505Y844869D01*
X688878Y845619D01*
X689065Y846494D01*
X688878Y847369D01*
X688318Y848119D01*
X687665Y848369D01*
X684771D01*
G01X693298Y851869D02*
X695538D01*
G01X694418D02*
Y844369D01*
G01X693298D02*
X695538D01*
G01X700145D02*
Y851869D01*
X703691D01*
G01X702385Y848244D02*
X700145D01*
G01X709418Y851869D02*
X708671Y851619D01*
X708111Y850994D01*
X707738Y850244D01*
X707458Y849244D01*
X707365Y848119D01*
X707458Y846994D01*
X707738Y845994D01*
X708111Y845244D01*
X708671Y844619D01*
X709418Y844369D01*
X710165Y844619D01*
X710725Y845244D01*
X711098Y845994D01*
X711378Y846994D01*
X711471Y848119D01*
X711378Y849244D01*
X711098Y850244D01*
X710725Y850994D01*
X710165Y851619D01*
X709418Y851869D01*
G01X590503Y940707D02*
Y946907D01*
X593703D01*
Y940707D01*
X590503D01*
G01Y948121D02*
Y954321D01*
X593703D01*
Y948121D01*
X590503D01*
G01X597818Y950521D02*
Y948299D01*
X597971Y947834D01*
X598278Y947524D01*
X598661Y947421D01*
X599044Y947524D01*
X599351Y947834D01*
X599504Y948299D01*
Y950521D01*
G01X602221Y947421D02*
Y950521D01*
X600803Y948299D01*
X602719D01*
G01X604018Y948041D02*
X604248Y947679D01*
X604554Y947473D01*
X604899Y947421D01*
X605206Y947473D01*
X605513Y947731D01*
X605704Y948041D01*
X605743Y948351D01*
X605666Y948713D01*
X605398Y948971D01*
X605129Y949074D01*
X604784D01*
G01X605129D02*
X605359Y949229D01*
X605551Y949488D01*
X605628Y949798D01*
X605551Y950108D01*
X605359Y950366D01*
X605014Y950521D01*
X604669Y950469D01*
X604324Y950263D01*
G01X607961Y947421D02*
Y950521D01*
X607501Y949901D01*
G01Y947421D02*
X608421D01*
G01X599323Y987631D02*
X602523D01*
G01X599323Y981431D02*
Y987631D01*
G01X602523Y981431D02*
X599323D01*
G01X602523Y987631D02*
Y981431D01*
G01X603323Y987631D02*
X606523D01*
G01X603323Y981431D02*
Y987631D01*
G01X606523Y981431D02*
X603323D01*
G01X591323Y987631D02*
X594523D01*
G01X591323Y981431D02*
Y987631D01*
G01X594523Y981431D02*
X591323D01*
G01X594523Y987631D02*
Y981431D01*
G01X595323Y987631D02*
X598523D01*
G01X595323Y981431D02*
Y987631D01*
G01X598523Y981431D02*
X595323D01*
G01X598523Y987631D02*
Y981431D01*
G01X599323Y990431D02*
Y996631D01*
G01X602523Y990431D02*
X599323D01*
G01X602523Y996631D02*
Y990431D01*
G01X603323D02*
Y996631D01*
G01X606523Y990431D02*
X603323D01*
G01X591323D02*
Y996631D01*
G01X594523Y990431D02*
X591323D01*
G01X594523Y996631D02*
Y990431D01*
G01X595323D02*
Y996631D01*
G01X598523Y990431D02*
X595323D01*
G01X598523Y996631D02*
Y990431D01*
G01X590523Y987631D02*
Y981431D01*
G01Y996631D02*
Y990431D01*
G01X592266Y1012671D02*
Y1008071D01*
G01X599323Y996631D02*
X602523D01*
G01X603323D02*
X606523D01*
G01X591323D02*
X594523D01*
G01X595323D02*
X598523D01*
G01X594737Y1008271D02*
Y1014471D01*
G01X597937Y1008271D02*
X594737D01*
G01X597937Y1014471D02*
Y1008271D01*
G01X594687Y1015271D02*
Y1019871D01*
G01X604887Y1015271D02*
X594687D01*
G01Y1019871D02*
X604887D01*
G01X592266Y1025271D02*
Y1020671D01*
G01X593887Y1032471D02*
Y1026071D01*
G01Y1019871D02*
Y1013471D01*
G01X594737Y1014471D02*
X597937D01*
G01X594737Y1020871D02*
Y1027071D01*
G01X597937Y1020871D02*
X594737D01*
G01X597937Y1027071D02*
Y1020871D01*
G01X594687Y1027871D02*
Y1032471D01*
G01X604887Y1027871D02*
X594687D01*
G01Y1032471D02*
X604887D01*
G01X594737Y1027071D02*
X597937D01*
G01X598425Y1071456D02*
X785433D01*
G01X598425Y1258464D02*
Y1071456D01*
G01X593241Y1112608D02*
Y1108008D01*
G01Y1125208D02*
Y1120608D01*
G01Y1137808D02*
Y1133208D01*
G01Y1150408D02*
Y1145808D01*
G01Y1163008D02*
Y1158408D01*
G01Y1175608D02*
Y1171008D01*
G01Y1188208D02*
Y1183608D01*
G01X588603Y1216448D02*
X590865Y1214186D01*
G01X593694Y1211358D02*
X589310Y1206974D01*
G01X591432Y1213620D02*
X593694Y1211358D01*
G01X785433Y1258464D02*
X598425D01*
G01X599585Y1492058D02*
X593385D01*
Y1495258D01*
X599585D01*
Y1492058D01*
G01Y1495958D02*
X593385D01*
Y1499158D01*
X599585D01*
Y1495958D01*
G01X590032Y1499287D02*
Y1496087D01*
G01Y1495287D02*
Y1492087D01*
G01X599685Y1499858D02*
X593485D01*
Y1503058D01*
X599685D01*
Y1499858D01*
G01X590032Y1503287D02*
Y1500087D01*
G01Y1511287D02*
Y1508087D01*
G01X595781Y1504194D02*
X589581D01*
Y1507394D01*
X595781D01*
Y1504194D01*
G01X590258Y1525315D02*
Y1531515D01*
X593458D01*
Y1525315D01*
X590258D01*
G01X601842Y1543185D02*
Y1536985D01*
X598642D01*
Y1543185D01*
X601842D01*
G01X589409Y1540101D02*
Y1533901D01*
G01X597409D02*
X594209D01*
G01X597409Y1540101D02*
Y1533901D01*
G01X594209Y1540101D02*
X597409D01*
G01X594209Y1533901D02*
Y1540101D01*
G01X590209D02*
X593409D01*
G01X590209Y1533901D02*
Y1540101D01*
G01X593409Y1533901D02*
X590209D01*
G01X593409Y1540101D02*
Y1533901D01*
G01X595768Y1564843D02*
Y1690040D01*
G01X607762Y1609336D02*
X608562Y1609836D01*
X609095Y1610436D01*
X609362Y1611136D01*
X609095Y1611936D01*
X608562Y1612536D01*
X607762Y1613136D01*
X606695Y1613336D01*
X601362D01*
G01X608162Y1617136D02*
X608829Y1617736D01*
X609229Y1618436D01*
X609362Y1619336D01*
X609095Y1620236D01*
X608562Y1620936D01*
X607629Y1621436D01*
X606562Y1621536D01*
X605495Y1621336D01*
X604829Y1620836D01*
X604295Y1620136D01*
X604162Y1619436D01*
X604295Y1618736D01*
X604829Y1617836D01*
X601362Y1618136D01*
Y1620836D01*
G01X595386Y1723583D02*
X605386D01*
G01X595386Y1726083D02*
Y1723583D01*
G01Y1736083D02*
Y1731083D01*
G01Y1743583D02*
Y1741083D01*
G01X595031Y1744783D02*
X596641Y1747883D01*
G01X595031D02*
X596641Y1744783D01*
G01X598936D02*
Y1747883D01*
X598476Y1747263D01*
G01Y1744783D02*
X599396D01*
G01X601193Y1745248D02*
X601423Y1744990D01*
X601691Y1744835D01*
X602036Y1744783D01*
X602381Y1744886D01*
X602649Y1745093D01*
X602841Y1745455D01*
X602879Y1745868D01*
X602803Y1746281D01*
X602611Y1746540D01*
X602343Y1746746D01*
X602074Y1746798D01*
X601806Y1746746D01*
X601461Y1746540D01*
X601576Y1747883D01*
X602611D01*
G01X605386Y1743583D02*
X595386D01*
G01X595312Y1769624D02*
X605312D01*
G01X595312Y1772124D02*
Y1769624D01*
G01X594957Y1790824D02*
X596567Y1793924D01*
G01X594957D02*
X596567Y1790824D01*
G01X598134Y1793407D02*
X598364Y1793717D01*
X598632Y1793872D01*
X598939Y1793924D01*
X599322Y1793821D01*
X599590Y1793562D01*
X599667Y1793252D01*
X599629Y1792942D01*
X599475Y1792684D01*
X598709Y1792167D01*
X598364Y1791806D01*
X598134Y1791289D01*
X598057Y1790824D01*
X599667D01*
G01X601962D02*
Y1793924D01*
X601502Y1793304D01*
G01Y1790824D02*
X602422D01*
G01X595312Y1789624D02*
Y1787124D01*
G01Y1782124D02*
Y1777124D01*
G01X605312Y1789624D02*
X595312D01*
G01X622894Y57756D02*
X616513D01*
G01X622598Y58150D02*
X616918D01*
G01X611544Y156615D02*
X612291Y155990D01*
X613131Y155615D01*
X613877D01*
X614624Y155990D01*
X615184Y156615D01*
X615464Y157490D01*
X615277Y158365D01*
X614811Y159115D01*
X613971Y159615D01*
X612851Y159865D01*
X612197Y160365D01*
X611917Y161240D01*
X612104Y162115D01*
X612571Y162740D01*
X613224Y163115D01*
X613877D01*
X614531Y162865D01*
X615091Y162240D01*
G01X619044Y156615D02*
X619791Y155990D01*
X620631Y155615D01*
X621377D01*
X622124Y155990D01*
X622684Y156615D01*
X622964Y157490D01*
X622777Y158365D01*
X622311Y159115D01*
X621471Y159615D01*
X620351Y159865D01*
X619697Y160365D01*
X619417Y161240D01*
X619604Y162115D01*
X620071Y162740D01*
X620724Y163115D01*
X621377D01*
X622031Y162865D01*
X622591Y162240D01*
G01X626451Y155615D02*
Y163115D01*
X628317D01*
X629064Y162740D01*
X629624Y162240D01*
X630091Y161490D01*
X630464Y160615D01*
X630557Y159365D01*
X630464Y158115D01*
X630091Y157240D01*
X629624Y156490D01*
X629064Y155990D01*
X628317Y155615D01*
X626451D01*
G01X633951Y156740D02*
X634511Y156115D01*
X635164Y155740D01*
X636004Y155615D01*
X636844Y155865D01*
X637497Y156365D01*
X637964Y157240D01*
X638057Y158240D01*
X637871Y159240D01*
X637404Y159865D01*
X636751Y160365D01*
X636097Y160490D01*
X635444Y160365D01*
X634604Y159865D01*
X634884Y163115D01*
X637404D01*
G01X614994Y164436D02*
X629794D01*
G01X614994Y195440D02*
Y164436D01*
G01X616513Y153150D02*
X622894D01*
G01X616918Y152756D02*
X622598D01*
G01X629794Y195440D02*
X614994D01*
G01X618997Y199912D02*
Y202338D01*
G01X612200Y212601D02*
X609100D01*
Y213521D01*
X609255Y213828D01*
X609617Y214058D01*
X610030Y214135D01*
X610443Y214058D01*
X610753Y213866D01*
X610908Y213521D01*
Y212601D01*
G01X612200Y215625D02*
X609100D01*
Y216391D01*
X609255Y216698D01*
X609462Y216928D01*
X609772Y217120D01*
X610133Y217273D01*
X610650Y217311D01*
X611167Y217273D01*
X611528Y217120D01*
X611838Y216928D01*
X612045Y216698D01*
X612200Y216391D01*
Y215625D01*
G01X609617Y218840D02*
X609307Y219070D01*
X609152Y219338D01*
X609100Y219645D01*
X609203Y220028D01*
X609462Y220296D01*
X609772Y220373D01*
X610082Y220335D01*
X610340Y220181D01*
X610857Y219415D01*
X611218Y219070D01*
X611735Y218840D01*
X612200Y218763D01*
Y220373D01*
G01Y222591D02*
X611528Y222668D01*
X610960Y222783D01*
X610443Y222936D01*
X609875Y223128D01*
X609100Y223435D01*
Y221901D01*
G01X625045Y203452D02*
X613549D01*
G01D02*
Y233011D01*
G01X618897Y236652D02*
Y234412D01*
G01X620522Y235625D02*
X617272D01*
G01X613549Y233011D02*
X625045D01*
G01X618766Y259204D02*
Y261630D01*
G01X624814Y262744D02*
X613318D01*
G01D02*
Y292303D01*
G01X612200Y263983D02*
X609100D01*
Y264903D01*
X609255Y265210D01*
X609617Y265440D01*
X610030Y265517D01*
X610443Y265440D01*
X610753Y265248D01*
X610908Y264903D01*
Y263983D01*
G01X612200Y267007D02*
X609100D01*
Y267773D01*
X609255Y268080D01*
X609462Y268310D01*
X609772Y268502D01*
X610133Y268655D01*
X610650Y268693D01*
X611167Y268655D01*
X611528Y268502D01*
X611838Y268310D01*
X612045Y268080D01*
X612200Y267773D01*
Y267007D01*
G01Y270950D02*
X609100D01*
X609720Y270490D01*
G01X612200D02*
Y271410D01*
G01X609100Y274050D02*
X609203Y273743D01*
X609462Y273513D01*
X609772Y273360D01*
X610185Y273245D01*
X610650Y273207D01*
X611115Y273245D01*
X611528Y273360D01*
X611838Y273513D01*
X612097Y273743D01*
X612200Y274050D01*
X612097Y274357D01*
X611838Y274587D01*
X611528Y274740D01*
X611115Y274855D01*
X610650Y274893D01*
X610185Y274855D01*
X609772Y274740D01*
X609462Y274587D01*
X609203Y274357D01*
X609100Y274050D01*
G01X611580Y276307D02*
X611942Y276537D01*
X612148Y276843D01*
X612200Y277188D01*
X612148Y277495D01*
X611890Y277802D01*
X611580Y277993D01*
X611270Y278032D01*
X610908Y277955D01*
X610650Y277687D01*
X610547Y277418D01*
Y277073D01*
G01Y277418D02*
X610392Y277648D01*
X610133Y277840D01*
X609823Y277917D01*
X609513Y277840D01*
X609255Y277648D01*
X609100Y277303D01*
X609152Y276958D01*
X609358Y276613D01*
G01X623037Y296195D02*
Y293955D01*
G01X624662Y295168D02*
X621412D01*
G01X613318Y292303D02*
X624814D01*
G01X622580Y366583D02*
X622890Y366775D01*
X623097Y367005D01*
X623200Y367273D01*
X623097Y367580D01*
X622890Y367810D01*
X622580Y368040D01*
X622167Y368117D01*
X620100D01*
G01X620617Y369722D02*
X620307Y369952D01*
X620152Y370220D01*
X620100Y370527D01*
X620203Y370910D01*
X620462Y371178D01*
X620772Y371255D01*
X621082Y371217D01*
X621340Y371063D01*
X621857Y370297D01*
X622218Y369952D01*
X622735Y369722D01*
X623200Y369645D01*
Y371255D01*
G01X620617Y372822D02*
X620307Y373052D01*
X620152Y373320D01*
X620100Y373627D01*
X620203Y374010D01*
X620462Y374278D01*
X620772Y374355D01*
X621082Y374317D01*
X621340Y374163D01*
X621857Y373397D01*
X622218Y373052D01*
X622735Y372822D01*
X623200Y372745D01*
Y374355D01*
G01X606586Y377000D02*
Y380200D01*
G01X612786Y377000D02*
X606586D01*
G01X612786Y380200D02*
Y377000D01*
G01X606586Y380200D02*
X612786D01*
G01Y384200D02*
Y381000D01*
G01X606586Y384200D02*
X612786D01*
G01X606586Y381000D02*
Y384200D01*
G01X612786Y381000D02*
X606586D01*
G01X605086Y456900D02*
Y450700D01*
G01X606586Y458000D02*
Y461200D01*
G01X612786Y458000D02*
X606586D01*
G01X612786Y461200D02*
Y458000D01*
G01X606586Y461200D02*
X612786D01*
G01Y465200D02*
Y462000D01*
G01X606586Y465200D02*
X612786D01*
G01X606586Y462000D02*
Y465200D01*
G01X612786Y462000D02*
X606586D01*
G01X606674Y552955D02*
Y556155D01*
G01X612874Y552955D02*
X606674D01*
G01X612874Y556155D02*
Y552955D01*
G01X605874Y556155D02*
Y552955D01*
G01X606674Y556155D02*
X612874D01*
G01X606674Y556955D02*
Y560155D01*
G01X612874Y556955D02*
X606674D01*
G01X612874Y560155D02*
Y556955D01*
G01X606674Y560155D02*
X612874D01*
G01X606706Y560967D02*
Y564167D01*
G01X612906Y560967D02*
X606706D01*
G01X612906Y564167D02*
Y560967D01*
G01X606706Y564167D02*
X612906D01*
G01X605874Y560155D02*
Y556955D01*
G01Y564155D02*
Y560955D01*
G01X606968Y576556D02*
Y588556D01*
G01X612968Y576556D02*
X606968D01*
G01X612968Y588556D02*
Y576556D01*
G01X605968Y588556D02*
Y576556D01*
G01X606968Y588556D02*
X612968D01*
G01X612154Y597188D02*
Y593988D01*
G01X605954Y597188D02*
X612154D01*
G01X605954Y593988D02*
Y597188D01*
G01X612154Y593988D02*
X605954D01*
G01X612154Y593188D02*
Y589988D01*
G01X605954Y593188D02*
X612154D01*
G01X605954Y589988D02*
Y593188D01*
G01X612154Y589988D02*
X605954D01*
G01X612186Y605200D02*
Y602000D01*
G01X605986D02*
Y605200D01*
G01X612186Y602000D02*
X605986D01*
G01X612154Y601188D02*
Y597988D01*
G01X605954Y601188D02*
X612154D01*
G01X605954Y597988D02*
Y601188D01*
G01X612154Y597988D02*
X605954D01*
G01X605986Y605200D02*
X612186D01*
G01Y613200D02*
Y610000D01*
G01X605986Y613200D02*
X612186D01*
G01X605986Y610000D02*
Y613200D01*
G01X612186Y610000D02*
X605986D01*
G01X612186Y621200D02*
Y618000D01*
G01X605986D02*
Y621200D01*
G01X612186Y618000D02*
X605986D01*
G01X612154Y609188D02*
Y605988D01*
G01X605954Y609188D02*
X612154D01*
G01X605954Y605988D02*
Y609188D01*
G01X612154Y605988D02*
X605954D01*
G01X612186Y617200D02*
Y614000D01*
G01X605986Y617200D02*
X612186D01*
G01X605986Y614000D02*
Y617200D01*
G01X612186Y614000D02*
X605986D01*
G01Y621200D02*
X612186D01*
G01Y639569D02*
Y636369D01*
G01X605986D02*
Y639569D01*
G01X612186Y636369D02*
X605986D01*
G01Y629821D02*
Y633021D01*
G01X612186Y629821D02*
X605986D01*
G01X612186Y633021D02*
Y629821D01*
G01X605986Y633021D02*
X612186D01*
G01Y625200D02*
Y622000D01*
G01X605986Y625200D02*
X612186D01*
G01X605986Y622000D02*
Y625200D01*
G01X612186Y622000D02*
X605986D01*
G01X612186Y629200D02*
Y626000D01*
G01X605986Y629200D02*
X612186D01*
G01X605986Y626000D02*
Y629200D01*
G01X612186Y626000D02*
X605986D01*
G01Y639569D02*
X612186D01*
G01Y643574D02*
Y640374D01*
G01X605986Y643574D02*
X612186D01*
G01X605986Y640374D02*
Y643574D01*
G01X612186Y640374D02*
X605986D01*
G01X607323Y990431D02*
Y996631D01*
G01X610523Y990431D02*
X607323D01*
G01X610523Y996631D02*
Y990431D01*
G01X615323D02*
Y996631D01*
G01X618523Y990431D02*
X615323D01*
G01X618523Y996631D02*
Y990431D01*
G01X611323D02*
Y996631D01*
G01X614523Y990431D02*
X611323D01*
G01X614523Y996631D02*
Y990431D01*
G01X606523Y987631D02*
Y981431D01*
G01Y996631D02*
Y990431D01*
G01X607323Y987631D02*
X610523D01*
G01X607323Y981431D02*
Y987631D01*
G01X610523Y981431D02*
X607323D01*
G01X610523Y987631D02*
Y981431D01*
G01X615323Y987631D02*
X618523D01*
G01X615323Y981431D02*
Y987631D01*
G01X618523Y981431D02*
X615323D01*
G01X618523Y987631D02*
Y981431D01*
G01X607323Y996631D02*
X610523D01*
G01X615323D02*
X618523D01*
G01X611323D02*
X614523D01*
G01X604887Y1019871D02*
Y1015271D01*
G01Y1032471D02*
Y1027871D01*
G01X605314Y1066535D02*
G03X605264Y1068315I-31496J6D01*
G01X683063Y1425158D02*
X612835D01*
G01D02*
Y1437032D01*
G01Y1441224D02*
Y1689331D01*
G01D02*
X725827D01*
G01X605386Y1723583D02*
Y1724133D01*
G01X620083Y1723836D02*
Y1723286D01*
X630083D01*
G01X605386Y1733033D02*
Y1734133D01*
G01X620083Y1733836D02*
Y1732736D01*
G01X605386Y1743033D02*
Y1743583D01*
G01X630083Y1740786D02*
Y1743286D01*
X620083D01*
Y1742736D01*
G01X605312Y1769624D02*
Y1770174D01*
G01X619711Y1770988D02*
Y1770438D01*
X629711D01*
G01X605312Y1779074D02*
Y1780174D01*
G01Y1789074D02*
Y1789624D01*
G01X619711Y1780988D02*
Y1779888D01*
G01X629711Y1787938D02*
Y1790438D01*
X619711D01*
Y1789888D01*
G01X622894Y57756D02*
Y104601D01*
G01X622598Y58150D02*
Y104601D01*
G01X634430Y86929D02*
X631230D01*
G01X634430Y93129D02*
Y86929D01*
G01X631230Y93129D02*
X634430D01*
G01X631230Y86929D02*
Y93129D01*
G01X628426Y97026D02*
Y103226D01*
G01X631626Y97026D02*
X628426D01*
G01X631626Y103226D02*
Y97026D01*
G01X638430Y86929D02*
X635230D01*
G01Y93129D02*
X638430D01*
G01X635230Y86929D02*
Y93129D01*
G01X630430Y86929D02*
X627230D01*
G01X630430Y93129D02*
Y86929D01*
G01X627230Y93129D02*
X630430D01*
G01X627230Y86929D02*
Y93129D01*
G01X634509Y96673D02*
Y102873D01*
G01X637709Y96673D02*
X634509D01*
G01X622894Y111507D02*
Y107060D01*
G01X622598Y111507D02*
Y107060D01*
G01Y118680D02*
Y114087D01*
G01X622894Y118680D02*
Y114087D01*
G01X628426Y103226D02*
X631626D01*
G01X634509Y102873D02*
X637709D01*
G01X622598Y132859D02*
Y128325D01*
G01X622894Y132859D02*
Y128325D01*
G01Y125844D02*
Y121329D01*
G01X622598Y125844D02*
Y121329D01*
G01Y152756D02*
Y135420D01*
G01X622894Y153150D02*
Y135420D01*
G01X636094Y139647D02*
Y142847D01*
G01X642294Y139647D02*
X636094D01*
G01Y142847D02*
X642294D01*
G01X632124Y145940D02*
Y149140D01*
G01X638324Y145940D02*
X632124D01*
G01Y149140D02*
X638324D01*
G01X629794Y164436D02*
Y195440D01*
G01X632124Y153140D02*
X638324D01*
G01X632124Y149940D02*
Y153140D01*
G01X638324Y149940D02*
X632124D01*
G01X638760Y171473D02*
X635560D01*
G01Y177673D02*
X638760D01*
G01X635560Y171473D02*
Y177673D01*
G01X634760Y171473D02*
X631560D01*
G01X634760Y177673D02*
Y171473D01*
G01X631560Y177673D02*
X634760D01*
G01X631560Y171473D02*
Y177673D01*
G01X635583Y170297D02*
X641783D01*
G01X635583Y167097D02*
Y170297D01*
G01X641783Y167097D02*
X635583D01*
G01X635778Y193541D02*
X641978D01*
G01X635778Y190341D02*
Y193541D01*
G01X641978Y190341D02*
X635778D01*
G01X638987Y182730D02*
X635787D01*
G01Y188930D02*
X638987D01*
G01X635787Y182730D02*
Y188930D01*
G01X627107Y213035D02*
Y225035D01*
G01X633107Y213035D02*
X627107D01*
G01X633107Y225035D02*
Y213035D01*
G01X625045Y233011D02*
Y203452D01*
G01X627107Y225035D02*
X633107D01*
G01X633947Y226621D02*
Y232621D01*
G01X645947Y226621D02*
X633947D01*
G01X637926Y215082D02*
X634726D01*
G01Y221282D02*
X637926D01*
G01X634726Y215082D02*
Y221282D01*
G01X633947Y232621D02*
X645947D01*
G01X626390Y250325D02*
Y234813D01*
G01D02*
X657482D01*
G01X624814Y292303D02*
Y262744D01*
G01X627183Y251200D02*
Y254300D01*
X628103D01*
X628410Y254145D01*
X628640Y253783D01*
X628717Y253370D01*
X628640Y252957D01*
X628448Y252647D01*
X628103Y252492D01*
X627183D01*
G01X630207Y251200D02*
Y254300D01*
X630973D01*
X631280Y254145D01*
X631510Y253938D01*
X631702Y253628D01*
X631855Y253267D01*
X631893Y252750D01*
X631855Y252233D01*
X631702Y251872D01*
X631510Y251562D01*
X631280Y251355D01*
X630973Y251200D01*
X630207D01*
G01X633422Y253783D02*
X633652Y254093D01*
X633920Y254248D01*
X634227Y254300D01*
X634610Y254197D01*
X634878Y253938D01*
X634955Y253628D01*
X634917Y253318D01*
X634763Y253060D01*
X633997Y252543D01*
X633652Y252182D01*
X633422Y251665D01*
X633345Y251200D01*
X634955D01*
G01X637250D02*
X637518Y251252D01*
X637825Y251407D01*
X638017Y251665D01*
X638093Y252027D01*
X638017Y252388D01*
X637787Y252698D01*
X637442Y252853D01*
X637058D01*
X636828Y252957D01*
X636637Y253215D01*
X636560Y253577D01*
X636675Y253938D01*
X636943Y254197D01*
X637250Y254300D01*
X637557Y254197D01*
X637825Y253938D01*
X637940Y253577D01*
X637863Y253215D01*
X637672Y252957D01*
X637442Y252853D01*
X637058D01*
X636713Y252698D01*
X636483Y252388D01*
X636407Y252027D01*
X636483Y251665D01*
X636675Y251407D01*
X636982Y251252D01*
X637250Y251200D01*
G01X657482Y250325D02*
X626390D01*
G01X634615Y258010D02*
Y264210D01*
G01X637815Y258010D02*
X634615D01*
G01X626685Y271655D02*
Y283655D01*
G01X632685Y271655D02*
X626685D01*
G01X632685Y283655D02*
Y271655D01*
G01X634615Y264210D02*
X637815D01*
G01X635574Y267653D02*
Y279427D01*
G01X645336Y267653D02*
X635574D01*
G01X626685Y283655D02*
X632685D01*
G01X636868Y283383D02*
X633668D01*
G01Y289583D02*
X636868D01*
G01X633668Y283383D02*
Y289583D01*
G01X635574Y279427D02*
X645336D01*
G01X625639Y366063D02*
Y391311D01*
G01Y366063D02*
X641185D01*
G01X625639Y398425D02*
Y393935D01*
G01Y405519D02*
Y401173D01*
G01Y412551D02*
Y408103D01*
G01Y419749D02*
Y415258D01*
G01Y426935D02*
Y422271D01*
G01Y433999D02*
Y429252D01*
G01Y441124D02*
Y436377D01*
G01Y469861D02*
Y443616D01*
G01Y477037D02*
Y472208D01*
G01Y484131D02*
Y479384D01*
G01Y491216D02*
Y486417D01*
G01Y513965D02*
Y493456D01*
G01Y521120D02*
Y516446D01*
G01Y639449D02*
Y537915D01*
G01Y528234D02*
Y523436D01*
G01Y535125D02*
Y530551D01*
G01X629907Y655576D02*
Y653354D01*
X630060Y652889D01*
X630367Y652579D01*
X630750Y652476D01*
X631133Y652579D01*
X631440Y652889D01*
X631593Y653354D01*
Y655576D01*
G01X633122Y655059D02*
X633352Y655369D01*
X633620Y655524D01*
X633927Y655576D01*
X634310Y655473D01*
X634578Y655214D01*
X634655Y654904D01*
X634617Y654594D01*
X634463Y654336D01*
X633697Y653819D01*
X633352Y653458D01*
X633122Y652941D01*
X633045Y652476D01*
X634655D01*
G01X636950Y655576D02*
X636643Y655473D01*
X636413Y655214D01*
X636260Y654904D01*
X636145Y654491D01*
X636107Y654026D01*
X636145Y653561D01*
X636260Y653148D01*
X636413Y652838D01*
X636643Y652579D01*
X636950Y652476D01*
X637257Y652579D01*
X637487Y652838D01*
X637640Y653148D01*
X637755Y653561D01*
X637793Y654026D01*
X637755Y654491D01*
X637640Y654904D01*
X637487Y655214D01*
X637257Y655473D01*
X636950Y655576D01*
G01X641115Y639449D02*
X625639D01*
G01X628688Y1419282D02*
X630555D01*
Y1417032D01*
X629995Y1416282D01*
X629341Y1415782D01*
X628408Y1415532D01*
X627475Y1415782D01*
X626821Y1416282D01*
X626261Y1417032D01*
X625888Y1417907D01*
X625701Y1418907D01*
Y1419782D01*
X625888Y1420532D01*
X626261Y1421407D01*
X626821Y1422157D01*
X627381Y1422657D01*
X628128Y1423032D01*
X628781D01*
X629528Y1422782D01*
X630088Y1422282D01*
G01X633761Y1415532D02*
Y1423032D01*
X636001D01*
X636748Y1422657D01*
X637308Y1421782D01*
X637495Y1420782D01*
X637308Y1419782D01*
X636841Y1419032D01*
X636001Y1418657D01*
X633761D01*
G01X641075Y1423032D02*
Y1417657D01*
X641448Y1416532D01*
X642195Y1415782D01*
X643128Y1415532D01*
X644061Y1415782D01*
X644808Y1416532D01*
X645181Y1417657D01*
Y1423032D01*
G01X647828Y1413032D02*
X653428D01*
G01X659995Y1415532D02*
X656261D01*
Y1423032D01*
X659995D01*
G01X658501Y1419407D02*
X656261D01*
G01X624646Y1436969D02*
X655697D01*
G01X624646Y1677520D02*
Y1441261D01*
G01Y1647993D02*
X714016D01*
G01Y1677520D02*
X624646D01*
G01X630438Y1722086D02*
X628828Y1718986D01*
G01X630438D02*
X628828Y1722086D01*
G01X627261Y1720794D02*
X626993Y1720433D01*
X626763Y1720226D01*
X626456Y1720123D01*
X626188Y1720226D01*
X625996Y1720433D01*
X625843Y1720743D01*
X625805Y1721104D01*
X625843Y1721414D01*
X625996Y1721724D01*
X626226Y1721983D01*
X626495Y1722086D01*
X626801Y1721983D01*
X627070Y1721673D01*
X627223Y1721208D01*
X627261Y1720691D01*
X627185Y1720019D01*
X627070Y1719658D01*
X626878Y1719296D01*
X626610Y1719038D01*
X626341Y1718986D01*
X626073Y1719089D01*
X625881Y1719348D01*
G01X624161Y1720794D02*
X623893Y1720433D01*
X623663Y1720226D01*
X623356Y1720123D01*
X623088Y1720226D01*
X622896Y1720433D01*
X622743Y1720743D01*
X622705Y1721104D01*
X622743Y1721414D01*
X622896Y1721724D01*
X623126Y1721983D01*
X623395Y1722086D01*
X623701Y1721983D01*
X623970Y1721673D01*
X624123Y1721208D01*
X624161Y1720691D01*
X624085Y1720019D01*
X623970Y1719658D01*
X623778Y1719296D01*
X623510Y1719038D01*
X623241Y1718986D01*
X622973Y1719089D01*
X622781Y1719348D01*
G01X630083Y1723286D02*
Y1725786D01*
G01Y1730786D02*
Y1735786D01*
G01X630066Y1769238D02*
X628456Y1766138D01*
G01X630066D02*
X628456Y1769238D01*
G01X626238D02*
X626161Y1768566D01*
X626046Y1767998D01*
X625893Y1767481D01*
X625701Y1766913D01*
X625394Y1766138D01*
X626928D01*
G01X623061Y1769238D02*
Y1766138D01*
X623521Y1766758D01*
G01Y1769238D02*
X622601D01*
G01X629711Y1770438D02*
Y1772938D01*
G01Y1777938D02*
Y1782938D01*
G01X645384Y43262D02*
Y46362D01*
G01X646994D02*
Y43262D01*
G01Y44812D02*
X645384D01*
G01X648446Y43727D02*
X648676Y43469D01*
X648944Y43314D01*
X649289Y43262D01*
X649634Y43365D01*
X649902Y43572D01*
X650094Y43934D01*
X650132Y44347D01*
X650056Y44760D01*
X649864Y45019D01*
X649596Y45225D01*
X649327Y45277D01*
X649059Y45225D01*
X648714Y45019D01*
X648829Y46362D01*
X649864D01*
G01X651661Y45845D02*
X651891Y46155D01*
X652159Y46310D01*
X652466Y46362D01*
X652849Y46259D01*
X653117Y46000D01*
X653194Y45690D01*
X653156Y45380D01*
X653002Y45122D01*
X652236Y44605D01*
X651891Y44244D01*
X651661Y43727D01*
X651584Y43262D01*
X653194D01*
G01X649485Y66981D02*
Y70181D01*
G01X655685Y66981D02*
X649485D01*
G01X638819Y74540D02*
Y77740D01*
G01X645019Y74540D02*
X638819D01*
G01X645019Y77740D02*
Y74540D01*
G01X638819Y77740D02*
X645019D01*
G01X638819Y82540D02*
Y85740D01*
G01X645019Y82540D02*
X638819D01*
G01X645019Y85740D02*
Y82540D01*
G01X638819Y78540D02*
Y81740D01*
G01X645019Y78540D02*
X638819D01*
G01X645019Y81740D02*
Y78540D01*
G01X638819Y81740D02*
X645019D01*
G01X649485Y70181D02*
X655685D01*
G01X649485Y82181D02*
X655685D01*
G01X649485Y78981D02*
Y82181D01*
G01X655685Y78981D02*
X649485D01*
G01X649530Y74987D02*
Y78187D01*
G01X655730Y74987D02*
X649530D01*
G01Y78187D02*
X655730D01*
G01X649530Y70987D02*
Y74187D01*
G01X655730Y70987D02*
X649530D01*
G01Y74187D02*
X655730D01*
G01X638819Y85740D02*
X645019D01*
G01X642439Y86929D02*
X639239D01*
G01X642439Y93129D02*
Y86929D01*
G01X639239Y93129D02*
X642439D01*
G01X639239Y86929D02*
Y93129D01*
G01X638430D02*
Y86929D01*
G01X644013Y95950D02*
Y102150D01*
G01X647213Y95950D02*
X644013D01*
G01X647213Y102150D02*
Y95950D01*
G01X638509Y96673D02*
Y102873D01*
G01X641709Y96673D02*
X638509D01*
G01X641709Y102873D02*
Y96673D01*
G01X637709Y102873D02*
Y96673D01*
G01X648677Y95913D02*
Y111267D01*
G01X661158Y95913D02*
X648677D01*
G01X644013Y102150D02*
X647213D01*
G01X638509Y102873D02*
X641709D01*
G01X644013Y109762D02*
X647213D01*
G01X644013Y103562D02*
Y109762D01*
G01X647213Y103562D02*
X644013D01*
G01X647213Y109762D02*
Y103562D01*
G01X648677Y111267D02*
X661355D01*
G01X640492Y144690D02*
Y154138D01*
G01X651328Y144690D02*
X640492D01*
G01X651328Y154138D02*
Y144690D01*
G01X643073Y139647D02*
Y142847D01*
G01X649273Y139647D02*
X643073D01*
G01X649273Y142847D02*
Y139647D01*
G01X643073Y142847D02*
X649273D01*
G01X652735Y148168D02*
Y151368D01*
G01X658935Y148168D02*
X652735D01*
G01Y144168D02*
Y147368D01*
G01X658935Y144168D02*
X652735D01*
G01Y147368D02*
X658935D01*
G01X642294Y142847D02*
Y139647D01*
G01X638324Y149140D02*
Y145940D01*
G01X641150Y155600D02*
X640843Y155652D01*
X640575Y155858D01*
X640345Y156168D01*
X640192Y156530D01*
X640115Y156943D01*
Y157357D01*
X640192Y157770D01*
X640345Y158132D01*
X640575Y158442D01*
X640843Y158648D01*
X641150Y158700D01*
X641457Y158648D01*
X641725Y158442D01*
X641955Y158132D01*
X642108Y157770D01*
X642185Y157357D01*
Y156943D01*
X642108Y156530D01*
X641955Y156168D01*
X641725Y155858D01*
X641457Y155652D01*
X641150Y155600D01*
G01X641457Y156427D02*
X641917Y155600D01*
G01X643522Y158183D02*
X643752Y158493D01*
X644020Y158648D01*
X644327Y158700D01*
X644710Y158597D01*
X644978Y158338D01*
X645055Y158028D01*
X645017Y157718D01*
X644863Y157460D01*
X644097Y156943D01*
X643752Y156582D01*
X643522Y156065D01*
X643445Y155600D01*
X645055D01*
G01X646622Y158183D02*
X646852Y158493D01*
X647120Y158648D01*
X647427Y158700D01*
X647810Y158597D01*
X648078Y158338D01*
X648155Y158028D01*
X648117Y157718D01*
X647963Y157460D01*
X647197Y156943D01*
X646852Y156582D01*
X646622Y156065D01*
X646545Y155600D01*
X648155D01*
G01X649722Y158183D02*
X649952Y158493D01*
X650220Y158648D01*
X650527Y158700D01*
X650910Y158597D01*
X651178Y158338D01*
X651255Y158028D01*
X651217Y157718D01*
X651063Y157460D01*
X650297Y156943D01*
X649952Y156582D01*
X649722Y156065D01*
X649645Y155600D01*
X651255D01*
G01X647910Y154138D02*
X651328D01*
G01X645910Y152414D02*
X647910Y154138D01*
G01X643910D02*
X645910Y152414D01*
G01X640492Y154138D02*
X643910D01*
G01X652735Y151368D02*
X658935D01*
G01X638324Y153140D02*
Y149940D01*
G01X645057Y174900D02*
Y172678D01*
X645210Y172213D01*
X645517Y171903D01*
X645900Y171800D01*
X646283Y171903D01*
X646590Y172213D01*
X646743Y172678D01*
Y174900D01*
G01X648272Y173092D02*
X648540Y173453D01*
X648770Y173660D01*
X649077Y173763D01*
X649345Y173660D01*
X649537Y173453D01*
X649690Y173143D01*
X649728Y172782D01*
X649690Y172472D01*
X649537Y172162D01*
X649307Y171903D01*
X649038Y171800D01*
X648732Y171903D01*
X648463Y172213D01*
X648310Y172678D01*
X648272Y173195D01*
X648348Y173867D01*
X648463Y174228D01*
X648655Y174590D01*
X648923Y174848D01*
X649192Y174900D01*
X649460Y174797D01*
X649652Y174538D01*
G01X652100Y174900D02*
X651793Y174797D01*
X651563Y174538D01*
X651410Y174228D01*
X651295Y173815D01*
X651257Y173350D01*
X651295Y172885D01*
X651410Y172472D01*
X651563Y172162D01*
X651793Y171903D01*
X652100Y171800D01*
X652407Y171903D01*
X652637Y172162D01*
X652790Y172472D01*
X652905Y172885D01*
X652943Y173350D01*
X652905Y173815D01*
X652790Y174228D01*
X652637Y174538D01*
X652407Y174797D01*
X652100Y174900D01*
G01X643488Y176944D02*
Y178897D01*
G01X645441Y176944D02*
X643488D01*
G01X638760Y177673D02*
Y171473D01*
G01X641783Y170297D02*
Y167097D01*
G01X643488Y188756D02*
X645441D01*
G01X643488Y186803D02*
Y188756D01*
G01X641978Y193541D02*
Y190341D01*
G01X638987Y188930D02*
Y182730D01*
G01X642271Y200174D02*
Y203274D01*
X643191D01*
X643498Y203119D01*
X643728Y202757D01*
X643805Y202344D01*
X643728Y201931D01*
X643536Y201621D01*
X643191Y201466D01*
X642271D01*
G01X645295Y203274D02*
Y201052D01*
X645448Y200587D01*
X645755Y200277D01*
X646138Y200174D01*
X646521Y200277D01*
X646828Y200587D01*
X646981Y201052D01*
Y203274D01*
G01X648395Y200794D02*
X648625Y200432D01*
X648931Y200226D01*
X649276Y200174D01*
X649583Y200226D01*
X649890Y200484D01*
X650081Y200794D01*
X650120Y201104D01*
X650043Y201466D01*
X649775Y201724D01*
X649506Y201827D01*
X649161D01*
G01X649506D02*
X649736Y201982D01*
X649928Y202241D01*
X650005Y202551D01*
X649928Y202861D01*
X649736Y203119D01*
X649391Y203274D01*
X649046Y203222D01*
X648701Y203016D01*
G01X651495Y200794D02*
X651725Y200432D01*
X652031Y200226D01*
X652376Y200174D01*
X652683Y200226D01*
X652990Y200484D01*
X653181Y200794D01*
X653220Y201104D01*
X653143Y201466D01*
X652875Y201724D01*
X652606Y201827D01*
X652261D01*
G01X652606D02*
X652836Y201982D01*
X653028Y202241D01*
X653105Y202551D01*
X653028Y202861D01*
X652836Y203119D01*
X652491Y203274D01*
X652146Y203222D01*
X651801Y203016D01*
G01X656263Y220252D02*
Y208048D01*
X640959D01*
Y220252D01*
X656263D01*
G01X645947Y232621D02*
Y226621D01*
G01X637926Y221282D02*
Y215082D01*
G01X643947Y225921D02*
Y222721D01*
G01X637747Y225921D02*
X643947D01*
G01X637747Y222721D02*
Y225921D01*
G01X643947Y222721D02*
X637747D01*
G01X637815Y264210D02*
Y258010D01*
G01X642615D02*
Y264210D01*
G01X645815Y258010D02*
X642615D01*
G01X645815Y264210D02*
Y258010D01*
G01X641815D02*
X638615D01*
G01X641815Y264210D02*
Y258010D01*
G01X638615D02*
Y264210D01*
G01X652526Y264635D02*
X668038D01*
G01X652526Y295727D02*
Y264635D01*
G01X642615Y264210D02*
X645815D01*
G01X650894Y273701D02*
X647694D01*
G01X650894Y279901D02*
Y273701D01*
G01X647694D02*
Y279901D01*
G01X638615Y264210D02*
X641815D01*
G01X645336Y279427D02*
Y267653D01*
G01X636868Y289583D02*
Y283383D01*
G01X647694Y279901D02*
X650894D01*
G01X640868Y283383D02*
X637668D01*
G01X640868Y289583D02*
Y283383D01*
G01X637668Y289583D02*
X640868D01*
G01X637668Y283383D02*
Y289583D01*
G01X641668Y283383D02*
Y289583D01*
X644868D01*
Y283383D01*
X641668D01*
G01X649600Y282833D02*
X646500D01*
Y283753D01*
X646655Y284060D01*
X647017Y284290D01*
X647430Y284367D01*
X647843Y284290D01*
X648153Y284098D01*
X648308Y283753D01*
Y282833D01*
G01X646500Y285857D02*
X648722D01*
X649187Y286010D01*
X649497Y286317D01*
X649600Y286700D01*
X649497Y287083D01*
X649187Y287390D01*
X648722Y287543D01*
X646500D01*
G01X649600Y289800D02*
X646500D01*
X647120Y289340D01*
G01X649600D02*
Y290260D01*
G01X646500Y292900D02*
X646603Y292593D01*
X646862Y292363D01*
X647172Y292210D01*
X647585Y292095D01*
X648050Y292057D01*
X648515Y292095D01*
X648928Y292210D01*
X649238Y292363D01*
X649497Y292593D01*
X649600Y292900D01*
X649497Y293207D01*
X649238Y293437D01*
X648928Y293590D01*
X648515Y293705D01*
X648050Y293743D01*
X647585Y293705D01*
X647172Y293590D01*
X646862Y293437D01*
X646603Y293207D01*
X646500Y292900D01*
G01X649600Y296000D02*
X649548Y296268D01*
X649393Y296575D01*
X649135Y296767D01*
X648773Y296843D01*
X648412Y296767D01*
X648102Y296537D01*
X647947Y296192D01*
Y295808D01*
X647843Y295578D01*
X647585Y295387D01*
X647223Y295310D01*
X646862Y295425D01*
X646603Y295693D01*
X646500Y296000D01*
X646603Y296307D01*
X646862Y296575D01*
X647223Y296690D01*
X647585Y296613D01*
X647843Y296422D01*
X647947Y296192D01*
Y295808D01*
X648102Y295463D01*
X648412Y295233D01*
X648773Y295157D01*
X649135Y295233D01*
X649393Y295425D01*
X649548Y295732D01*
X649600Y296000D01*
G01X668038Y295727D02*
X652526D01*
G01X641633Y651488D02*
Y659952D01*
G01X654895Y651488D02*
X641633D01*
G01X646764Y659952D02*
X648264Y658181D01*
G01X641633Y659952D02*
X646764D01*
G01X649764D02*
X654895D01*
G01X648264Y658181D02*
X649764Y659952D01*
G01X648198Y669083D02*
Y685283D01*
G01X661198Y669083D02*
X648198D01*
G01Y685283D02*
X661198D01*
G01X651746Y757537D02*
Y760737D01*
G01X657946Y757537D02*
X651746D01*
G01Y760737D02*
X657946D01*
G01X651746Y765537D02*
Y768737D01*
G01X657946Y765537D02*
X651746D01*
G01Y761537D02*
Y764737D01*
G01X657946Y761537D02*
X651746D01*
G01Y764737D02*
X657946D01*
G01X651746Y768737D02*
X657946D01*
G01X651746Y777537D02*
Y780737D01*
G01X657946Y777537D02*
X651746D01*
G01Y780737D02*
X657946D01*
G01X651746Y773537D02*
Y776737D01*
G01X657946Y773537D02*
X651746D01*
G01Y776737D02*
X657946D01*
G01X651746Y769537D02*
Y772737D01*
G01X657946Y769537D02*
X651746D01*
G01Y772737D02*
X657946D01*
G01X651746Y781537D02*
Y784737D01*
G01X657946Y781537D02*
X651746D01*
G01Y785537D02*
Y788737D01*
G01X657946Y785537D02*
X651746D01*
G01Y788737D02*
X657946D01*
G01X651746Y784737D02*
X657946D01*
G01X644241Y808165D02*
G03X651041Y803165I6035J1083D01*
G01X656641Y808165D02*
G02X649841Y803165I-6035J1083D01*
G01X650291Y817615D02*
Y815015D01*
G01X648091D02*
X648791Y816715D01*
G01X647391D02*
X648091Y815015D01*
G01X645891Y817615D02*
Y815015D01*
G01X643441Y815215D02*
X643541Y815315D01*
G01X643291Y815115D02*
X643441Y815215D01*
G01X643041Y815065D02*
X643291Y815115D01*
G01X642841Y815065D02*
X643041D01*
G01X642691Y815115D02*
X642841Y815065D01*
G01X642541Y815215D02*
X642691Y815115D01*
G01X642441Y815315D02*
X642541Y815215D01*
G01X642341Y815465D02*
X642441Y815315D01*
G01X643701Y815765D02*
G02I-710J0D01*
G01X643541Y817565D02*
Y815015D01*
G01X641341Y816265D02*
Y815015D01*
G01X640241Y816715D02*
Y815015D01*
G01X638091D02*
X639291D01*
G01X638141Y815365D02*
X638091Y815015D01*
G01X638241Y815665D02*
X638141Y815365D01*
G01X650941Y813365D02*
G03X644241Y808165I-585J-6163D01*
G01X649941Y813365D02*
G02X656641Y808165I585J-6163D01*
G01X642291Y815715D02*
X642341Y815465D01*
G01X642291Y815915D02*
Y815715D01*
G01X642341Y816065D02*
X642291Y815915D01*
G01X642391Y816165D02*
X642341Y816065D01*
G01X642541Y816315D02*
X642391Y816165D01*
G01X642691Y816415D02*
X642541Y816315D01*
G01X642891Y816465D02*
X642691Y816415D01*
G01X643141Y816465D02*
X642891D01*
G01X643291Y816415D02*
X643141Y816465D01*
G01X643441Y816315D02*
X643291Y816415D01*
G01X643541Y816215D02*
X643441Y816315D01*
G01X641241Y816465D02*
X641341Y816265D01*
G01X641091Y816665D02*
X641241Y816465D01*
G01X640891Y816715D02*
X641091Y816665D01*
G01X640741Y816715D02*
X640891D01*
G01X640541Y816665D02*
X640741Y816715D01*
G01X640441Y816565D02*
X640541Y816665D01*
G01X640341Y816415D02*
X640441Y816565D01*
G01X640241Y816215D02*
X640341Y816415D01*
G01X638341Y815815D02*
X638241Y815665D01*
G01X638441Y815915D02*
X638341Y815815D01*
G01X638591Y816115D02*
X638441Y815915D01*
G01X638791Y816265D02*
X638591Y816115D01*
G01X638941Y816365D02*
X638791Y816265D01*
G01X639041Y816465D02*
X638941Y816365D01*
G01X639141Y816615D02*
X639041Y816465D01*
G01X639191Y816765D02*
X639141Y816615D01*
G01X639191Y817115D02*
Y816765D01*
G01X639141Y817265D02*
X639191Y817115D01*
G01X638891Y817515D02*
X639141Y817265D01*
G01X638641Y817565D02*
X638891Y817515D01*
G01X638441D02*
X638641Y817565D01*
G01X638291Y817415D02*
X638441Y817515D01*
G01X638191Y817315D02*
X638291Y817415D01*
G01X638091Y817115D02*
X638191Y817315D01*
G01X658451Y827165D02*
G02I-8010J0D01*
G01X645241Y833165D02*
X656241Y821665D01*
G01X670317Y67523D02*
X658113D01*
G01D02*
Y70183D01*
G01X665010Y59613D02*
Y56413D01*
G01X658810Y59613D02*
X665010D01*
G01X658810Y56413D02*
Y59613D01*
G01X665010Y56413D02*
X658810D01*
G01X655685Y70181D02*
Y66981D01*
G01X658113Y79047D02*
X670317D01*
G01X658113Y76285D02*
Y79047D01*
G01X661215Y73285D02*
X658113Y76285D01*
G01Y70183D02*
X661215Y73285D01*
G01X655685Y82181D02*
Y78981D01*
G01X655730Y78187D02*
Y74987D01*
G01Y74187D02*
Y70987D01*
G01X656520Y93476D02*
X659720D01*
G01X656520Y87276D02*
Y93476D01*
G01X659720Y87276D02*
X656520D01*
G01X659720Y93476D02*
Y87276D01*
G01X665220D02*
X662020D01*
G01X665220Y93476D02*
Y87276D01*
G01X662020Y93476D02*
X665220D01*
G01X662020Y87276D02*
Y93476D01*
G01X669169Y87204D02*
X665969D01*
G01Y93404D02*
X669169D01*
G01X665969Y87204D02*
Y93404D01*
G01X662500Y98507D02*
X664722D01*
X665187Y98660D01*
X665497Y98967D01*
X665600Y99350D01*
X665497Y99733D01*
X665187Y100040D01*
X664722Y100193D01*
X662500D01*
G01X665600Y102910D02*
X662500D01*
X664722Y101492D01*
Y103408D01*
G01X662500Y105550D02*
X662603Y105243D01*
X662862Y105013D01*
X663172Y104860D01*
X663585Y104745D01*
X664050Y104707D01*
X664515Y104745D01*
X664928Y104860D01*
X665238Y105013D01*
X665497Y105243D01*
X665600Y105550D01*
X665497Y105857D01*
X665238Y106087D01*
X664928Y106240D01*
X664515Y106355D01*
X664050Y106393D01*
X663585Y106355D01*
X663172Y106240D01*
X662862Y106087D01*
X662603Y105857D01*
X662500Y105550D01*
G01X664980Y107807D02*
X665342Y108037D01*
X665548Y108343D01*
X665600Y108688D01*
X665548Y108995D01*
X665290Y109302D01*
X664980Y109493D01*
X664670Y109532D01*
X664308Y109455D01*
X664050Y109187D01*
X663947Y108918D01*
Y108573D01*
G01Y108918D02*
X663792Y109148D01*
X663533Y109340D01*
X663223Y109417D01*
X662913Y109340D01*
X662655Y109148D01*
X662500Y108803D01*
X662552Y108458D01*
X662758Y108113D01*
G01X661355Y111267D02*
Y95913D01*
G01X662511Y111951D02*
Y118151D01*
G01X665711Y111951D02*
X662511D01*
G01X665711Y118151D02*
Y111951D01*
G01X661228Y116088D02*
Y112888D01*
G01X655028Y116088D02*
X661228D01*
G01X655028Y112888D02*
Y116088D01*
G01X661228Y112888D02*
X655028D01*
G01X667885Y111734D02*
Y123508D01*
G01X677647Y111734D02*
X667885D01*
G01X662511Y118151D02*
X665711D01*
G01X670656Y126223D02*
X667456D01*
G01Y132423D02*
X670656D01*
G01X667456Y126223D02*
Y132423D01*
G01X661370Y119182D02*
X658270D01*
Y120102D01*
X658425Y120409D01*
X658787Y120639D01*
X659200Y120716D01*
X659613Y120639D01*
X659923Y120447D01*
X660078Y120102D01*
Y119182D01*
G01X658270Y122206D02*
X660492D01*
X660957Y122359D01*
X661267Y122666D01*
X661370Y123049D01*
X661267Y123432D01*
X660957Y123739D01*
X660492Y123892D01*
X658270D01*
G01X661370Y126149D02*
X658270D01*
X658890Y125689D01*
G01X661370D02*
Y126609D01*
G01X658787Y128521D02*
X658477Y128751D01*
X658322Y129019D01*
X658270Y129326D01*
X658373Y129709D01*
X658632Y129977D01*
X658942Y130054D01*
X659252Y130016D01*
X659510Y129862D01*
X660027Y129096D01*
X660388Y128751D01*
X660905Y128521D01*
X661370Y128444D01*
Y130054D01*
G01X660905Y131506D02*
X661163Y131736D01*
X661318Y132004D01*
X661370Y132349D01*
X661267Y132694D01*
X661060Y132962D01*
X660698Y133154D01*
X660285Y133192D01*
X659872Y133116D01*
X659613Y132924D01*
X659407Y132656D01*
X659355Y132387D01*
X659407Y132119D01*
X659613Y131774D01*
X658270Y131889D01*
Y132924D01*
G01X667885Y123508D02*
X677647D01*
G01X658935Y151368D02*
Y148168D01*
G01Y147368D02*
Y144168D01*
G01X667845Y146229D02*
X664645D01*
G01X667845Y152429D02*
Y146229D01*
G01X664645D02*
Y152429D01*
G01X659900Y135707D02*
X662122D01*
X662587Y135860D01*
X662897Y136167D01*
X663000Y136550D01*
X662897Y136933D01*
X662587Y137240D01*
X662122Y137393D01*
X659900D01*
G01X662380Y138807D02*
X662742Y139037D01*
X662948Y139343D01*
X663000Y139688D01*
X662948Y139995D01*
X662690Y140302D01*
X662380Y140493D01*
X662070Y140532D01*
X661708Y140455D01*
X661450Y140187D01*
X661347Y139918D01*
Y139573D01*
G01Y139918D02*
X661192Y140148D01*
X660933Y140340D01*
X660623Y140417D01*
X660313Y140340D01*
X660055Y140148D01*
X659900Y139803D01*
X659952Y139458D01*
X660158Y139113D01*
G01X663000Y142750D02*
X662948Y143018D01*
X662793Y143325D01*
X662535Y143517D01*
X662173Y143593D01*
X661812Y143517D01*
X661502Y143287D01*
X661347Y142942D01*
Y142558D01*
X661243Y142328D01*
X660985Y142137D01*
X660623Y142060D01*
X660262Y142175D01*
X660003Y142443D01*
X659900Y142750D01*
X660003Y143057D01*
X660262Y143325D01*
X660623Y143440D01*
X660985Y143363D01*
X661243Y143172D01*
X661347Y142942D01*
Y142558D01*
X661502Y142213D01*
X661812Y141983D01*
X662173Y141907D01*
X662535Y141983D01*
X662793Y142175D01*
X662948Y142482D01*
X663000Y142750D01*
G01X662638Y145198D02*
X662897Y145467D01*
X663000Y145773D01*
X662897Y146080D01*
X662587Y146348D01*
X662122Y146540D01*
X661657Y146617D01*
X661088D01*
X660623Y146540D01*
X660210Y146348D01*
X660003Y146118D01*
X659900Y145850D01*
X660003Y145543D01*
X660210Y145313D01*
X660520Y145160D01*
X660933Y145083D01*
X661295Y145160D01*
X661657Y145352D01*
X661863Y145582D01*
X661915Y145850D01*
X661812Y146157D01*
X661553Y146387D01*
X661088Y146617D01*
G01X666335Y144395D02*
Y135095D01*
G01X676935Y144395D02*
X666335D01*
G01Y134995D02*
X676935D01*
G01X664645Y152429D02*
X667845D01*
G01X664645Y159540D02*
X667845D01*
G01X664645Y153340D02*
Y159540D01*
G01X667845Y153340D02*
X664645D01*
G01X667845Y159540D02*
Y153340D01*
G01X655300Y178897D02*
Y176944D01*
G01D02*
X653347D01*
G01X659671Y179065D02*
Y182265D01*
G01X665871Y179065D02*
X659671D01*
G01X665871Y182265D02*
Y179065D01*
G01X659671Y171065D02*
Y174265D01*
G01X665871Y171065D02*
X659671D01*
G01X665871Y174265D02*
Y171065D01*
G01X659671Y174265D02*
X665871D01*
G01X659671Y175065D02*
Y178265D01*
G01X665871Y175065D02*
X659671D01*
G01X665871Y178265D02*
Y175065D01*
G01X659671Y178265D02*
X665871D01*
G01X659671Y167065D02*
Y170265D01*
G01X665871Y167065D02*
X659671D01*
G01X665871Y170265D02*
Y167065D01*
G01X659671Y170265D02*
X665871D01*
G01X655300Y188756D02*
Y186803D01*
G01X653347Y188756D02*
X655300D01*
G01X667439Y189435D02*
X669679D01*
G01X668466Y191060D02*
Y187810D01*
G01X659671Y182265D02*
X665871D01*
G01X659671Y183065D02*
Y186265D01*
G01X665871Y183065D02*
X659671D01*
G01X665871Y186265D02*
Y183065D01*
G01X659671Y186265D02*
X665871D01*
G01X659671Y187065D02*
Y190265D01*
G01X665871Y187065D02*
X659671D01*
G01X665871Y190265D02*
Y187065D01*
G01X659671Y190265D02*
X665871D01*
G01Y194265D02*
Y191065D01*
G01X659671Y194265D02*
X665871D01*
G01X659671Y191065D02*
Y194265D01*
G01X665871Y191065D02*
X659671D01*
G01X665871Y198265D02*
Y195065D01*
G01X659671D02*
Y198265D01*
G01X665871Y195065D02*
X659671D01*
G01Y198265D02*
X665871D01*
G01X659766Y207264D02*
Y210464D01*
G01X665966Y207264D02*
X659766D01*
G01X665966Y210464D02*
Y207264D01*
G01X659766Y210464D02*
X665966D01*
G01Y206464D02*
Y203264D01*
G01X659766Y206464D02*
X665966D01*
G01X659766Y203264D02*
Y206464D01*
G01X665966Y203264D02*
X659766D01*
G01Y214464D02*
X665966D01*
Y211264D01*
X659766D01*
Y214464D01*
G01Y202464D02*
X665966D01*
Y199264D01*
X659766D01*
Y202464D01*
G01Y215264D02*
Y218464D01*
G01X665966Y215264D02*
X659766D01*
G01X665966Y218464D02*
Y215264D01*
G01X659766Y218464D02*
X665966D01*
G01X659766Y220264D02*
Y223464D01*
G01X665966Y220264D02*
X659766D01*
G01X665966Y223464D02*
Y220264D01*
G01X659766Y223464D02*
X665966D01*
G01X659763Y227319D02*
X665963D01*
Y224119D01*
X659763D01*
Y227319D01*
G01X657482Y234813D02*
Y250325D01*
G01X668038Y264635D02*
Y295727D01*
G01X661131Y366063D02*
Y391211D01*
G01X653635Y366063D02*
X661131D01*
G01Y408102D02*
Y412746D01*
G01Y401039D02*
Y405714D01*
G01Y393802D02*
Y398671D01*
G01Y422281D02*
Y426977D01*
G01Y415104D02*
Y419739D01*
G01Y436398D02*
Y441124D01*
G01Y429376D02*
Y433999D01*
G01Y451956D02*
Y443420D01*
G01Y472291D02*
Y476944D01*
G01Y459056D02*
Y469892D01*
G01Y486417D02*
Y491184D01*
G01Y479302D02*
Y484110D01*
G01Y493480D02*
Y514036D01*
G01Y516322D02*
Y521079D01*
G01Y580396D02*
Y537875D01*
G01Y530592D02*
Y535257D01*
G01Y523437D02*
Y528152D01*
G01Y587506D02*
Y639449D01*
G01X654895Y659952D02*
Y651488D01*
G01X659664Y651636D02*
X656464D01*
G01X659664Y657836D02*
Y651636D01*
G01X656464D02*
Y657836D01*
G01X663664Y651636D02*
X660464D01*
G01X663664Y657836D02*
Y651636D01*
G01X660464D02*
Y657836D01*
G01X661131Y639449D02*
X653685D01*
G01X661198Y675683D02*
Y669083D01*
G01X660427Y667875D02*
Y664675D01*
G01X654227Y667875D02*
X660427D01*
G01X654227Y664675D02*
Y667875D01*
G01X660427Y664675D02*
X654227D01*
G01X656442Y658802D02*
Y662002D01*
G01X662642Y658802D02*
X656442D01*
G01X662642Y662002D02*
Y658802D01*
G01X656442Y662002D02*
X662642D01*
G01X656464Y657836D02*
X659664D01*
G01X660464D02*
X663664D01*
G01X662500Y671507D02*
X664722D01*
X665187Y671660D01*
X665497Y671967D01*
X665600Y672350D01*
X665497Y672733D01*
X665187Y673040D01*
X664722Y673193D01*
X662500D01*
G01X663017Y674722D02*
X662707Y674952D01*
X662552Y675220D01*
X662500Y675527D01*
X662603Y675910D01*
X662862Y676178D01*
X663172Y676255D01*
X663482Y676217D01*
X663740Y676063D01*
X664257Y675297D01*
X664618Y674952D01*
X665135Y674722D01*
X665600Y674645D01*
Y676255D01*
G01Y678550D02*
X662500D01*
X663120Y678090D01*
G01X665600D02*
Y679010D01*
G01X658698Y677183D02*
X661198Y675683D01*
G01Y678683D02*
X658698Y677183D01*
G01X661198Y685283D02*
Y678683D01*
G01X668000Y696750D02*
X667948Y696443D01*
X667742Y696175D01*
X667432Y695945D01*
X667070Y695792D01*
X666657Y695715D01*
X666243D01*
X665830Y695792D01*
X665468Y695945D01*
X665158Y696175D01*
X664952Y696443D01*
X664900Y696750D01*
X664952Y697057D01*
X665158Y697325D01*
X665468Y697555D01*
X665830Y697708D01*
X666243Y697785D01*
X666657D01*
X667070Y697708D01*
X667432Y697555D01*
X667742Y697325D01*
X667948Y697057D01*
X668000Y696750D01*
G01X667173Y697057D02*
X668000Y697517D01*
G01X667380Y699007D02*
X667742Y699237D01*
X667948Y699543D01*
X668000Y699888D01*
X667948Y700195D01*
X667690Y700502D01*
X667380Y700693D01*
X667070Y700732D01*
X666708Y700655D01*
X666450Y700387D01*
X666347Y700118D01*
Y699773D01*
G01Y700118D02*
X666192Y700348D01*
X665933Y700540D01*
X665623Y700617D01*
X665313Y700540D01*
X665055Y700348D01*
X664900Y700003D01*
X664952Y699658D01*
X665158Y699313D01*
G01X663540Y696206D02*
X661209Y698537D01*
G01X663540Y693097D02*
Y696206D01*
G01X654878Y693097D02*
X663540D01*
G01X654878Y703977D02*
Y693097D01*
G01X663540Y700868D02*
Y703977D01*
G01X661209Y698537D02*
X663540Y700868D01*
G01X660463Y688094D02*
Y691294D01*
G01X666663Y688094D02*
X660463D01*
G01X666663Y691294D02*
Y688094D01*
G01X660463Y691294D02*
X666663D01*
G01X663540Y703977D02*
X654878D01*
G01X662543Y711729D02*
Y708529D01*
G01X656343Y711729D02*
X662543D01*
G01X656343Y708529D02*
Y711729D01*
G01X662543Y708529D02*
X656343D01*
G01X665246Y761537D02*
Y764737D01*
G01X671446Y761537D02*
X665246D01*
G01Y764737D02*
X671446D01*
G01X657946Y760737D02*
Y757537D01*
G01Y768737D02*
Y765537D01*
G01Y764737D02*
Y761537D01*
G01X665246Y777537D02*
Y780737D01*
G01X671446Y777537D02*
X665246D01*
G01Y780737D02*
X671446D01*
G01X665246Y769537D02*
Y772737D01*
G01X671446Y769537D02*
X665246D01*
G01Y772737D02*
X671446D01*
G01X657946Y780737D02*
Y777537D01*
G01Y776737D02*
Y773537D01*
G01Y772737D02*
Y769537D01*
G01Y784737D02*
Y781537D01*
G01Y788737D02*
Y785537D01*
G01X665246D02*
Y788737D01*
G01X671446Y785537D02*
X665246D01*
G01Y788737D02*
X671446D01*
G01X661991Y815015D02*
X662691Y815065D01*
G01X661991Y817515D02*
Y815015D01*
G01X660041D02*
X660291Y815115D01*
G01X659841Y815015D02*
X660041D01*
G01X659591Y815065D02*
X659841Y815015D01*
G01X659491Y815115D02*
X659591Y815065D01*
G01X659341Y815215D02*
X659491Y815115D01*
G01X659241Y815315D02*
X659341Y815215D01*
G01X659141Y815465D02*
X659241Y815315D01*
G01X657591Y815015D02*
X658291Y815065D01*
G01X657591Y817515D02*
Y815015D01*
G01X654941Y816715D02*
Y815015D01*
G01X656041Y816265D02*
Y815015D01*
G01X653191Y816765D02*
Y815015D01*
G01X661541Y816665D02*
X662441D01*
G01X659091Y815565D02*
X659141Y815465D01*
G01X659041Y815765D02*
X659091Y815565D01*
G01X659041Y815915D02*
Y815765D01*
G01X659091Y816165D02*
X659041Y815915D01*
G01X659141Y816265D02*
X659091Y816165D01*
G01X659241Y816415D02*
X659141Y816265D01*
G01X659341Y816515D02*
X659241Y816415D01*
G01X659491Y816615D02*
X659341Y816515D01*
G01X659591Y816665D02*
X659491Y816615D01*
G01X659791Y816715D02*
X659591Y816665D01*
G01X659941Y816715D02*
X659791D01*
G01X660141Y816665D02*
X659941Y816715D01*
G01X660291Y816615D02*
X660141Y816665D01*
G01X657141D02*
X658041D01*
G01X655941Y816465D02*
X656041Y816265D01*
G01X655791Y816665D02*
X655941Y816465D01*
G01X655591Y816715D02*
X655791Y816665D01*
G01X655441Y816715D02*
X655591D01*
G01X655241Y816665D02*
X655441Y816715D01*
G01X655141Y816565D02*
X655241Y816665D01*
G01X655041Y816415D02*
X655141Y816565D01*
G01X654941Y816215D02*
X655041Y816415D01*
G01X653291Y817915D02*
X653191Y818015D01*
G01X653291Y817815D02*
Y817915D01*
G01X653191Y817715D02*
X653291Y817815D01*
G01X653091D02*
X653191Y817715D01*
G01X653091Y817915D02*
Y817815D01*
G01X653191Y818015D02*
X653091Y817915D01*
G01X664155Y1436969D02*
X689735D01*
G01X671700Y68307D02*
X673922D01*
X674387Y68460D01*
X674697Y68767D01*
X674800Y69150D01*
X674697Y69533D01*
X674387Y69840D01*
X673922Y69993D01*
X671700D01*
G01X674800Y72250D02*
X671700D01*
X672320Y71790D01*
G01X674800D02*
Y72710D01*
G01X674180Y74507D02*
X674542Y74737D01*
X674748Y75043D01*
X674800Y75388D01*
X674748Y75695D01*
X674490Y76002D01*
X674180Y76193D01*
X673870Y76232D01*
X673508Y76155D01*
X673250Y75887D01*
X673147Y75618D01*
Y75273D01*
G01Y75618D02*
X672992Y75848D01*
X672733Y76040D01*
X672423Y76117D01*
X672113Y76040D01*
X671855Y75848D01*
X671700Y75503D01*
X671752Y75158D01*
X671958Y74813D01*
G01X674800Y78450D02*
X671700D01*
X672320Y77990D01*
G01X674800D02*
Y78910D01*
G01X670317Y79047D02*
Y67523D01*
G01X673076Y87299D02*
X669876D01*
G01X673076Y93499D02*
Y87299D01*
G01X669876Y93499D02*
X673076D01*
G01X669876Y87299D02*
Y93499D01*
G01X669169Y93404D02*
Y87204D01*
G01X680048Y110172D02*
Y122172D01*
G01X686048Y110172D02*
X680048D01*
G01X677431Y109424D02*
X680631D01*
G01X677431Y103224D02*
Y109424D01*
G01X680631Y103224D02*
X677431D01*
G01X680631Y109424D02*
Y103224D01*
G01X685125Y108095D02*
X691325D01*
G01X685125Y104895D02*
Y108095D01*
G01X691325Y104895D02*
X685125D01*
G01X669431Y109424D02*
X672631D01*
G01X669431Y103224D02*
Y109424D01*
G01X672631Y103224D02*
X669431D01*
G01X672631Y109424D02*
Y103224D01*
G01X685125Y100895D02*
Y104095D01*
G01X691325Y100895D02*
X685125D01*
G01Y104095D02*
X691325D01*
G01X673431Y109424D02*
X676631D01*
G01X673431Y103224D02*
Y109424D01*
G01X676631Y103224D02*
X673431D01*
G01X676631Y109424D02*
Y103224D01*
G01X677647Y123508D02*
Y111734D01*
G01X680048Y122172D02*
X686048D01*
G01X678656Y126223D02*
X675456D01*
G01X678656Y132423D02*
Y126223D01*
G01X675456Y132423D02*
X678656D01*
G01X675456Y126223D02*
Y132423D01*
G01X670656D02*
Y126223D01*
G01X671456Y132423D02*
X674656D01*
G01X671456Y126223D02*
Y132423D01*
G01X674656Y126223D02*
X671456D01*
G01X674656Y132423D02*
Y126223D01*
G01X682710Y126228D02*
X679510D01*
G01X682710Y132428D02*
Y126228D01*
G01X679510Y132428D02*
X682710D01*
G01X679510Y126228D02*
Y132428D01*
G01X682889Y141337D02*
X679689D01*
G01X682889Y147537D02*
Y141337D01*
G01X679689Y147537D02*
X682889D01*
G01X679689Y141337D02*
Y147537D01*
G01X679554Y133238D02*
Y136438D01*
G01X685754Y133238D02*
X679554D01*
G01Y136438D02*
X685754D01*
G01X679554Y137238D02*
Y140438D01*
G01X685754Y137238D02*
X679554D01*
G01Y140438D02*
X685754D01*
G01X676935Y134995D02*
Y144395D01*
G01X674558Y149950D02*
Y165304D01*
G01X687236Y149950D02*
X674558D01*
G01X674755Y165304D02*
X687236D01*
G01X671183Y179600D02*
Y182700D01*
X672103D01*
X672410Y182545D01*
X672640Y182183D01*
X672717Y181770D01*
X672640Y181357D01*
X672448Y181047D01*
X672103Y180892D01*
X671183D01*
G01X674207Y179600D02*
Y182700D01*
X674973D01*
X675280Y182545D01*
X675510Y182338D01*
X675702Y182028D01*
X675855Y181667D01*
X675893Y181150D01*
X675855Y180633D01*
X675702Y180272D01*
X675510Y179962D01*
X675280Y179755D01*
X674973Y179600D01*
X674207D01*
G01X677422Y180892D02*
X677690Y181253D01*
X677920Y181460D01*
X678227Y181563D01*
X678495Y181460D01*
X678687Y181253D01*
X678840Y180943D01*
X678878Y180582D01*
X678840Y180272D01*
X678687Y179962D01*
X678457Y179703D01*
X678188Y179600D01*
X677882Y179703D01*
X677613Y180013D01*
X677460Y180478D01*
X677422Y180995D01*
X677498Y181667D01*
X677613Y182028D01*
X677805Y182390D01*
X678073Y182648D01*
X678342Y182700D01*
X678610Y182597D01*
X678802Y182338D01*
G01X681710Y179600D02*
Y182700D01*
X680292Y180478D01*
X682208D01*
G01X671080Y195583D02*
X700639D01*
G01X671080Y184087D02*
Y195583D01*
G01X700639Y184087D02*
X671080D01*
G01X690056Y197645D02*
X678056D01*
G01D02*
Y203645D01*
G01D02*
X690056D01*
G01X671233Y204506D02*
Y216506D01*
G01X677233Y204506D02*
X671233D01*
G01X677233Y216506D02*
Y204506D01*
G01X678033Y208306D02*
Y214506D01*
G01X681233Y208306D02*
X678033D01*
G01X681233Y214506D02*
Y208306D01*
G01X681809Y208464D02*
X688009D01*
G01X681809Y205264D02*
Y208464D01*
G01X688009Y205264D02*
X681809D01*
G01X682839Y226801D02*
X695043D01*
Y211497D01*
X682839D01*
Y226801D01*
G01X671233Y216506D02*
X677233D01*
G01X678033Y214506D02*
X681233D01*
G01X678399Y245521D02*
Y254969D01*
G01X689235Y245521D02*
X678399D01*
G01X681975Y231334D02*
X678775D01*
G01X681975Y237534D02*
Y231334D01*
G01X678775Y237534D02*
X681975D01*
G01X678775Y231334D02*
Y237534D01*
G01X687502Y231446D02*
X684302D01*
G01Y237646D02*
X687502D01*
G01X684302Y231446D02*
Y237646D01*
G01X680201Y243678D02*
Y240478D01*
G01X674001Y243678D02*
X680201D01*
G01X674001Y240478D02*
Y243678D01*
G01X680201Y240478D02*
X674001D01*
G01X680980Y243678D02*
X687180D01*
G01X680980Y240478D02*
Y243678D01*
G01X687180Y240478D02*
X680980D01*
G01X670031Y246771D02*
Y249971D01*
G01X676231Y246771D02*
X670031D01*
G01X676231Y249971D02*
Y246771D01*
G01X679150Y256200D02*
X678843Y256252D01*
X678575Y256458D01*
X678345Y256768D01*
X678192Y257130D01*
X678115Y257543D01*
Y257957D01*
X678192Y258370D01*
X678345Y258732D01*
X678575Y259042D01*
X678843Y259248D01*
X679150Y259300D01*
X679457Y259248D01*
X679725Y259042D01*
X679955Y258732D01*
X680108Y258370D01*
X680185Y257957D01*
Y257543D01*
X680108Y257130D01*
X679955Y256768D01*
X679725Y256458D01*
X679457Y256252D01*
X679150Y256200D01*
G01X679457Y257027D02*
X679917Y256200D01*
G01X681522Y258783D02*
X681752Y259093D01*
X682020Y259248D01*
X682327Y259300D01*
X682710Y259197D01*
X682978Y258938D01*
X683055Y258628D01*
X683017Y258318D01*
X682863Y258060D01*
X682097Y257543D01*
X681752Y257182D01*
X681522Y256665D01*
X681445Y256200D01*
X683055D01*
G01X685350Y259300D02*
X685043Y259197D01*
X684813Y258938D01*
X684660Y258628D01*
X684545Y258215D01*
X684507Y257750D01*
X684545Y257285D01*
X684660Y256872D01*
X684813Y256562D01*
X685043Y256303D01*
X685350Y256200D01*
X685657Y256303D01*
X685887Y256562D01*
X686040Y256872D01*
X686155Y257285D01*
X686193Y257750D01*
X686155Y258215D01*
X686040Y258628D01*
X685887Y258938D01*
X685657Y259197D01*
X685350Y259300D01*
G01X687722Y258783D02*
X687952Y259093D01*
X688220Y259248D01*
X688527Y259300D01*
X688910Y259197D01*
X689178Y258938D01*
X689255Y258628D01*
X689217Y258318D01*
X689063Y258060D01*
X688297Y257543D01*
X687952Y257182D01*
X687722Y256665D01*
X687645Y256200D01*
X689255D01*
G01X683817Y253245D02*
X685817Y254969D01*
G01X681817D02*
X683817Y253245D01*
G01X678399Y254969D02*
X681817D01*
G01X670031Y249971D02*
X676231D01*
G01Y253971D02*
Y250771D01*
G01X670031Y253971D02*
X676231D01*
G01X670031Y250771D02*
Y253971D01*
G01X676231Y250771D02*
X670031D01*
G01X672800Y265183D02*
X669700D01*
Y266103D01*
X669855Y266410D01*
X670217Y266640D01*
X670630Y266717D01*
X671043Y266640D01*
X671353Y266448D01*
X671508Y266103D01*
Y265183D01*
G01X672800Y268207D02*
X669700D01*
Y268973D01*
X669855Y269280D01*
X670062Y269510D01*
X670372Y269702D01*
X670733Y269855D01*
X671250Y269893D01*
X671767Y269855D01*
X672128Y269702D01*
X672438Y269510D01*
X672645Y269280D01*
X672800Y268973D01*
Y268207D01*
G01Y272150D02*
X669700D01*
X670320Y271690D01*
G01X672800D02*
Y272610D01*
G01X669700Y275250D02*
X669803Y274943D01*
X670062Y274713D01*
X670372Y274560D01*
X670785Y274445D01*
X671250Y274407D01*
X671715Y274445D01*
X672128Y274560D01*
X672438Y274713D01*
X672697Y274943D01*
X672800Y275250D01*
X672697Y275557D01*
X672438Y275787D01*
X672128Y275940D01*
X671715Y276055D01*
X671250Y276093D01*
X670785Y276055D01*
X670372Y275940D01*
X670062Y275787D01*
X669803Y275557D01*
X669700Y275250D01*
G01X672800Y278350D02*
X669700D01*
X670320Y277890D01*
G01X672800D02*
Y278810D01*
G01X679986Y460400D02*
Y457200D01*
G01X673786D02*
Y460400D01*
G01X679986Y457200D02*
X673786D01*
G01Y460400D02*
X679986D01*
G01X673786Y461200D02*
Y464400D01*
G01X679986Y461200D02*
X673786D01*
G01X679986Y464400D02*
Y461200D01*
G01X673786Y464400D02*
X679986D01*
G01X682586Y555300D02*
X688786D01*
G01X682586Y552100D02*
Y555300D01*
G01X688786Y552100D02*
X682586D01*
G01X673986Y548200D02*
Y551400D01*
G01X680186Y548200D02*
X673986D01*
G01X680186Y551400D02*
Y548200D01*
G01X673986Y551400D02*
X680186D01*
G01Y547400D02*
Y544200D01*
G01X673986Y547400D02*
X680186D01*
G01X673986Y544200D02*
Y547400D01*
G01X680186Y544200D02*
X673986D01*
G01X682586Y548100D02*
Y551300D01*
G01X688786Y548100D02*
X682586D01*
G01Y551300D02*
X688786D01*
G01X682586Y559300D02*
X688786D01*
G01X682586Y556100D02*
Y559300D01*
G01X688786Y556100D02*
X682586D01*
G01X680186Y560400D02*
Y557200D01*
G01X673986Y560400D02*
X680186D01*
G01X673986Y557200D02*
Y560400D01*
G01X680186Y557200D02*
X673986D01*
G01X680186Y564400D02*
Y561200D01*
G01X673986Y564400D02*
X680186D01*
G01X673986Y561200D02*
Y564400D01*
G01X680186Y561200D02*
X673986D01*
G01X674386Y619800D02*
Y623000D01*
G01X680586Y619800D02*
X674386D01*
G01X680586Y623000D02*
Y619800D01*
G01X674386Y623000D02*
X680586D01*
G01X674386Y623800D02*
Y627000D01*
G01X680586Y623800D02*
X674386D01*
G01X680586Y627000D02*
Y623800D01*
G01X674386Y627000D02*
X680586D01*
G01X671446Y764737D02*
Y761537D01*
G01Y780737D02*
Y777537D01*
G01Y772737D02*
Y769537D01*
G01Y788737D02*
Y785537D01*
G01X679726Y1021229D02*
Y1029229D01*
X682126D01*
X682926Y1028829D01*
X683526Y1027896D01*
X683726Y1026829D01*
X683526Y1025762D01*
X683026Y1024962D01*
X682126Y1024562D01*
X679726D01*
G01X691726Y1021229D02*
X687726D01*
Y1029229D01*
X691726D01*
G01X690126Y1025362D02*
X687726D01*
G01X695626Y1021229D02*
X699826Y1029229D01*
G01X695626D02*
X699826Y1021229D01*
G01X705726D02*
Y1029229D01*
X704526Y1027629D01*
G01Y1021229D02*
X706926D01*
G01X700748Y58150D02*
Y111674D01*
G01X700452Y57756D02*
Y111674D01*
G01X695875Y56407D02*
X696185Y56599D01*
X696392Y56829D01*
X696495Y57097D01*
X696392Y57404D01*
X696185Y57634D01*
X695875Y57864D01*
X695462Y57941D01*
X693395D01*
G01X695875Y59431D02*
X696237Y59661D01*
X696443Y59967D01*
X696495Y60312D01*
X696443Y60619D01*
X696185Y60926D01*
X695875Y61117D01*
X695565Y61156D01*
X695203Y61079D01*
X694945Y60811D01*
X694842Y60542D01*
Y60197D01*
G01Y60542D02*
X694687Y60772D01*
X694428Y60964D01*
X694118Y61041D01*
X693808Y60964D01*
X693550Y60772D01*
X693395Y60427D01*
X693447Y60082D01*
X693653Y59737D01*
G01X695203Y62646D02*
X694842Y62914D01*
X694635Y63144D01*
X694532Y63451D01*
X694635Y63719D01*
X694842Y63911D01*
X695152Y64064D01*
X695513Y64102D01*
X695823Y64064D01*
X696133Y63911D01*
X696392Y63681D01*
X696495Y63412D01*
X696392Y63106D01*
X696082Y62837D01*
X695617Y62684D01*
X695100Y62646D01*
X694428Y62722D01*
X694067Y62837D01*
X693705Y63029D01*
X693447Y63297D01*
X693395Y63566D01*
X693498Y63834D01*
X693757Y64026D01*
G01X706833Y57756D02*
X700452D01*
G01X706428Y58150D02*
X700748D01*
G01X689309Y96067D02*
Y99267D01*
G01X695509Y96067D02*
X689309D01*
G01X695509Y99267D02*
Y96067D01*
G01X689309Y99267D02*
X695509D01*
G01X700748Y118848D02*
Y114048D01*
G01X700452Y118848D02*
Y114048D01*
G01X686048Y122172D02*
Y110172D01*
G01X691325Y108095D02*
Y104895D01*
G01X692182Y108086D02*
X695382D01*
G01X692182Y101886D02*
Y108086D01*
G01X695382Y101886D02*
X692182D01*
G01X695382Y108086D02*
Y101886D01*
G01X691325Y104095D02*
Y100895D01*
G01X700748Y132607D02*
Y128340D01*
G01X700452Y132607D02*
Y128340D01*
G01Y125781D02*
Y121219D01*
G01X700748Y125781D02*
Y121219D01*
G01X700452Y153150D02*
Y135557D01*
G01X700748Y152756D02*
Y135557D01*
G01X685754Y136438D02*
Y133238D01*
G01X686100Y148437D02*
X689300D01*
G01X686100Y142237D02*
Y148437D01*
G01X689300Y142237D02*
X686100D01*
G01X689300Y148437D02*
Y142237D01*
G01X685754Y140438D02*
Y137238D01*
G01X688300Y153707D02*
X690522D01*
X690987Y153860D01*
X691297Y154167D01*
X691400Y154550D01*
X691297Y154933D01*
X690987Y155240D01*
X690522Y155393D01*
X688300D01*
G01X690780Y156807D02*
X691142Y157037D01*
X691348Y157343D01*
X691400Y157688D01*
X691348Y157995D01*
X691090Y158302D01*
X690780Y158493D01*
X690470Y158532D01*
X690108Y158455D01*
X689850Y158187D01*
X689747Y157918D01*
Y157573D01*
G01Y157918D02*
X689592Y158148D01*
X689333Y158340D01*
X689023Y158417D01*
X688713Y158340D01*
X688455Y158148D01*
X688300Y157803D01*
X688352Y157458D01*
X688558Y157113D01*
G01X690108Y160022D02*
X689747Y160290D01*
X689540Y160520D01*
X689437Y160827D01*
X689540Y161095D01*
X689747Y161287D01*
X690057Y161440D01*
X690418Y161478D01*
X690728Y161440D01*
X691038Y161287D01*
X691297Y161057D01*
X691400Y160788D01*
X691297Y160482D01*
X690987Y160213D01*
X690522Y160060D01*
X690005Y160022D01*
X689333Y160098D01*
X688972Y160213D01*
X688610Y160405D01*
X688352Y160673D01*
X688300Y160942D01*
X688403Y161210D01*
X688662Y161402D01*
G01X691038Y163198D02*
X691297Y163467D01*
X691400Y163773D01*
X691297Y164080D01*
X690987Y164348D01*
X690522Y164540D01*
X690057Y164617D01*
X689488D01*
X689023Y164540D01*
X688610Y164348D01*
X688403Y164118D01*
X688300Y163850D01*
X688403Y163543D01*
X688610Y163313D01*
X688920Y163160D01*
X689333Y163083D01*
X689695Y163160D01*
X690057Y163352D01*
X690263Y163582D01*
X690315Y163850D01*
X690212Y164157D01*
X689953Y164387D01*
X689488Y164617D01*
G01X687236Y165304D02*
Y149950D01*
G01X700452Y153150D02*
X706833D01*
G01X700748Y152756D02*
X706428D01*
G01X704179Y189535D02*
X701753D01*
G01X700639Y195583D02*
Y184087D01*
G01X690056Y203645D02*
Y197645D01*
G01X688009Y208464D02*
Y205264D01*
G01X701329Y213532D02*
X698229D01*
Y214452D01*
X698384Y214759D01*
X698746Y214989D01*
X699159Y215066D01*
X699572Y214989D01*
X699882Y214797D01*
X700037Y214452D01*
Y213532D01*
G01X698229Y216556D02*
X700451D01*
X700916Y216709D01*
X701226Y217016D01*
X701329Y217399D01*
X701226Y217782D01*
X700916Y218089D01*
X700451Y218242D01*
X698229D01*
G01X700864Y219656D02*
X701122Y219886D01*
X701277Y220154D01*
X701329Y220499D01*
X701226Y220844D01*
X701019Y221112D01*
X700657Y221304D01*
X700244Y221342D01*
X699831Y221266D01*
X699572Y221074D01*
X699366Y220806D01*
X699314Y220537D01*
X699366Y220269D01*
X699572Y219924D01*
X698229Y220039D01*
Y221074D01*
G01X701329Y223599D02*
X701277Y223867D01*
X701122Y224174D01*
X700864Y224366D01*
X700502Y224442D01*
X700141Y224366D01*
X699831Y224136D01*
X699676Y223791D01*
Y223407D01*
X699572Y223177D01*
X699314Y222986D01*
X698952Y222909D01*
X698591Y223024D01*
X698332Y223292D01*
X698229Y223599D01*
X698332Y223906D01*
X698591Y224174D01*
X698952Y224289D01*
X699314Y224212D01*
X699572Y224021D01*
X699676Y223791D01*
Y223407D01*
X699831Y223062D01*
X700141Y222832D01*
X700502Y222756D01*
X700864Y222832D01*
X701122Y223024D01*
X701277Y223331D01*
X701329Y223599D01*
G01X689235Y254969D02*
Y245521D01*
G01X687502Y237646D02*
Y231446D01*
G01X699612Y231459D02*
X696412D01*
G01X699612Y237659D02*
Y231459D01*
G01X696412Y237659D02*
X699612D01*
G01X696412Y231459D02*
Y237659D01*
G01X687180Y243678D02*
Y240478D01*
G01X691377Y231434D02*
X688177D01*
G01X691377Y237634D02*
Y231434D01*
G01X688177Y237634D02*
X691377D01*
G01X688177Y231434D02*
Y237634D01*
G01X692412Y237659D02*
X695612D01*
G01X692412Y231459D02*
Y237659D01*
G01X695612Y231459D02*
X692412D01*
G01X695612Y237659D02*
Y231459D01*
G01X691038Y240081D02*
Y243281D01*
G01X697238Y240081D02*
X691038D01*
G01X697238Y243281D02*
Y240081D01*
G01X691038Y243281D02*
X697238D01*
G01X685817Y254969D02*
X689235D01*
G01X696842Y252199D02*
Y248999D01*
G01X690642Y252199D02*
X696842D01*
G01X690642Y248999D02*
Y252199D01*
G01X696842Y248999D02*
X690642D01*
G01X692450Y386318D02*
Y383118D01*
G01X686250Y386318D02*
X692450D01*
G01X686250Y383118D02*
Y386318D01*
G01X692450Y383118D02*
X686250D01*
G01X692450Y382318D02*
Y379118D01*
G01X686250Y382318D02*
X692450D01*
G01X686250Y379118D02*
Y382318D01*
G01X692450Y379118D02*
X686250D01*
G01X692450Y394318D02*
Y391118D01*
G01X686250D02*
Y394318D01*
G01X692450Y391118D02*
X686250D01*
G01Y387118D02*
Y390318D01*
G01X692450Y387118D02*
X686250D01*
G01X692450Y390318D02*
Y387118D01*
G01X686250Y390318D02*
X692450D01*
G01X686250Y394318D02*
X692450D01*
G01Y398318D02*
Y395118D01*
G01X686250Y398318D02*
X692450D01*
G01X686250Y395118D02*
Y398318D01*
G01X692450Y395118D02*
X686250D01*
G01X692450Y402318D02*
Y399118D01*
G01X686250Y402318D02*
X692450D01*
G01X686250Y399118D02*
Y402318D01*
G01X692450Y399118D02*
X686250D01*
G01X692450Y406318D02*
Y403118D01*
G01X686250Y406318D02*
X692450D01*
G01X686250Y403118D02*
Y406318D01*
G01X692450Y403118D02*
X686250D01*
G01X692450Y410318D02*
Y407118D01*
G01X686250D02*
Y410318D01*
G01X692450Y407118D02*
X686250D01*
G01Y410318D02*
X692450D01*
G01Y414318D02*
Y411118D01*
G01X686250Y414318D02*
X692450D01*
G01X686250Y411118D02*
Y414318D01*
G01X692450Y411118D02*
X686250D01*
G01X688786Y555300D02*
Y552100D01*
G01Y551300D02*
Y548100D01*
G01Y559300D02*
Y556100D01*
G01X701964Y619263D02*
X698764D01*
G01D02*
Y625463D01*
G01X696600Y632550D02*
X696548Y632243D01*
X696342Y631975D01*
X696032Y631745D01*
X695670Y631592D01*
X695257Y631515D01*
X694843D01*
X694430Y631592D01*
X694068Y631745D01*
X693758Y631975D01*
X693552Y632243D01*
X693500Y632550D01*
X693552Y632857D01*
X693758Y633125D01*
X694068Y633355D01*
X694430Y633508D01*
X694843Y633585D01*
X695257D01*
X695670Y633508D01*
X696032Y633355D01*
X696342Y633125D01*
X696548Y632857D01*
X696600Y632550D01*
G01X695773Y632857D02*
X696600Y633317D01*
G01Y635650D02*
X693500D01*
X694120Y635190D01*
G01X696600D02*
Y636110D01*
G01X694017Y638022D02*
X693707Y638252D01*
X693552Y638520D01*
X693500Y638827D01*
X693603Y639210D01*
X693862Y639478D01*
X694172Y639555D01*
X694482Y639517D01*
X694740Y639363D01*
X695257Y638597D01*
X695618Y638252D01*
X696135Y638022D01*
X696600Y637945D01*
Y639555D01*
G01X693500Y641850D02*
X693603Y641543D01*
X693862Y641313D01*
X694172Y641160D01*
X694585Y641045D01*
X695050Y641007D01*
X695515Y641045D01*
X695928Y641160D01*
X696238Y641313D01*
X696497Y641543D01*
X696600Y641850D01*
X696497Y642157D01*
X696238Y642387D01*
X695928Y642540D01*
X695515Y642655D01*
X695050Y642693D01*
X694585Y642655D01*
X694172Y642540D01*
X693862Y642387D01*
X693603Y642157D01*
X693500Y641850D01*
G01X698393Y635329D02*
X700117Y637329D01*
G01X698393Y631911D02*
Y635329D01*
G01X707841Y631911D02*
X698393D01*
G01X698764Y625463D02*
X701964D01*
G01X698393Y639329D02*
Y642747D01*
G01X700117Y637329D02*
X698393Y639329D01*
G01Y642747D02*
X707841D01*
G01X701588Y649146D02*
Y655346D01*
G01X704788Y649146D02*
X701588D01*
G01X697588D02*
Y655346D01*
G01X700788Y649146D02*
X697588D01*
G01X700788Y655346D02*
Y649146D01*
G01X701588Y655346D02*
X704788D01*
G01X697588D02*
X700788D01*
G01X697169Y658013D02*
Y673013D01*
G01X710169Y658013D02*
X697169D01*
G01X697411Y677432D02*
X703611D01*
G01X697411Y674232D02*
Y677432D01*
G01X703611Y674232D02*
X697411D01*
G01X697169Y673013D02*
X710169D01*
G01X691978Y693647D02*
Y691425D01*
X692131Y690960D01*
X692438Y690650D01*
X692821Y690547D01*
X693204Y690650D01*
X693511Y690960D01*
X693664Y691425D01*
Y693647D01*
G01X696381Y690547D02*
Y693647D01*
X694963Y691425D01*
X696879D01*
G01X698178Y691167D02*
X698408Y690805D01*
X698714Y690599D01*
X699059Y690547D01*
X699366Y690599D01*
X699673Y690857D01*
X699864Y691167D01*
X699903Y691477D01*
X699826Y691839D01*
X699558Y692097D01*
X699289Y692200D01*
X698944D01*
G01X699289D02*
X699519Y692355D01*
X699711Y692614D01*
X699788Y692924D01*
X699711Y693234D01*
X699519Y693492D01*
X699174Y693647D01*
X698829Y693595D01*
X698484Y693389D01*
G01X701469Y690909D02*
X701738Y690650D01*
X702044Y690547D01*
X702351Y690650D01*
X702619Y690960D01*
X702811Y691425D01*
X702888Y691890D01*
Y692459D01*
X702811Y692924D01*
X702619Y693337D01*
X702389Y693544D01*
X702121Y693647D01*
X701814Y693544D01*
X701584Y693337D01*
X701431Y693027D01*
X701354Y692614D01*
X701431Y692252D01*
X701623Y691890D01*
X701853Y691684D01*
X702121Y691632D01*
X702428Y691735D01*
X702658Y691994D01*
X702888Y692459D01*
G01X710526Y695253D02*
X696926D01*
G01D02*
Y704053D01*
G01X691563Y695548D02*
Y701748D01*
X694763D01*
Y695548D01*
X691563D01*
G01X690328Y705034D02*
Y698834D01*
X687128D01*
Y705034D01*
X690328D01*
G01X702726Y704053D02*
X696926D01*
G01X691597Y740930D02*
X691290Y740982D01*
X691022Y741188D01*
X690792Y741498D01*
X690639Y741860D01*
X690562Y742273D01*
Y742687D01*
X690639Y743100D01*
X690792Y743462D01*
X691022Y743772D01*
X691290Y743978D01*
X691597Y744030D01*
X691904Y743978D01*
X692172Y743772D01*
X692402Y743462D01*
X692555Y743100D01*
X692632Y742687D01*
Y742273D01*
X692555Y741860D01*
X692402Y741498D01*
X692172Y741188D01*
X691904Y740982D01*
X691597Y740930D01*
G01X691904Y741757D02*
X692364Y740930D01*
G01X693969Y743513D02*
X694199Y743823D01*
X694467Y743978D01*
X694774Y744030D01*
X695157Y743927D01*
X695425Y743668D01*
X695502Y743358D01*
X695464Y743048D01*
X695310Y742790D01*
X694544Y742273D01*
X694199Y741912D01*
X693969Y741395D01*
X693892Y740930D01*
X695502D01*
G01X698257D02*
Y744030D01*
X696839Y741808D01*
X698755D01*
G01X700897Y744030D02*
X700590Y743927D01*
X700360Y743668D01*
X700207Y743358D01*
X700092Y742945D01*
X700054Y742480D01*
X700092Y742015D01*
X700207Y741602D01*
X700360Y741292D01*
X700590Y741033D01*
X700897Y740930D01*
X701204Y741033D01*
X701434Y741292D01*
X701587Y741602D01*
X701702Y742015D01*
X701740Y742480D01*
X701702Y742945D01*
X701587Y743358D01*
X701434Y743668D01*
X701204Y743927D01*
X700897Y744030D01*
G01X690812Y758499D02*
X705528D01*
G01X690812Y778577D02*
Y758499D01*
G01X693107Y783500D02*
Y781278D01*
X693260Y780813D01*
X693567Y780503D01*
X693950Y780400D01*
X694333Y780503D01*
X694640Y780813D01*
X694793Y781278D01*
Y783500D01*
G01X696207Y780865D02*
X696437Y780607D01*
X696705Y780452D01*
X697050Y780400D01*
X697395Y780503D01*
X697663Y780710D01*
X697855Y781072D01*
X697893Y781485D01*
X697817Y781898D01*
X697625Y782157D01*
X697357Y782363D01*
X697088Y782415D01*
X696820Y782363D01*
X696475Y782157D01*
X696590Y783500D01*
X697625D01*
G01X700150D02*
X699843Y783397D01*
X699613Y783138D01*
X699460Y782828D01*
X699345Y782415D01*
X699307Y781950D01*
X699345Y781485D01*
X699460Y781072D01*
X699613Y780762D01*
X699843Y780503D01*
X700150Y780400D01*
X700457Y780503D01*
X700687Y780762D01*
X700840Y781072D01*
X700955Y781485D01*
X700993Y781950D01*
X700955Y782415D01*
X700840Y782828D01*
X700687Y783138D01*
X700457Y783397D01*
X700150Y783500D01*
G01X702209Y778577D02*
X698170Y774538D01*
G01X694131Y778577D02*
X690812D01*
G01X698170Y774538D02*
X694131Y778577D01*
G01X717762Y1425158D02*
X693988D01*
G01X698933Y1436969D02*
X714016D01*
G01X726556Y-23526D02*
Y-40126D01*
X716956D01*
Y-23526D01*
X726556D01*
G01X707863Y-21559D02*
Y-18459D01*
X708629D01*
X708936Y-18614D01*
X709166Y-18821D01*
X709358Y-19131D01*
X709511Y-19492D01*
X709549Y-20009D01*
X709511Y-20526D01*
X709358Y-20887D01*
X709166Y-21197D01*
X708936Y-21404D01*
X708629Y-21559D01*
X707863D01*
G01X712573D02*
X711039D01*
Y-18459D01*
X712573D01*
G01X711959Y-19957D02*
X711039D01*
G01X714906Y-21559D02*
Y-18459D01*
X714446Y-19079D01*
G01Y-21559D02*
X715366D01*
G01X718006D02*
Y-18459D01*
X717546Y-19079D01*
G01Y-21559D02*
X718466D01*
G01X721106Y-18459D02*
Y-21559D01*
G01X720224Y-18459D02*
X721988D01*
G01X723056Y-22592D02*
X725356D01*
G01X726578Y-18976D02*
X726808Y-18666D01*
X727076Y-18511D01*
X727383Y-18459D01*
X727766Y-18562D01*
X728034Y-18821D01*
X728111Y-19131D01*
X728073Y-19441D01*
X727919Y-19699D01*
X727153Y-20216D01*
X726808Y-20577D01*
X726578Y-21094D01*
X726501Y-21559D01*
X728111D01*
G01X713906Y156615D02*
X714653Y155990D01*
X715493Y155615D01*
X716239D01*
X716986Y155990D01*
X717546Y156615D01*
X717826Y157490D01*
X717639Y158365D01*
X717173Y159115D01*
X716333Y159615D01*
X715213Y159865D01*
X714559Y160365D01*
X714279Y161240D01*
X714466Y162115D01*
X714933Y162740D01*
X715586Y163115D01*
X716239D01*
X716893Y162865D01*
X717453Y162240D01*
G01X721406Y156615D02*
X722153Y155990D01*
X722993Y155615D01*
X723739D01*
X724486Y155990D01*
X725046Y156615D01*
X725326Y157490D01*
X725139Y158365D01*
X724673Y159115D01*
X723833Y159615D01*
X722713Y159865D01*
X722059Y160365D01*
X721779Y161240D01*
X721966Y162115D01*
X722433Y162740D01*
X723086Y163115D01*
X723739D01*
X724393Y162865D01*
X724953Y162240D01*
G01X728813Y155615D02*
Y163115D01*
X730679D01*
X731426Y162740D01*
X731986Y162240D01*
X732453Y161490D01*
X732826Y160615D01*
X732919Y159365D01*
X732826Y158115D01*
X732453Y157240D01*
X731986Y156490D01*
X731426Y155990D01*
X730679Y155615D01*
X728813D01*
G01X736593Y158740D02*
X737246Y159615D01*
X737806Y160115D01*
X738553Y160365D01*
X739206Y160115D01*
X739673Y159615D01*
X740046Y158865D01*
X740139Y157990D01*
X740046Y157240D01*
X739673Y156490D01*
X739113Y155865D01*
X738459Y155615D01*
X737713Y155865D01*
X737059Y156615D01*
X736686Y157740D01*
X736593Y158990D01*
X736779Y160615D01*
X737059Y161490D01*
X737526Y162365D01*
X738179Y162990D01*
X738833Y163115D01*
X739486Y162865D01*
X739953Y162240D01*
G01X717356Y164436D02*
X732156D01*
G01X717356Y195440D02*
Y164436D01*
G01X732156Y195440D02*
X717356D01*
G01X721359Y199912D02*
Y202338D01*
G01X714600Y204183D02*
X711500D01*
Y205103D01*
X711655Y205410D01*
X712017Y205640D01*
X712430Y205717D01*
X712843Y205640D01*
X713153Y205448D01*
X713308Y205103D01*
Y204183D01*
G01X714600Y207207D02*
X711500D01*
Y207973D01*
X711655Y208280D01*
X711862Y208510D01*
X712172Y208702D01*
X712533Y208855D01*
X713050Y208893D01*
X713567Y208855D01*
X713928Y208702D01*
X714238Y208510D01*
X714445Y208280D01*
X714600Y207973D01*
Y207207D01*
G01X713980Y210307D02*
X714342Y210537D01*
X714548Y210843D01*
X714600Y211188D01*
X714548Y211495D01*
X714290Y211802D01*
X713980Y211993D01*
X713670Y212032D01*
X713308Y211955D01*
X713050Y211687D01*
X712947Y211418D01*
Y211073D01*
G01Y211418D02*
X712792Y211648D01*
X712533Y211840D01*
X712223Y211917D01*
X711913Y211840D01*
X711655Y211648D01*
X711500Y211303D01*
X711552Y210958D01*
X711758Y210613D01*
G01X714600Y214250D02*
X711500D01*
X712120Y213790D01*
G01X714600D02*
Y214710D01*
G01X727407Y203452D02*
X715911D01*
G01D02*
Y233011D01*
G01X721259Y236652D02*
Y234412D01*
G01X722884Y235625D02*
X719634D01*
G01X715911Y233011D02*
X727407D01*
G01X721128Y259204D02*
Y261630D01*
G01X727176Y262744D02*
X715680D01*
G01D02*
Y292303D01*
G01X714600Y263783D02*
X711500D01*
Y264703D01*
X711655Y265010D01*
X712017Y265240D01*
X712430Y265317D01*
X712843Y265240D01*
X713153Y265048D01*
X713308Y264703D01*
Y263783D01*
G01X714600Y266807D02*
X711500D01*
Y267573D01*
X711655Y267880D01*
X711862Y268110D01*
X712172Y268302D01*
X712533Y268455D01*
X713050Y268493D01*
X713567Y268455D01*
X713928Y268302D01*
X714238Y268110D01*
X714445Y267880D01*
X714600Y267573D01*
Y266807D01*
G01Y270750D02*
X711500D01*
X712120Y270290D01*
G01X714600D02*
Y271210D01*
G01X711500Y273850D02*
X711603Y273543D01*
X711862Y273313D01*
X712172Y273160D01*
X712585Y273045D01*
X713050Y273007D01*
X713515Y273045D01*
X713928Y273160D01*
X714238Y273313D01*
X714497Y273543D01*
X714600Y273850D01*
X714497Y274157D01*
X714238Y274387D01*
X713928Y274540D01*
X713515Y274655D01*
X713050Y274693D01*
X712585Y274655D01*
X712172Y274540D01*
X711862Y274387D01*
X711603Y274157D01*
X711500Y273850D01*
G01X713308Y276222D02*
X712947Y276490D01*
X712740Y276720D01*
X712637Y277027D01*
X712740Y277295D01*
X712947Y277487D01*
X713257Y277640D01*
X713618Y277678D01*
X713928Y277640D01*
X714238Y277487D01*
X714497Y277257D01*
X714600Y276988D01*
X714497Y276682D01*
X714187Y276413D01*
X713722Y276260D01*
X713205Y276222D01*
X712533Y276298D01*
X712172Y276413D01*
X711810Y276605D01*
X711552Y276873D01*
X711500Y277142D01*
X711603Y277410D01*
X711862Y277602D01*
G01X721628Y297627D02*
Y295387D01*
G01X723253Y296600D02*
X720003D01*
G01X715680Y292303D02*
X727176D01*
G01X720180Y366783D02*
X720490Y366975D01*
X720697Y367205D01*
X720800Y367473D01*
X720697Y367780D01*
X720490Y368010D01*
X720180Y368240D01*
X719767Y368317D01*
X717700D01*
G01X718217Y369922D02*
X717907Y370152D01*
X717752Y370420D01*
X717700Y370727D01*
X717803Y371110D01*
X718062Y371378D01*
X718372Y371455D01*
X718682Y371417D01*
X718940Y371263D01*
X719457Y370497D01*
X719818Y370152D01*
X720335Y369922D01*
X720800Y369845D01*
Y371455D01*
G01X720180Y372907D02*
X720542Y373137D01*
X720748Y373443D01*
X720800Y373788D01*
X720748Y374095D01*
X720490Y374402D01*
X720180Y374593D01*
X719870Y374632D01*
X719508Y374555D01*
X719250Y374287D01*
X719147Y374018D01*
Y373673D01*
G01Y374018D02*
X718992Y374248D01*
X718733Y374440D01*
X718423Y374517D01*
X718113Y374440D01*
X717855Y374248D01*
X717700Y373903D01*
X717752Y373558D01*
X717958Y373213D01*
G01X704686Y444273D02*
Y447473D01*
G01X710886Y444273D02*
X704686D01*
G01X710886Y447473D02*
Y444273D01*
G01X704686Y447473D02*
X710886D01*
G01X704686Y448273D02*
Y451473D01*
G01X710886Y448273D02*
X704686D01*
G01X710886Y451473D02*
Y448273D01*
G01X704686Y451473D02*
X710886D01*
G01Y460459D02*
Y457259D01*
G01X704686D02*
Y460459D01*
G01X710886Y457259D02*
X704686D01*
G01X710886Y455473D02*
Y452273D01*
G01X704686Y455473D02*
X710886D01*
G01X704686Y452273D02*
Y455473D01*
G01X710886Y452273D02*
X704686D01*
G01Y460459D02*
X710886D01*
G01X704686Y461259D02*
Y464459D01*
G01X710886Y461259D02*
X704686D01*
G01X710886Y464459D02*
Y461259D01*
G01X704686Y464459D02*
X710886D01*
G01X710071Y544312D02*
Y541112D01*
G01X703871Y544312D02*
X710071D01*
G01X703871Y541112D02*
Y544312D01*
G01X710071Y541112D02*
X703871D01*
G01Y545112D02*
Y548312D01*
G01X710071Y545112D02*
X703871D01*
G01X710071Y548312D02*
Y545112D01*
G01X703871Y548312D02*
X710071D01*
G01X701964Y625463D02*
Y619263D01*
G01X705964D02*
X702764D01*
G01X705964Y625463D02*
Y619263D01*
G01X702764D02*
Y625463D01*
G01X709964Y619263D02*
X706764D01*
G01X709964Y625463D02*
Y619263D01*
G01X706764D02*
Y625463D01*
G01X707841Y642747D02*
Y631911D01*
G01X702764Y625463D02*
X705964D01*
G01X706764D02*
X709964D01*
G01X704788Y655346D02*
Y649146D01*
G01X705588D02*
Y655346D01*
G01X708788Y649146D02*
X705588D01*
G01X708788Y655346D02*
Y649146D01*
G01X705588Y655346D02*
X708788D01*
G01X713622Y667923D02*
Y665701D01*
X713775Y665236D01*
X714082Y664926D01*
X714465Y664823D01*
X714848Y664926D01*
X715155Y665236D01*
X715308Y665701D01*
Y667923D01*
G01X716837Y667406D02*
X717067Y667716D01*
X717335Y667871D01*
X717642Y667923D01*
X718025Y667820D01*
X718293Y667561D01*
X718370Y667251D01*
X718332Y666941D01*
X718178Y666683D01*
X717412Y666166D01*
X717067Y665805D01*
X716837Y665288D01*
X716760Y664823D01*
X718370D01*
G01X719937Y667406D02*
X720167Y667716D01*
X720435Y667871D01*
X720742Y667923D01*
X721125Y667820D01*
X721393Y667561D01*
X721470Y667251D01*
X721432Y666941D01*
X721278Y666683D01*
X720512Y666166D01*
X720167Y665805D01*
X719937Y665288D01*
X719860Y664823D01*
X721470D01*
G01X710169Y673013D02*
Y658013D01*
G01X703611Y677432D02*
Y674232D01*
G01X704251Y674289D02*
Y677489D01*
G01X710451Y674289D02*
X704251D01*
G01X710451Y677489D02*
Y674289D01*
G01X704251Y677489D02*
X710451D01*
G01X710526Y704053D02*
Y695253D01*
G01X717875Y695118D02*
X711675D01*
Y698318D01*
X717875D01*
Y695118D01*
G01X714982Y706837D02*
Y700637D01*
X711782D01*
Y706837D01*
X714982D01*
G01X715689Y693209D02*
X721889D01*
Y690009D01*
X715689D01*
Y693209D01*
G01X710526Y704053D02*
X704726D01*
G01D02*
X703726Y702553D01*
X702726Y704053D01*
G01X702485Y710903D02*
X708685D01*
Y707703D01*
X702485D01*
Y710903D01*
G01X705490Y729650D02*
X711690D01*
Y726450D01*
X705490D01*
Y729650D01*
G01X704688Y732266D02*
Y744078D01*
X717312D01*
Y732266D01*
X704688D01*
G01X705528Y758499D02*
Y778577D01*
G01X715596Y781558D02*
X721796D01*
G01X715596Y778358D02*
Y781558D01*
G01X721796Y778358D02*
X715596D01*
G01X714950Y785053D02*
Y781853D01*
G01X708750D02*
Y785053D01*
G01X714950Y781853D02*
X708750D01*
G01X705528Y778577D02*
X702209D01*
G01X708750Y785053D02*
X714950D01*
G01X714016Y1436969D02*
Y1677520D01*
G01X723897Y1458598D02*
X716397D01*
Y1460838D01*
X716772Y1461585D01*
X717647Y1462145D01*
X718647Y1462332D01*
X719647Y1462145D01*
X720397Y1461678D01*
X720772Y1460838D01*
Y1458598D01*
G01X723897Y1466098D02*
X716397D01*
Y1468432D01*
X716772Y1469178D01*
X717272Y1469645D01*
X718272Y1469832D01*
X719272Y1469645D01*
X719897Y1469085D01*
X720272Y1468432D01*
Y1466098D01*
G01Y1468432D02*
X723897Y1469832D01*
G01Y1477332D02*
Y1473598D01*
X716397D01*
Y1477332D01*
G01X720022Y1475838D02*
Y1473598D01*
G01X722897Y1481005D02*
X723522Y1481752D01*
X723897Y1482592D01*
Y1483338D01*
X723522Y1484085D01*
X722897Y1484645D01*
X722022Y1484925D01*
X721147Y1484738D01*
X720397Y1484272D01*
X719897Y1483432D01*
X719647Y1482312D01*
X719147Y1481658D01*
X718272Y1481378D01*
X717397Y1481565D01*
X716772Y1482032D01*
X716397Y1482685D01*
Y1483338D01*
X716647Y1483992D01*
X717272Y1484552D01*
G01X722897Y1488505D02*
X723522Y1489252D01*
X723897Y1490092D01*
Y1490838D01*
X723522Y1491585D01*
X722897Y1492145D01*
X722022Y1492425D01*
X721147Y1492238D01*
X720397Y1491772D01*
X719897Y1490932D01*
X719647Y1489812D01*
X719147Y1489158D01*
X718272Y1488878D01*
X717397Y1489065D01*
X716772Y1489532D01*
X716397Y1490185D01*
Y1490838D01*
X716647Y1491492D01*
X717272Y1492052D01*
G01X721397Y1496752D02*
Y1499178D01*
G01X723897Y1503692D02*
X716397D01*
Y1507238D01*
G01X720022Y1505932D02*
Y1503692D01*
G01X716397Y1511845D02*
Y1514085D01*
G01Y1512965D02*
X723897D01*
G01Y1511845D02*
Y1514085D01*
G01X716397Y1520465D02*
X723897D01*
G01X716397Y1518318D02*
Y1522612D01*
G01X724960Y58150D02*
Y104501D01*
G01X725256Y57756D02*
Y104501D01*
G01Y57756D02*
X718875D01*
G01X724960Y58150D02*
X719280D01*
G01X730788Y97026D02*
Y103226D01*
G01X733988Y97026D02*
X730788D01*
G01X733988Y103226D02*
Y97026D01*
G01X736792Y86929D02*
X733592D01*
G01Y93129D02*
X736792D01*
G01X733592Y86929D02*
Y93129D01*
G01X732792Y86929D02*
X729592D01*
G01X732792Y93129D02*
Y86929D01*
G01X729592Y93129D02*
X732792D01*
G01X729592Y86929D02*
Y93129D01*
G01X725256Y111507D02*
Y107060D01*
G01X724960Y111507D02*
Y107060D01*
G01Y118680D02*
Y114087D01*
G01X725256Y118680D02*
Y114087D01*
G01X730788Y103226D02*
X733988D01*
G01X724960Y132859D02*
Y128325D01*
G01X725256Y132859D02*
Y128325D01*
G01Y125844D02*
Y121329D01*
G01X724960Y125844D02*
Y121329D01*
G01Y152756D02*
Y135471D01*
G01X725256Y153150D02*
Y135471D01*
G01X732156Y164436D02*
Y195440D01*
G01X718875Y153150D02*
X725256D01*
G01X719280Y152756D02*
X724960D01*
G01X737122Y171473D02*
X733922D01*
G01Y177673D02*
X737122D01*
G01X733922Y171473D02*
Y177673D01*
G01X729469Y213035D02*
Y225035D01*
G01X735469Y213035D02*
X729469D01*
G01X727407Y233011D02*
Y203452D01*
G01X729469Y225035D02*
X735469D01*
G01X728752Y250325D02*
Y234813D01*
G01D02*
X759844D01*
G01X727176Y292303D02*
Y262744D01*
G01X728983Y251600D02*
Y254700D01*
X729903D01*
X730210Y254545D01*
X730440Y254183D01*
X730517Y253770D01*
X730440Y253357D01*
X730248Y253047D01*
X729903Y252892D01*
X728983D01*
G01X732007Y251600D02*
Y254700D01*
X732773D01*
X733080Y254545D01*
X733310Y254338D01*
X733502Y254028D01*
X733655Y253667D01*
X733693Y253150D01*
X733655Y252633D01*
X733502Y252272D01*
X733310Y251962D01*
X733080Y251755D01*
X732773Y251600D01*
X732007D01*
G01X735107Y252220D02*
X735337Y251858D01*
X735643Y251652D01*
X735988Y251600D01*
X736295Y251652D01*
X736602Y251910D01*
X736793Y252220D01*
X736832Y252530D01*
X736755Y252892D01*
X736487Y253150D01*
X736218Y253253D01*
X735873D01*
G01X736218D02*
X736448Y253408D01*
X736640Y253667D01*
X736717Y253977D01*
X736640Y254287D01*
X736448Y254545D01*
X736103Y254700D01*
X735758Y254648D01*
X735413Y254442D01*
G01X738322Y254183D02*
X738552Y254493D01*
X738820Y254648D01*
X739127Y254700D01*
X739510Y254597D01*
X739778Y254338D01*
X739855Y254028D01*
X739817Y253718D01*
X739663Y253460D01*
X738897Y252943D01*
X738552Y252582D01*
X738322Y252065D01*
X738245Y251600D01*
X739855D01*
G01X759844Y250325D02*
X728752D01*
G01X729047Y271655D02*
Y283655D01*
G01X735047Y271655D02*
X729047D01*
G01Y283655D02*
X735047D01*
G01X722726Y366063D02*
X730172D01*
G01X722726Y418006D02*
Y366063D01*
G01Y425116D02*
Y467780D01*
G01Y474925D02*
Y470260D01*
G01Y481999D02*
Y477273D01*
G01Y489023D02*
Y484398D01*
G01Y511780D02*
Y491483D01*
G01Y519090D02*
Y514395D01*
G01Y526062D02*
Y521356D01*
G01Y533279D02*
Y528543D01*
G01Y546456D02*
Y535678D01*
G01Y553556D02*
Y562026D01*
G01Y569098D02*
Y564383D01*
G01Y576183D02*
Y571518D01*
G01Y583287D02*
Y578613D01*
G01Y590310D02*
Y585655D01*
G01Y597384D02*
Y592730D01*
G01Y604489D02*
Y599824D01*
G01Y639449D02*
Y613992D01*
G01Y611543D02*
Y606908D01*
G01X730222Y639449D02*
X722726D01*
G01X718660Y695022D02*
Y701222D01*
X721860D01*
Y695022D01*
X718660D01*
G01X737042Y733944D02*
X735042Y737344D01*
X733242Y734044D01*
G01X727026Y733940D02*
Y745948D01*
X743066D01*
Y733940D01*
X727026D01*
G01X722211Y743656D02*
X725411D01*
G01X722211Y737456D02*
Y743656D01*
G01X725411Y737456D02*
X722211D01*
G01X725411Y743656D02*
Y737456D01*
G01X729446Y769737D02*
Y766537D01*
G01X723246D02*
Y769737D01*
G01X729446Y766537D02*
X723246D01*
G01X729446Y757737D02*
Y754537D01*
G01X723246Y757737D02*
X729446D01*
G01X723246Y754537D02*
Y757737D01*
G01X729446Y754537D02*
X723246D01*
G01X729446Y765737D02*
Y762537D01*
G01X723246Y765737D02*
X729446D01*
G01X723246Y762537D02*
Y765737D01*
G01X729446Y762537D02*
X723246D01*
G01Y758537D02*
Y761737D01*
G01X729446Y758537D02*
X723246D01*
G01X729446Y761737D02*
Y758537D01*
G01X723246Y761737D02*
X729446D01*
G01X721796Y781558D02*
Y778358D01*
G01X723246Y769737D02*
X729446D01*
G01Y773737D02*
Y770537D01*
G01X723246Y773737D02*
X729446D01*
G01X723246Y770537D02*
Y773737D01*
G01X729446Y770537D02*
X723246D01*
G01X722218Y844969D02*
Y852969D01*
X724718D01*
X725518Y852569D01*
X726018Y852036D01*
X726218Y850969D01*
X726018Y849902D01*
X725418Y849236D01*
X724718Y848836D01*
X722218D01*
G01X724718D02*
X726218Y844969D01*
G01X730718Y848569D02*
X733918D01*
X733618Y849502D01*
X733118Y850036D01*
X732418Y850302D01*
X731718Y850169D01*
X731118Y849769D01*
X730718Y848836D01*
X730518Y848035D01*
Y847236D01*
X730718Y846436D01*
X731218Y845636D01*
X731818Y845102D01*
X732518Y844969D01*
X733218Y845236D01*
X733918Y846035D01*
G01X738418Y850302D02*
X740218Y844969D01*
X742018Y850302D01*
G01X748218Y844702D02*
X748018Y844836D01*
Y845102D01*
X748218Y845236D01*
X748418Y845102D01*
Y844836D01*
X748218Y844702D01*
G01Y848302D02*
X748018Y848436D01*
Y848702D01*
X748218Y848836D01*
X748418Y848702D01*
Y848436D01*
X748218Y848302D01*
G01X754318Y844969D02*
Y852969D01*
X758118D01*
G01X756718Y849102D02*
X754318D01*
G01X725827Y1689331D02*
Y1425158D01*
G01X727643Y1595447D02*
Y1593225D01*
X727796Y1592760D01*
X728103Y1592450D01*
X728486Y1592347D01*
X728869Y1592450D01*
X729176Y1592760D01*
X729329Y1593225D01*
Y1595447D01*
G01X730743Y1592967D02*
X730973Y1592605D01*
X731279Y1592399D01*
X731624Y1592347D01*
X731931Y1592399D01*
X732238Y1592657D01*
X732429Y1592967D01*
X732468Y1593277D01*
X732391Y1593639D01*
X732123Y1593897D01*
X731854Y1594000D01*
X731509D01*
G01X731854D02*
X732084Y1594155D01*
X732276Y1594414D01*
X732353Y1594724D01*
X732276Y1595034D01*
X732084Y1595292D01*
X731739Y1595447D01*
X731394Y1595395D01*
X731049Y1595189D01*
G01X733843Y1592967D02*
X734073Y1592605D01*
X734379Y1592399D01*
X734724Y1592347D01*
X735031Y1592399D01*
X735338Y1592657D01*
X735529Y1592967D01*
X735568Y1593277D01*
X735491Y1593639D01*
X735223Y1593897D01*
X734954Y1594000D01*
X734609D01*
G01X734954D02*
X735184Y1594155D01*
X735376Y1594414D01*
X735453Y1594724D01*
X735376Y1595034D01*
X735184Y1595292D01*
X734839Y1595447D01*
X734494Y1595395D01*
X734149Y1595189D01*
G01X737786Y1592347D02*
X738054Y1592399D01*
X738361Y1592554D01*
X738553Y1592812D01*
X738629Y1593174D01*
X738553Y1593535D01*
X738323Y1593845D01*
X737978Y1594000D01*
X737594D01*
X737364Y1594104D01*
X737173Y1594362D01*
X737096Y1594724D01*
X737211Y1595085D01*
X737479Y1595344D01*
X737786Y1595447D01*
X738093Y1595344D01*
X738361Y1595085D01*
X738476Y1594724D01*
X738399Y1594362D01*
X738208Y1594104D01*
X737978Y1594000D01*
X737594D01*
X737249Y1593845D01*
X737019Y1593535D01*
X736943Y1593174D01*
X737019Y1592812D01*
X737211Y1592554D01*
X737518Y1592399D01*
X737786Y1592347D01*
G01X736992Y1597665D02*
X733792D01*
G01Y1603865D02*
X736992D01*
G01X733792Y1597665D02*
Y1603865D01*
G01X731300Y1608200D02*
X737500D01*
G01X731300Y1605000D02*
Y1608200D01*
G01X737500Y1605000D02*
X731300D01*
G01X729713Y1610850D02*
X729661Y1610543D01*
X729455Y1610275D01*
X729145Y1610045D01*
X728783Y1609892D01*
X728370Y1609815D01*
X727956D01*
X727543Y1609892D01*
X727181Y1610045D01*
X726871Y1610275D01*
X726665Y1610543D01*
X726613Y1610850D01*
X726665Y1611157D01*
X726871Y1611425D01*
X727181Y1611655D01*
X727543Y1611808D01*
X727956Y1611885D01*
X728370D01*
X728783Y1611808D01*
X729145Y1611655D01*
X729455Y1611425D01*
X729661Y1611157D01*
X729713Y1610850D01*
G01X728886Y1611157D02*
X729713Y1611617D01*
G01Y1613950D02*
X726613D01*
X727233Y1613490D01*
G01X729713D02*
Y1614410D01*
G01X727130Y1616322D02*
X726820Y1616552D01*
X726665Y1616820D01*
X726613Y1617127D01*
X726716Y1617510D01*
X726975Y1617778D01*
X727285Y1617855D01*
X727595Y1617817D01*
X727853Y1617663D01*
X728370Y1616897D01*
X728731Y1616552D01*
X729248Y1616322D01*
X729713Y1616245D01*
Y1617855D01*
G01X729248Y1619307D02*
X729506Y1619537D01*
X729661Y1619805D01*
X729713Y1620150D01*
X729610Y1620495D01*
X729403Y1620763D01*
X729041Y1620955D01*
X728628Y1620993D01*
X728215Y1620917D01*
X727956Y1620725D01*
X727750Y1620457D01*
X727698Y1620188D01*
X727750Y1619920D01*
X727956Y1619575D01*
X726613Y1619690D01*
Y1620725D01*
G01X730951Y1610120D02*
X741465D01*
G01X730951Y1618782D02*
Y1610120D01*
G01X733770Y1626690D02*
Y1620490D01*
G01X730570Y1626690D02*
X733770D01*
G01X730570Y1620490D02*
Y1626690D01*
G01X733770Y1620490D02*
X730570D01*
G01X741465Y1618782D02*
X730951D01*
G01X736851Y1632885D02*
X730651D01*
Y1636085D01*
X736851D01*
Y1632885D01*
G01X736867Y1628430D02*
X730667D01*
Y1631630D01*
X736867D01*
Y1628430D01*
G01X741181Y82540D02*
Y85740D01*
G01X747381Y82540D02*
X741181D01*
G01X747381Y85740D02*
Y82540D01*
G01X741181Y74540D02*
Y77740D01*
G01X747381Y74540D02*
X741181D01*
G01X747381Y77740D02*
Y74540D01*
G01X741181Y77740D02*
X747381D01*
G01X741181Y78540D02*
Y81740D01*
G01X747381Y78540D02*
X741181D01*
G01X747381Y81740D02*
Y78540D01*
G01X741181Y81740D02*
X747381D01*
G01X741181Y85740D02*
X747381D01*
G01X744801Y86929D02*
X741601D01*
G01X744801Y93129D02*
Y86929D01*
G01X741601Y93129D02*
X744801D01*
G01X741601Y86929D02*
Y93129D01*
G01X740792Y86929D02*
X737592D01*
G01X740792Y93129D02*
Y86929D01*
G01X737592Y93129D02*
X740792D01*
G01X737592Y86929D02*
Y93129D01*
G01X736792D02*
Y86929D01*
G01X740871Y96673D02*
Y102873D01*
G01X744071Y96673D02*
X740871D01*
G01X744071Y102873D02*
Y96673D01*
G01X746375Y95950D02*
Y102150D01*
G01X749575Y95950D02*
X746375D01*
G01X749575Y102150D02*
Y95950D01*
G01X736871Y96673D02*
Y102873D01*
G01X740071Y96673D02*
X736871D01*
G01X740071Y102873D02*
Y96673D01*
G01X740871Y102873D02*
X744071D01*
G01X746375Y102150D02*
X749575D01*
G01X736871Y102873D02*
X740071D01*
G01X746375Y109762D02*
X749575D01*
G01X746375Y103562D02*
Y109762D01*
G01X749575Y103562D02*
X746375D01*
G01X749575Y109762D02*
Y103562D01*
G01X742854Y144690D02*
Y154138D01*
G01X753690Y144690D02*
X742854D01*
G01X745435Y139647D02*
Y142847D01*
G01X751635Y139647D02*
X745435D01*
G01Y142847D02*
X751635D01*
G01X738456Y139647D02*
Y142847D01*
G01X744656Y139647D02*
X738456D01*
G01X744656Y142847D02*
Y139647D01*
G01X738456Y142847D02*
X744656D01*
G01X734486Y145940D02*
Y149140D01*
G01X740686Y145940D02*
X734486D01*
G01X740686Y149140D02*
Y145940D01*
G01X734486Y149140D02*
X740686D01*
G01X743550Y155600D02*
X743243Y155652D01*
X742975Y155858D01*
X742745Y156168D01*
X742592Y156530D01*
X742515Y156943D01*
Y157357D01*
X742592Y157770D01*
X742745Y158132D01*
X742975Y158442D01*
X743243Y158648D01*
X743550Y158700D01*
X743857Y158648D01*
X744125Y158442D01*
X744355Y158132D01*
X744508Y157770D01*
X744585Y157357D01*
Y156943D01*
X744508Y156530D01*
X744355Y156168D01*
X744125Y155858D01*
X743857Y155652D01*
X743550Y155600D01*
G01X743857Y156427D02*
X744317Y155600D01*
G01X745922Y158183D02*
X746152Y158493D01*
X746420Y158648D01*
X746727Y158700D01*
X747110Y158597D01*
X747378Y158338D01*
X747455Y158028D01*
X747417Y157718D01*
X747263Y157460D01*
X746497Y156943D01*
X746152Y156582D01*
X745922Y156065D01*
X745845Y155600D01*
X747455D01*
G01X749022Y158183D02*
X749252Y158493D01*
X749520Y158648D01*
X749827Y158700D01*
X750210Y158597D01*
X750478Y158338D01*
X750555Y158028D01*
X750517Y157718D01*
X750363Y157460D01*
X749597Y156943D01*
X749252Y156582D01*
X749022Y156065D01*
X748945Y155600D01*
X750555D01*
G01X752007Y156220D02*
X752237Y155858D01*
X752543Y155652D01*
X752888Y155600D01*
X753195Y155652D01*
X753502Y155910D01*
X753693Y156220D01*
X753732Y156530D01*
X753655Y156892D01*
X753387Y157150D01*
X753118Y157253D01*
X752773D01*
G01X753118D02*
X753348Y157408D01*
X753540Y157667D01*
X753617Y157977D01*
X753540Y158287D01*
X753348Y158545D01*
X753003Y158700D01*
X752658Y158648D01*
X752313Y158442D01*
G01X750272Y154138D02*
X753690D01*
G01X748272Y152414D02*
X750272Y154138D01*
G01X746272D02*
X748272Y152414D01*
G01X742854Y154138D02*
X746272D01*
G01X740686Y153140D02*
Y149940D01*
G01X734486Y153140D02*
X740686D01*
G01X734486Y149940D02*
Y153140D01*
G01X740686Y149940D02*
X734486D01*
G01X748457Y174900D02*
Y172678D01*
X748610Y172213D01*
X748917Y171903D01*
X749300Y171800D01*
X749683Y171903D01*
X749990Y172213D01*
X750143Y172678D01*
Y174900D01*
G01X751672Y173092D02*
X751940Y173453D01*
X752170Y173660D01*
X752477Y173763D01*
X752745Y173660D01*
X752937Y173453D01*
X753090Y173143D01*
X753128Y172782D01*
X753090Y172472D01*
X752937Y172162D01*
X752707Y171903D01*
X752438Y171800D01*
X752132Y171903D01*
X751863Y172213D01*
X751710Y172678D01*
X751672Y173195D01*
X751748Y173867D01*
X751863Y174228D01*
X752055Y174590D01*
X752323Y174848D01*
X752592Y174900D01*
X752860Y174797D01*
X753052Y174538D01*
G01X755500Y171800D02*
Y174900D01*
X755040Y174280D01*
G01Y171800D02*
X755960D01*
G01X745850Y176944D02*
Y178897D01*
G01X747803Y176944D02*
X745850D01*
G01X741122Y171473D02*
X737922D01*
G01X741122Y177673D02*
Y171473D01*
G01X737922Y177673D02*
X741122D01*
G01X737922Y171473D02*
Y177673D01*
G01X744145Y170297D02*
Y167097D01*
G01X737945Y170297D02*
X744145D01*
G01X737945Y167097D02*
Y170297D01*
G01X744145Y167097D02*
X737945D01*
G01X737122Y177673D02*
Y171473D01*
G01X745850Y188756D02*
X747803D01*
G01X745850Y186803D02*
Y188756D01*
G01X741349Y182730D02*
X738149D01*
G01X741349Y188930D02*
Y182730D01*
G01X738149Y188930D02*
X741349D01*
G01X738149Y182730D02*
Y188930D01*
G01X744340Y193541D02*
Y190341D01*
G01X738140Y193541D02*
X744340D01*
G01X738140Y190341D02*
Y193541D01*
G01X744340Y190341D02*
X738140D01*
G01X735469Y225035D02*
Y213035D01*
G01X744923Y201762D02*
Y204862D01*
X745843D01*
X746150Y204707D01*
X746380Y204345D01*
X746457Y203932D01*
X746380Y203519D01*
X746188Y203209D01*
X745843Y203054D01*
X744923D01*
G01X747947Y204862D02*
Y202640D01*
X748100Y202175D01*
X748407Y201865D01*
X748790Y201762D01*
X749173Y201865D01*
X749480Y202175D01*
X749633Y202640D01*
Y204862D01*
G01X751047Y202382D02*
X751277Y202020D01*
X751583Y201814D01*
X751928Y201762D01*
X752235Y201814D01*
X752542Y202072D01*
X752733Y202382D01*
X752772Y202692D01*
X752695Y203054D01*
X752427Y203312D01*
X752158Y203415D01*
X751813D01*
G01X752158D02*
X752388Y203570D01*
X752580Y203829D01*
X752657Y204139D01*
X752580Y204449D01*
X752388Y204707D01*
X752043Y204862D01*
X751698Y204810D01*
X751353Y204604D01*
G01X754147Y202227D02*
X754377Y201969D01*
X754645Y201814D01*
X754990Y201762D01*
X755335Y201865D01*
X755603Y202072D01*
X755795Y202434D01*
X755833Y202847D01*
X755757Y203260D01*
X755565Y203519D01*
X755297Y203725D01*
X755028Y203777D01*
X754760Y203725D01*
X754415Y203519D01*
X754530Y204862D01*
X755565D01*
G01X758625Y220252D02*
Y208048D01*
X743321D01*
Y220252D01*
X758625D01*
G01X736309Y226621D02*
Y232621D01*
G01X748309Y226621D02*
X736309D01*
G01X748309Y232621D02*
Y226621D01*
G01X740288Y215082D02*
X737088D01*
G01X740288Y221282D02*
Y215082D01*
G01X737088Y221282D02*
X740288D01*
G01X737088Y215082D02*
Y221282D01*
G01X746309Y225921D02*
Y222721D01*
G01X740109Y225921D02*
X746309D01*
G01X740109Y222721D02*
Y225921D01*
G01X746309Y222721D02*
X740109D01*
G01X736309Y232621D02*
X748309D01*
G01X736977Y258010D02*
Y264210D01*
G01X740177Y258010D02*
X736977D01*
G01X740177Y264210D02*
Y258010D01*
G01X744977D02*
Y264210D01*
G01X748177Y258010D02*
X744977D01*
G01X748177Y264210D02*
Y258010D01*
G01X744177D02*
X740977D01*
G01X744177Y264210D02*
Y258010D01*
G01X740977D02*
Y264210D01*
G01X735047Y283655D02*
Y271655D01*
G01X736977Y264210D02*
X740177D01*
G01X744977D02*
X748177D01*
G01X753256Y273701D02*
X750056D01*
G01D02*
Y279901D01*
G01X740977Y264210D02*
X744177D01*
G01X747698Y279427D02*
Y267653D01*
G01X737936D02*
Y279427D01*
G01X747698Y267653D02*
X737936D01*
G01X750056Y279901D02*
X753256D01*
G01X739230Y283383D02*
X736030D01*
G01X739230Y289583D02*
Y283383D01*
G01X736030Y289583D02*
X739230D01*
G01X736030Y283383D02*
Y289583D01*
G01X743230Y283383D02*
X740030D01*
G01X743230Y289583D02*
Y283383D01*
G01X740030Y289583D02*
X743230D01*
G01X740030Y283383D02*
Y289583D01*
G01X744030Y283383D02*
Y289583D01*
X747230D01*
Y283383D01*
X744030D01*
G01X752000Y282833D02*
X748900D01*
Y283753D01*
X749055Y284060D01*
X749417Y284290D01*
X749830Y284367D01*
X750243Y284290D01*
X750553Y284098D01*
X750708Y283753D01*
Y282833D01*
G01X748900Y285857D02*
X751122D01*
X751587Y286010D01*
X751897Y286317D01*
X752000Y286700D01*
X751897Y287083D01*
X751587Y287390D01*
X751122Y287543D01*
X748900D01*
G01X752000Y289800D02*
X748900D01*
X749520Y289340D01*
G01X752000D02*
Y290260D01*
G01X748900Y292900D02*
X749003Y292593D01*
X749262Y292363D01*
X749572Y292210D01*
X749985Y292095D01*
X750450Y292057D01*
X750915Y292095D01*
X751328Y292210D01*
X751638Y292363D01*
X751897Y292593D01*
X752000Y292900D01*
X751897Y293207D01*
X751638Y293437D01*
X751328Y293590D01*
X750915Y293705D01*
X750450Y293743D01*
X749985Y293705D01*
X749572Y293590D01*
X749262Y293437D01*
X749003Y293207D01*
X748900Y292900D01*
G01X751638Y295348D02*
X751897Y295617D01*
X752000Y295923D01*
X751897Y296230D01*
X751587Y296498D01*
X751122Y296690D01*
X750657Y296767D01*
X750088D01*
X749623Y296690D01*
X749210Y296498D01*
X749003Y296268D01*
X748900Y296000D01*
X749003Y295693D01*
X749210Y295463D01*
X749520Y295310D01*
X749933Y295233D01*
X750295Y295310D01*
X750657Y295502D01*
X750863Y295732D01*
X750915Y296000D01*
X750812Y296307D01*
X750553Y296537D01*
X750088Y296767D01*
G01X737936Y279427D02*
X747698D01*
G01X742501Y316273D02*
Y319473D01*
G01X748701Y316273D02*
X742501D01*
G01X748701Y319473D02*
Y316273D01*
G01X742501Y319473D02*
X748701D01*
G01X742742Y366063D02*
X758218D01*
G01Y639449D02*
X742672D01*
G01X735095Y732635D02*
Y730413D01*
X735248Y729948D01*
X735555Y729638D01*
X735938Y729535D01*
X736321Y729638D01*
X736628Y729948D01*
X736781Y730413D01*
Y732635D01*
G01X738195Y730000D02*
X738425Y729742D01*
X738693Y729587D01*
X739038Y729535D01*
X739383Y729638D01*
X739651Y729845D01*
X739843Y730207D01*
X739881Y730620D01*
X739805Y731033D01*
X739613Y731292D01*
X739345Y731498D01*
X739076Y731550D01*
X738808Y731498D01*
X738463Y731292D01*
X738578Y732635D01*
X739613D01*
G01X741410Y732118D02*
X741640Y732428D01*
X741908Y732583D01*
X742215Y732635D01*
X742598Y732532D01*
X742866Y732273D01*
X742943Y731963D01*
X742905Y731653D01*
X742751Y731395D01*
X741985Y730878D01*
X741640Y730517D01*
X741410Y730000D01*
X741333Y729535D01*
X742943D01*
G01X747036Y1426462D02*
Y1439109D01*
G01X737194Y1426462D02*
X747036D01*
G01X737194Y1429109D02*
Y1426462D01*
G01Y1449109D02*
Y1434209D01*
G01X747036Y1444209D02*
Y1456856D01*
G01X738506Y1459607D02*
Y1462707D01*
X739426D01*
X739733Y1462552D01*
X739963Y1462190D01*
X740040Y1461777D01*
X739963Y1461364D01*
X739771Y1461054D01*
X739426Y1460899D01*
X738506D01*
G01X741606Y1460227D02*
X741798Y1459917D01*
X742028Y1459710D01*
X742296Y1459607D01*
X742603Y1459710D01*
X742833Y1459917D01*
X743063Y1460227D01*
X743140Y1460640D01*
Y1462707D01*
G01X745473Y1459607D02*
Y1462707D01*
X745013Y1462087D01*
G01Y1459607D02*
X745933D01*
G01X737194Y1456856D02*
Y1454209D01*
G01X747036Y1456856D02*
X737194D01*
G01X783219Y1462144D02*
G02X764406Y1521850I-12747J28800D01*
G01X748185Y1521142D02*
Y1524242D01*
G01X749795D02*
Y1521142D01*
G01Y1522692D02*
X748185D01*
G01X752090Y1521142D02*
X752358Y1521194D01*
X752665Y1521349D01*
X752857Y1521607D01*
X752933Y1521969D01*
X752857Y1522330D01*
X752627Y1522640D01*
X752282Y1522795D01*
X751898D01*
X751668Y1522899D01*
X751477Y1523157D01*
X751400Y1523519D01*
X751515Y1523880D01*
X751783Y1524139D01*
X752090Y1524242D01*
X752397Y1524139D01*
X752665Y1523880D01*
X752780Y1523519D01*
X752703Y1523157D01*
X752512Y1522899D01*
X752282Y1522795D01*
X751898D01*
X751553Y1522640D01*
X751323Y1522330D01*
X751247Y1521969D01*
X751323Y1521607D01*
X751515Y1521349D01*
X751822Y1521194D01*
X752090Y1521142D01*
G01X755190Y1524242D02*
X754883Y1524139D01*
X754653Y1523880D01*
X754500Y1523570D01*
X754385Y1523157D01*
X754347Y1522692D01*
X754385Y1522227D01*
X754500Y1521814D01*
X754653Y1521504D01*
X754883Y1521245D01*
X755190Y1521142D01*
X755497Y1521245D01*
X755727Y1521504D01*
X755880Y1521814D01*
X755995Y1522227D01*
X756033Y1522692D01*
X755995Y1523157D01*
X755880Y1523570D01*
X755727Y1523880D01*
X755497Y1524139D01*
X755190Y1524242D01*
G01X745540Y1588410D02*
X748740D01*
G01X745540Y1582210D02*
Y1588410D01*
G01X748740Y1582210D02*
X745540D01*
G01X748740Y1588410D02*
Y1582210D01*
G01X752740D02*
X749540D01*
G01Y1588410D02*
X752740D01*
G01X749540Y1582210D02*
Y1588410D01*
G01X740255Y1597665D02*
Y1591517D01*
G01D02*
X751673D01*
G01X736992Y1603865D02*
Y1597665D01*
G01X737500Y1608200D02*
Y1605000D01*
G01X747324Y1610268D02*
Y1616468D01*
G01X750524Y1610268D02*
X747324D01*
G01X746524D02*
X743324D01*
G01X746524Y1616468D02*
Y1610268D01*
G01X743324D02*
Y1616468D01*
G01X740255Y1601483D02*
X742964Y1599574D01*
G01X740255Y1607631D02*
Y1601483D01*
G01X751673Y1607631D02*
X740255D01*
G01X742964Y1599574D02*
X740255Y1597665D01*
G01X741465Y1610120D02*
Y1618782D01*
G01X747324Y1616468D02*
X750524D01*
G01X743324D02*
X746524D01*
G01X740830Y1620415D02*
X734630D01*
G01X740830Y1623615D02*
Y1620415D01*
G01X734630Y1623615D02*
X740830D01*
G01X734630Y1620415D02*
Y1623615D01*
G01X750597Y1626010D02*
Y1619810D01*
X747397D01*
Y1626010D01*
X750597D01*
G01X741731Y1629119D02*
Y1635319D01*
X744931D01*
Y1629119D01*
X741731D01*
G01X749190Y1635309D02*
Y1629109D01*
X745990D01*
Y1635309D01*
X749190D01*
G01X772679Y67523D02*
X760475D01*
G01D02*
Y70183D01*
G01X761172Y59613D02*
X767372D01*
G01X761172Y56413D02*
Y59613D01*
G01X767372Y56413D02*
X761172D01*
G01X758047Y70181D02*
Y66981D01*
G01X751847D02*
Y70181D01*
G01X758047Y66981D02*
X751847D01*
G01X760475Y79047D02*
X772679D01*
G01X760475Y76285D02*
Y79047D01*
G01X763577Y73285D02*
X760475Y76285D01*
G01Y70183D02*
X763577Y73285D01*
G01X751847Y70181D02*
X758047D01*
G01X751892Y70962D02*
Y74162D01*
G01X758092Y70962D02*
X751892D01*
G01X758092Y74162D02*
Y70962D01*
G01X751892Y74162D02*
X758092D01*
G01X751892Y74987D02*
Y78187D01*
G01X758092Y74987D02*
X751892D01*
G01X758092Y78187D02*
Y74987D01*
G01X751892Y78187D02*
X758092D01*
G01X758047Y82181D02*
Y78981D01*
G01X751847Y82181D02*
X758047D01*
G01X751847Y78981D02*
Y82181D01*
G01X758047Y78981D02*
X751847D01*
G01X758882Y93476D02*
X762082D01*
G01X758882Y87276D02*
Y93476D01*
G01X762082Y87276D02*
X758882D01*
G01X762082Y93476D02*
Y87276D01*
G01X767582D02*
X764382D01*
G01Y93476D02*
X767582D01*
G01X764382Y87276D02*
Y93476D01*
G01X765100Y98907D02*
X767322D01*
X767787Y99060D01*
X768097Y99367D01*
X768200Y99750D01*
X768097Y100133D01*
X767787Y100440D01*
X767322Y100593D01*
X765100D01*
G01X768200Y103310D02*
X765100D01*
X767322Y101892D01*
Y103808D01*
G01X765100Y105950D02*
X765203Y105643D01*
X765462Y105413D01*
X765772Y105260D01*
X766185Y105145D01*
X766650Y105107D01*
X767115Y105145D01*
X767528Y105260D01*
X767838Y105413D01*
X768097Y105643D01*
X768200Y105950D01*
X768097Y106257D01*
X767838Y106487D01*
X767528Y106640D01*
X767115Y106755D01*
X766650Y106793D01*
X766185Y106755D01*
X765772Y106640D01*
X765462Y106487D01*
X765203Y106257D01*
X765100Y105950D01*
G01X768200Y109510D02*
X765100D01*
X767322Y108092D01*
Y110008D01*
G01X763717Y111267D02*
Y95913D01*
G01X751039D02*
Y111267D01*
G01X763520Y95913D02*
X751039D01*
G01X764873Y111951D02*
Y118151D01*
G01X768073Y111951D02*
X764873D01*
G01X763590Y116088D02*
Y112888D01*
G01X757390Y116088D02*
X763590D01*
G01X757390Y112888D02*
Y116088D01*
G01X763590Y112888D02*
X757390D01*
G01X751039Y111267D02*
X763717D01*
G01X764873Y118151D02*
X768073D01*
G01X764074Y119160D02*
X760974D01*
Y120080D01*
X761129Y120387D01*
X761491Y120617D01*
X761904Y120694D01*
X762317Y120617D01*
X762627Y120425D01*
X762782Y120080D01*
Y119160D01*
G01X760974Y122184D02*
X763196D01*
X763661Y122337D01*
X763971Y122644D01*
X764074Y123027D01*
X763971Y123410D01*
X763661Y123717D01*
X763196Y123870D01*
X760974D01*
G01X764074Y126127D02*
X760974D01*
X761594Y125667D01*
G01X764074D02*
Y126587D01*
G01X761491Y128499D02*
X761181Y128729D01*
X761026Y128997D01*
X760974Y129304D01*
X761077Y129687D01*
X761336Y129955D01*
X761646Y130032D01*
X761956Y129994D01*
X762214Y129840D01*
X762731Y129074D01*
X763092Y128729D01*
X763609Y128499D01*
X764074Y128422D01*
Y130032D01*
G01X762782Y131599D02*
X762421Y131867D01*
X762214Y132097D01*
X762111Y132404D01*
X762214Y132672D01*
X762421Y132864D01*
X762731Y133017D01*
X763092Y133055D01*
X763402Y133017D01*
X763712Y132864D01*
X763971Y132634D01*
X764074Y132365D01*
X763971Y132059D01*
X763661Y131790D01*
X763196Y131637D01*
X762679Y131599D01*
X762007Y131675D01*
X761646Y131790D01*
X761284Y131982D01*
X761026Y132250D01*
X760974Y132519D01*
X761077Y132787D01*
X761336Y132979D01*
G01X753690Y154138D02*
Y144690D01*
G01X755097Y144168D02*
Y147368D01*
G01X761297Y144168D02*
X755097D01*
G01X761297Y147368D02*
Y144168D01*
G01X755097Y147368D02*
X761297D01*
G01X751635Y142847D02*
Y139647D01*
G01X761297Y151368D02*
Y148168D01*
G01X755097D02*
Y151368D01*
G01X761297Y148168D02*
X755097D01*
G01X762100Y136907D02*
X764322D01*
X764787Y137060D01*
X765097Y137367D01*
X765200Y137750D01*
X765097Y138133D01*
X764787Y138440D01*
X764322Y138593D01*
X762100D01*
G01X764580Y140007D02*
X764942Y140237D01*
X765148Y140543D01*
X765200Y140888D01*
X765148Y141195D01*
X764890Y141502D01*
X764580Y141693D01*
X764270Y141732D01*
X763908Y141655D01*
X763650Y141387D01*
X763547Y141118D01*
Y140773D01*
G01Y141118D02*
X763392Y141348D01*
X763133Y141540D01*
X762823Y141617D01*
X762513Y141540D01*
X762255Y141348D01*
X762100Y141003D01*
X762152Y140658D01*
X762358Y140313D01*
G01X765200Y143950D02*
X765148Y144218D01*
X764993Y144525D01*
X764735Y144717D01*
X764373Y144793D01*
X764012Y144717D01*
X763702Y144487D01*
X763547Y144142D01*
Y143758D01*
X763443Y143528D01*
X763185Y143337D01*
X762823Y143260D01*
X762462Y143375D01*
X762203Y143643D01*
X762100Y143950D01*
X762203Y144257D01*
X762462Y144525D01*
X762823Y144640D01*
X763185Y144563D01*
X763443Y144372D01*
X763547Y144142D01*
Y143758D01*
X763702Y143413D01*
X764012Y143183D01*
X764373Y143107D01*
X764735Y143183D01*
X764993Y143375D01*
X765148Y143682D01*
X765200Y143950D01*
G01Y147050D02*
X765148Y147318D01*
X764993Y147625D01*
X764735Y147817D01*
X764373Y147893D01*
X764012Y147817D01*
X763702Y147587D01*
X763547Y147242D01*
Y146858D01*
X763443Y146628D01*
X763185Y146437D01*
X762823Y146360D01*
X762462Y146475D01*
X762203Y146743D01*
X762100Y147050D01*
X762203Y147357D01*
X762462Y147625D01*
X762823Y147740D01*
X763185Y147663D01*
X763443Y147472D01*
X763547Y147242D01*
Y146858D01*
X763702Y146513D01*
X764012Y146283D01*
X764373Y146207D01*
X764735Y146283D01*
X764993Y146475D01*
X765148Y146782D01*
X765200Y147050D01*
G01X755097Y151368D02*
X761297D01*
G01X757662Y178897D02*
Y176944D01*
G01D02*
X755709D01*
G01X762033Y179065D02*
Y182265D01*
G01X768233Y179065D02*
X762033D01*
G01Y171065D02*
Y174265D01*
G01X768233Y171065D02*
X762033D01*
G01Y174265D02*
X768233D01*
G01X762033Y175065D02*
Y178265D01*
G01X768233Y175065D02*
X762033D01*
G01Y178265D02*
X768233D01*
G01X762033Y167065D02*
Y170265D01*
G01X768233Y167065D02*
X762033D01*
G01Y170265D02*
X768233D01*
G01X757662Y188756D02*
Y186803D01*
G01X755709Y188756D02*
X757662D01*
G01X762033Y182265D02*
X768233D01*
G01X762033Y183065D02*
Y186265D01*
G01X768233Y183065D02*
X762033D01*
G01Y186265D02*
X768233D01*
G01X762033Y187065D02*
Y190265D01*
G01X768233Y187065D02*
X762033D01*
G01Y190265D02*
X768233D01*
G01X762033Y195065D02*
Y198265D01*
G01X768233Y195065D02*
X762033D01*
G01Y194265D02*
X768233D01*
G01X762033Y191065D02*
Y194265D01*
G01X768233Y191065D02*
X762033D01*
G01X754709Y195020D02*
Y198220D01*
G01X760909Y195020D02*
X754709D01*
G01X760909Y198220D02*
Y195020D01*
G01X762128Y202464D02*
X768328D01*
Y199264D01*
X762128D01*
Y202464D01*
G01X762033Y198265D02*
X768233D01*
G01X754709Y198220D02*
X760909D01*
G01X762128Y207264D02*
Y210464D01*
G01X768328Y207264D02*
X762128D01*
G01Y210464D02*
X768328D01*
G01X762128Y206464D02*
X768328D01*
G01X762128Y203264D02*
Y206464D01*
G01X768328Y203264D02*
X762128D01*
G01Y214464D02*
X768328D01*
Y211264D01*
X762128D01*
Y214464D01*
G01Y215264D02*
Y218464D01*
G01X768328Y215264D02*
X762128D01*
G01Y218464D02*
X768328D01*
G01X762128Y220264D02*
Y223464D01*
G01X768328Y220264D02*
X762128D01*
G01Y223464D02*
X768328D01*
G01X759844Y234813D02*
Y250325D01*
G01X754888Y264635D02*
X770400D01*
G01X754888Y295727D02*
Y264635D01*
G01X753256Y279901D02*
Y273701D01*
G01X770400Y295727D02*
X754888D01*
G01X753950Y324600D02*
X753643Y324652D01*
X753375Y324858D01*
X753145Y325168D01*
X752992Y325530D01*
X752915Y325943D01*
Y326357D01*
X752992Y326770D01*
X753145Y327132D01*
X753375Y327442D01*
X753643Y327648D01*
X753950Y327700D01*
X754257Y327648D01*
X754525Y327442D01*
X754755Y327132D01*
X754908Y326770D01*
X754985Y326357D01*
Y325943D01*
X754908Y325530D01*
X754755Y325168D01*
X754525Y324858D01*
X754257Y324652D01*
X753950Y324600D01*
G01X754257Y325427D02*
X754717Y324600D01*
G01X757510D02*
Y327700D01*
X756092Y325478D01*
X758008D01*
G01X762990Y323621D02*
X760659Y321290D01*
G01X766099Y323621D02*
X762990D01*
G01X766099Y314959D02*
Y323621D01*
G01X755219Y314959D02*
X766099D01*
G01X755219Y323621D02*
Y314959D01*
G01X758328Y323621D02*
X755219D01*
G01X760659Y321290D02*
X758328Y323621D01*
G01X771037Y326084D02*
X764437D01*
G01D02*
Y339084D01*
G01X763229Y327342D02*
X760029D01*
G01X763229Y333542D02*
Y327342D01*
G01X760029D02*
Y333542D01*
G01X758071Y340646D02*
Y349110D01*
G01X771333Y340646D02*
X758071D01*
G01X764437Y339084D02*
X780637D01*
G01X760029Y333542D02*
X763229D01*
G01X761107Y353300D02*
Y351078D01*
X761260Y350613D01*
X761567Y350303D01*
X761950Y350200D01*
X762333Y350303D01*
X762640Y350613D01*
X762793Y351078D01*
Y353300D01*
G01X764322Y352783D02*
X764552Y353093D01*
X764820Y353248D01*
X765127Y353300D01*
X765510Y353197D01*
X765778Y352938D01*
X765855Y352628D01*
X765817Y352318D01*
X765663Y352060D01*
X764897Y351543D01*
X764552Y351182D01*
X764322Y350665D01*
X764245Y350200D01*
X765855D01*
G01X767307Y350665D02*
X767537Y350407D01*
X767805Y350252D01*
X768150Y350200D01*
X768495Y350303D01*
X768763Y350510D01*
X768955Y350872D01*
X768993Y351285D01*
X768917Y351698D01*
X768725Y351957D01*
X768457Y352163D01*
X768188Y352215D01*
X767920Y352163D01*
X767575Y351957D01*
X767690Y353300D01*
X768725D01*
G01X763202Y349110D02*
X764702Y347339D01*
G01X758071Y349110D02*
X763202D01*
G01X766202D02*
X771333D01*
G01X764702Y347339D02*
X766202Y349110D01*
G01X758218Y366063D02*
Y467779D01*
G01Y470189D02*
Y474925D01*
G01Y484428D02*
Y488909D01*
G01Y477324D02*
Y481824D01*
G01Y491595D02*
Y511832D01*
G01Y521427D02*
Y526164D01*
G01Y514354D02*
Y519080D01*
G01Y535565D02*
Y561873D01*
G01Y528512D02*
Y533125D01*
G01Y564498D02*
Y568894D01*
G01Y585748D02*
Y589992D01*
G01Y578695D02*
Y583103D01*
G01Y571662D02*
Y575968D01*
G01Y599937D02*
Y604181D01*
G01Y592945D02*
Y597230D01*
G01Y639449D02*
Y614014D01*
G01Y607072D02*
Y611439D01*
G01X755102Y1402617D02*
Y1414567D01*
G01X765102Y1402617D02*
X755102D01*
G01X765102Y1404567D02*
Y1402617D01*
G01Y1424567D02*
Y1410667D01*
G01X755102Y1420667D02*
Y1432617D01*
G01X765102D02*
Y1430667D01*
G01X756047Y1436464D02*
X756239Y1436154D01*
X756469Y1435947D01*
X756737Y1435844D01*
X757044Y1435947D01*
X757274Y1436154D01*
X757504Y1436464D01*
X757581Y1436877D01*
Y1438944D01*
G01X759071Y1436309D02*
X759301Y1436051D01*
X759569Y1435896D01*
X759914Y1435844D01*
X760259Y1435947D01*
X760527Y1436154D01*
X760719Y1436516D01*
X760757Y1436929D01*
X760681Y1437342D01*
X760489Y1437601D01*
X760221Y1437807D01*
X759952Y1437859D01*
X759684Y1437807D01*
X759339Y1437601D01*
X759454Y1438944D01*
X760489D01*
G01X763014Y1435844D02*
X763282Y1435896D01*
X763589Y1436051D01*
X763781Y1436309D01*
X763857Y1436671D01*
X763781Y1437032D01*
X763551Y1437342D01*
X763206Y1437497D01*
X762822D01*
X762592Y1437601D01*
X762401Y1437859D01*
X762324Y1438221D01*
X762439Y1438582D01*
X762707Y1438841D01*
X763014Y1438944D01*
X763321Y1438841D01*
X763589Y1438582D01*
X763704Y1438221D01*
X763627Y1437859D01*
X763436Y1437601D01*
X763206Y1437497D01*
X762822D01*
X762477Y1437342D01*
X762247Y1437032D01*
X762171Y1436671D01*
X762247Y1436309D01*
X762439Y1436051D01*
X762746Y1435896D01*
X763014Y1435844D01*
G01X755102Y1432617D02*
X765102D01*
G01X765912Y1445102D02*
Y1451302D01*
G01X769112Y1445102D02*
X765912D01*
G01Y1451302D02*
X769112D01*
G01X765784Y1565872D02*
Y1568972D01*
G01X767394D02*
Y1565872D01*
G01Y1567422D02*
X765784D01*
G01X768846Y1566337D02*
X769076Y1566079D01*
X769344Y1565924D01*
X769689Y1565872D01*
X770034Y1565975D01*
X770302Y1566182D01*
X770494Y1566544D01*
X770532Y1566957D01*
X770456Y1567370D01*
X770264Y1567629D01*
X769996Y1567835D01*
X769727Y1567887D01*
X769459Y1567835D01*
X769114Y1567629D01*
X769229Y1568972D01*
X770264D01*
G01X772789Y1565872D02*
X773057Y1565924D01*
X773364Y1566079D01*
X773556Y1566337D01*
X773632Y1566699D01*
X773556Y1567060D01*
X773326Y1567370D01*
X772981Y1567525D01*
X772597D01*
X772367Y1567629D01*
X772176Y1567887D01*
X772099Y1568249D01*
X772214Y1568610D01*
X772482Y1568869D01*
X772789Y1568972D01*
X773096Y1568869D01*
X773364Y1568610D01*
X773479Y1568249D01*
X773402Y1567887D01*
X773211Y1567629D01*
X772981Y1567525D01*
X772597D01*
X772252Y1567370D01*
X772022Y1567060D01*
X771946Y1566699D01*
X772022Y1566337D01*
X772214Y1566079D01*
X772521Y1565924D01*
X772789Y1565872D01*
G01X757042Y1607937D02*
X770042D01*
Y1591737D01*
X757042D01*
Y1598337D01*
X759542Y1599837D01*
X757042Y1601337D01*
Y1607937D01*
G01X761545Y1588388D02*
X764745D01*
G01X761545Y1582188D02*
Y1588388D01*
G01X764745Y1582188D02*
X761545D01*
G01X764745Y1588388D02*
Y1582188D01*
G01X760769Y1588435D02*
Y1582235D01*
X757569D01*
Y1588435D01*
X760769D01*
G01X752740Y1588410D02*
Y1582210D01*
G01X753587Y1582224D02*
Y1588424D01*
X756787D01*
Y1582224D01*
X753587D01*
G01X751673Y1591517D02*
Y1607631D01*
G01X750524Y1616468D02*
Y1610268D01*
G01X761052Y1612242D02*
X757852D01*
G01X761052Y1618442D02*
Y1612242D01*
G01X757852Y1618442D02*
X761052D01*
G01X757852Y1612242D02*
Y1618442D01*
G01X765852D02*
X769052D01*
G01Y1612242D02*
X765852D01*
G01D02*
Y1618442D01*
G01X761852D02*
X765052D01*
G01X761852Y1612242D02*
Y1618442D01*
G01X765052Y1612242D02*
X761852D01*
G01X765052Y1618442D02*
Y1612242D01*
G01X768878Y1619775D02*
X756674D01*
Y1635775D01*
X768878D01*
Y1629775D01*
X765776Y1627775D01*
X768878Y1625775D01*
Y1619775D01*
G01X753750Y1635334D02*
Y1629134D01*
X750550D01*
Y1635334D01*
X753750D01*
G01X772679Y79047D02*
Y67523D01*
G01X767372Y59613D02*
Y56413D01*
G01X774500Y68507D02*
X776722D01*
X777187Y68660D01*
X777497Y68967D01*
X777600Y69350D01*
X777497Y69733D01*
X777187Y70040D01*
X776722Y70193D01*
X774500D01*
G01X777600Y72450D02*
X774500D01*
X775120Y71990D01*
G01X777600D02*
Y72910D01*
G01X776980Y74707D02*
X777342Y74937D01*
X777548Y75243D01*
X777600Y75588D01*
X777548Y75895D01*
X777290Y76202D01*
X776980Y76393D01*
X776670Y76432D01*
X776308Y76355D01*
X776050Y76087D01*
X775947Y75818D01*
Y75473D01*
G01Y75818D02*
X775792Y76048D01*
X775533Y76240D01*
X775223Y76317D01*
X774913Y76240D01*
X774655Y76048D01*
X774500Y75703D01*
X774552Y75358D01*
X774758Y75013D01*
G01X775017Y77922D02*
X774707Y78152D01*
X774552Y78420D01*
X774500Y78727D01*
X774603Y79110D01*
X774862Y79378D01*
X775172Y79455D01*
X775482Y79417D01*
X775740Y79263D01*
X776257Y78497D01*
X776618Y78152D01*
X777135Y77922D01*
X777600Y77845D01*
Y79455D01*
G01X775438Y87299D02*
X772238D01*
G01X775438Y93499D02*
Y87299D01*
G01X772238Y93499D02*
X775438D01*
G01X772238Y87299D02*
Y93499D01*
G01X771531Y87204D02*
X768331D01*
G01X771531Y93404D02*
Y87204D01*
G01X768331Y93404D02*
X771531D01*
G01X768331Y87204D02*
Y93404D01*
G01X767582Y93476D02*
Y87276D01*
G01X782410Y110172D02*
Y122172D01*
G01X788410Y110172D02*
X782410D01*
G01X779793Y109424D02*
X782993D01*
G01X779793Y103224D02*
Y109424D01*
G01X782993Y103224D02*
X779793D01*
G01X768073Y118151D02*
Y111951D01*
G01X771793Y109424D02*
X774993D01*
G01X771793Y103224D02*
Y109424D01*
G01X774993Y103224D02*
X771793D01*
G01X774993Y109424D02*
Y103224D01*
G01X775793Y109424D02*
X778993D01*
G01X775793Y103224D02*
Y109424D01*
G01X778993Y103224D02*
X775793D01*
G01X778993Y109424D02*
Y103224D01*
G01X770247Y111734D02*
Y123508D01*
G01X780009Y111734D02*
X770247D01*
G01X780009Y123508D02*
Y111734D01*
G01X782410Y122172D02*
X788410D01*
G01X771018Y126223D02*
X767818D01*
G01X771018Y132423D02*
Y126223D01*
G01X767818Y132423D02*
X771018D01*
G01X767818Y126223D02*
Y132423D01*
G01X781018Y126223D02*
X777818D01*
G01X781018Y132423D02*
Y126223D01*
G01X777818Y132423D02*
X781018D01*
G01X777818Y126223D02*
Y132423D01*
G01X773818D02*
X777018D01*
G01X773818Y126223D02*
Y132423D01*
G01X777018Y126223D02*
X773818D01*
G01X777018Y132423D02*
Y126223D01*
G01X785072Y126228D02*
X781872D01*
G01Y132428D02*
X785072D01*
G01X781872Y126228D02*
Y132428D01*
G01X770247Y123508D02*
X780009D01*
G01X785251Y141337D02*
X782051D01*
G01Y147537D02*
X785251D01*
G01X782051Y141337D02*
Y147537D01*
G01X781916Y133238D02*
Y136438D01*
G01X788116Y133238D02*
X781916D01*
G01Y136438D02*
X788116D01*
G01X781916Y137238D02*
Y140438D01*
G01X788116Y137238D02*
X781916D01*
G01Y140438D02*
X788116D01*
G01X770207Y146229D02*
X767007D01*
G01X770207Y152429D02*
Y146229D01*
G01X767007D02*
Y152429D01*
G01X768697Y144395D02*
Y135095D01*
G01X779297Y144395D02*
X768697D01*
G01X779297Y134995D02*
Y144395D01*
G01X768697Y134995D02*
X779297D01*
G01X767007Y159540D02*
X770207D01*
G01X767007Y153340D02*
Y159540D01*
G01X770207Y153340D02*
X767007D01*
G01X770207Y159540D02*
Y153340D01*
G01X767007Y152429D02*
X770207D01*
G01X776920Y149950D02*
Y165304D01*
G01X789598Y149950D02*
X776920D01*
G01X777117Y165304D02*
X789598D01*
G01X768233Y182265D02*
Y179065D01*
G01Y174265D02*
Y171065D01*
G01Y178265D02*
Y175065D01*
G01Y170265D02*
Y167065D01*
G01X769801Y189435D02*
X772041D01*
G01X770828Y191060D02*
Y187810D01*
G01X773442Y195583D02*
X803001D01*
G01X773442Y184087D02*
Y195583D01*
G01X803001Y184087D02*
X773442D01*
G01X792418Y197645D02*
X780418D01*
G01D02*
Y203645D01*
G01X768233Y186265D02*
Y183065D01*
G01Y190265D02*
Y187065D01*
G01Y198265D02*
Y195065D01*
G01Y194265D02*
Y191065D01*
G01X780418Y203645D02*
X792418D01*
G01X773595Y204506D02*
Y216506D01*
G01X779595Y204506D02*
X773595D01*
G01X779595Y216506D02*
Y204506D01*
G01X780395Y208306D02*
Y214506D01*
G01X783595Y208306D02*
X780395D01*
G01X768328Y210464D02*
Y207264D01*
G01Y206464D02*
Y203264D01*
G01X773595Y216506D02*
X779595D01*
G01X768328Y218464D02*
Y215264D01*
G01Y223464D02*
Y220264D01*
G01X780395Y214506D02*
X783595D01*
G01X780761Y245521D02*
Y254969D01*
G01X791597Y245521D02*
X780761D01*
G01X784337Y231334D02*
X781137D01*
G01Y237534D02*
X784337D01*
G01X781137Y231334D02*
Y237534D01*
G01X782563Y243678D02*
Y240478D01*
G01X776363Y243678D02*
X782563D01*
G01X776363Y240478D02*
Y243678D01*
G01X782563Y240478D02*
X776363D01*
G01X772393Y246771D02*
Y249971D01*
G01X778593Y246771D02*
X772393D01*
G01X778593Y249971D02*
Y246771D01*
G01X783194Y257665D02*
X782887Y257717D01*
X782619Y257923D01*
X782389Y258233D01*
X782236Y258595D01*
X782159Y259008D01*
Y259422D01*
X782236Y259835D01*
X782389Y260197D01*
X782619Y260507D01*
X782887Y260713D01*
X783194Y260765D01*
X783501Y260713D01*
X783769Y260507D01*
X783999Y260197D01*
X784152Y259835D01*
X784229Y259422D01*
Y259008D01*
X784152Y258595D01*
X783999Y258233D01*
X783769Y257923D01*
X783501Y257717D01*
X783194Y257665D01*
G01X783501Y258492D02*
X783961Y257665D01*
G01X785566Y260248D02*
X785796Y260558D01*
X786064Y260713D01*
X786371Y260765D01*
X786754Y260662D01*
X787022Y260403D01*
X787099Y260093D01*
X787061Y259783D01*
X786907Y259525D01*
X786141Y259008D01*
X785796Y258647D01*
X785566Y258130D01*
X785489Y257665D01*
X787099D01*
G01X789394Y260765D02*
X789087Y260662D01*
X788857Y260403D01*
X788704Y260093D01*
X788589Y259680D01*
X788551Y259215D01*
X788589Y258750D01*
X788704Y258337D01*
X788857Y258027D01*
X789087Y257768D01*
X789394Y257665D01*
X789701Y257768D01*
X789931Y258027D01*
X790084Y258337D01*
X790199Y258750D01*
X790237Y259215D01*
X790199Y259680D01*
X790084Y260093D01*
X789931Y260403D01*
X789701Y260662D01*
X789394Y260765D01*
G01X791651Y258285D02*
X791881Y257923D01*
X792187Y257717D01*
X792532Y257665D01*
X792839Y257717D01*
X793146Y257975D01*
X793337Y258285D01*
X793376Y258595D01*
X793299Y258957D01*
X793031Y259215D01*
X792762Y259318D01*
X792417D01*
G01X792762D02*
X792992Y259473D01*
X793184Y259732D01*
X793261Y260042D01*
X793184Y260352D01*
X792992Y260610D01*
X792647Y260765D01*
X792302Y260713D01*
X791957Y260507D01*
G01X780761Y254969D02*
X784179D01*
G01X772393Y249971D02*
X778593D01*
G01Y253971D02*
Y250771D01*
G01X772393Y253971D02*
X778593D01*
G01X772393Y250771D02*
Y253971D01*
G01X778593Y250771D02*
X772393D01*
G01X774800Y264783D02*
X771700D01*
Y265703D01*
X771855Y266010D01*
X772217Y266240D01*
X772630Y266317D01*
X773043Y266240D01*
X773353Y266048D01*
X773508Y265703D01*
Y264783D01*
G01X774800Y267807D02*
X771700D01*
Y268573D01*
X771855Y268880D01*
X772062Y269110D01*
X772372Y269302D01*
X772733Y269455D01*
X773250Y269493D01*
X773767Y269455D01*
X774128Y269302D01*
X774438Y269110D01*
X774645Y268880D01*
X774800Y268573D01*
Y267807D01*
G01Y271750D02*
X771700D01*
X772320Y271290D01*
G01X774800D02*
Y272210D01*
G01X771700Y274850D02*
X771803Y274543D01*
X772062Y274313D01*
X772372Y274160D01*
X772785Y274045D01*
X773250Y274007D01*
X773715Y274045D01*
X774128Y274160D01*
X774438Y274313D01*
X774697Y274543D01*
X774800Y274850D01*
X774697Y275157D01*
X774438Y275387D01*
X774128Y275540D01*
X773715Y275655D01*
X773250Y275693D01*
X772785Y275655D01*
X772372Y275540D01*
X772062Y275387D01*
X771803Y275157D01*
X771700Y274850D01*
G01Y277950D02*
X771803Y277643D01*
X772062Y277413D01*
X772372Y277260D01*
X772785Y277145D01*
X773250Y277107D01*
X773715Y277145D01*
X774128Y277260D01*
X774438Y277413D01*
X774697Y277643D01*
X774800Y277950D01*
X774697Y278257D01*
X774438Y278487D01*
X774128Y278640D01*
X773715Y278755D01*
X773250Y278793D01*
X772785Y278755D01*
X772372Y278640D01*
X772062Y278487D01*
X771803Y278257D01*
X771700Y277950D01*
G01X770400Y264635D02*
Y295727D01*
G01X779443Y308252D02*
X785643D01*
G01X779443Y305052D02*
Y308252D01*
G01X785643Y305052D02*
X779443D01*
G01X770949Y310215D02*
X767749D01*
G01X770949Y316415D02*
Y310215D01*
G01X767749D02*
Y316415D01*
G01X774013Y309749D02*
Y324749D01*
G01X787013Y309749D02*
X774013D01*
G01X772537Y328584D02*
X771037Y326084D01*
G01X774037D02*
X772537Y328584D01*
G01X780637Y326084D02*
X774037D01*
G01X780637Y339084D02*
Y326084D01*
G01X767749Y316415D02*
X770949D01*
G01X767749Y323415D02*
X770949D01*
G01X767749Y317215D02*
Y323415D01*
G01X770949Y317215D02*
X767749D01*
G01X770949Y323415D02*
Y317215D01*
G01X774013Y324749D02*
X787013D01*
G01X771333Y349110D02*
Y340646D01*
G01X782100Y331907D02*
X784322D01*
X784787Y332060D01*
X785097Y332367D01*
X785200Y332750D01*
X785097Y333133D01*
X784787Y333440D01*
X784322Y333593D01*
X782100D01*
G01X782617Y335122D02*
X782307Y335352D01*
X782152Y335620D01*
X782100Y335927D01*
X782203Y336310D01*
X782462Y336578D01*
X782772Y336655D01*
X783082Y336617D01*
X783340Y336463D01*
X783857Y335697D01*
X784218Y335352D01*
X784735Y335122D01*
X785200Y335045D01*
Y336655D01*
G01X783908Y338222D02*
X783547Y338490D01*
X783340Y338720D01*
X783237Y339027D01*
X783340Y339295D01*
X783547Y339487D01*
X783857Y339640D01*
X784218Y339678D01*
X784528Y339640D01*
X784838Y339487D01*
X785097Y339257D01*
X785200Y338988D01*
X785097Y338682D01*
X784787Y338413D01*
X784322Y338260D01*
X783805Y338222D01*
X783133Y338298D01*
X782772Y338413D01*
X782410Y338605D01*
X782152Y338873D01*
X782100Y339142D01*
X782203Y339410D01*
X782462Y339602D01*
G01X772902Y340794D02*
Y346994D01*
G01X776102Y340794D02*
X772902D01*
G01X776102Y346994D02*
Y340794D01*
G01X776902D02*
Y346994D01*
G01X780102Y340794D02*
X776902D01*
G01X780102Y346994D02*
Y340794D01*
G01X772894Y349250D02*
Y352450D01*
G01X779094Y349250D02*
X772894D01*
G01X779094Y352450D02*
Y349250D01*
G01X772894Y352450D02*
X779094D01*
G01X772902Y346994D02*
X776102D01*
G01X776902D02*
X780102D01*
G01X777434Y417437D02*
Y429437D01*
G01X783434Y417437D02*
X777434D01*
G01X776434Y429437D02*
Y417437D01*
G01X770434D02*
Y429437D01*
G01X776434Y417437D02*
X770434D01*
G01X777434Y429437D02*
X783434D01*
G01X770434D02*
X776434D01*
G01X779992Y440898D02*
Y444098D01*
G01X786192Y440898D02*
X779992D01*
G01Y444098D02*
X786192D01*
G01X780024Y452110D02*
X786224D01*
G01X780024Y448910D02*
Y452110D01*
G01X786224Y448910D02*
X780024D01*
G01Y448110D02*
X786224D01*
G01X780024Y444910D02*
Y448110D01*
G01X786224Y444910D02*
X780024D01*
G01X771071Y540312D02*
Y543512D01*
G01X777271Y540312D02*
X771071D01*
G01X777271Y543512D02*
Y540312D01*
G01X771071Y543512D02*
X777271D01*
G01X778771Y554812D02*
X781971D01*
G01X778771Y548612D02*
Y554812D01*
G01X781971Y548612D02*
X778771D01*
G01X781971Y554812D02*
Y548612D01*
G01X777271Y547512D02*
Y544312D01*
G01X771071Y547512D02*
X777271D01*
G01X771071Y544312D02*
Y547512D01*
G01X777271Y544312D02*
X771071D01*
G01Y621312D02*
Y624512D01*
G01X777271Y621312D02*
X771071D01*
G01X777271Y624512D02*
Y621312D01*
G01X771071Y624512D02*
X777271D01*
G01Y628512D02*
Y625312D01*
G01X771071Y628512D02*
X777271D01*
G01X771071Y625312D02*
Y628512D01*
G01X777271Y625312D02*
X771071D01*
G01X791013Y868294D02*
X781013D01*
G01D02*
Y880244D01*
G01Y886344D02*
Y898294D01*
G01X780796Y900481D02*
X780988Y900171D01*
X781218Y899964D01*
X781486Y899861D01*
X781793Y899964D01*
X782023Y900171D01*
X782253Y900481D01*
X782330Y900894D01*
Y902961D01*
G01X783820Y900326D02*
X784050Y900068D01*
X784318Y899913D01*
X784663Y899861D01*
X785008Y899964D01*
X785276Y900171D01*
X785468Y900533D01*
X785506Y900946D01*
X785430Y901359D01*
X785238Y901618D01*
X784970Y901824D01*
X784701Y901876D01*
X784433Y901824D01*
X784088Y901618D01*
X784203Y902961D01*
X785238D01*
G01X787111Y900223D02*
X787380Y899964D01*
X787686Y899861D01*
X787993Y899964D01*
X788261Y900274D01*
X788453Y900739D01*
X788530Y901204D01*
Y901773D01*
X788453Y902238D01*
X788261Y902651D01*
X788031Y902858D01*
X787763Y902961D01*
X787456Y902858D01*
X787226Y902651D01*
X787073Y902341D01*
X786996Y901928D01*
X787073Y901566D01*
X787265Y901204D01*
X787495Y900998D01*
X787763Y900946D01*
X788070Y901049D01*
X788300Y901308D01*
X788530Y901773D01*
G01X781013Y898294D02*
X791013D01*
G01X792227Y918808D02*
X782227D01*
G01D02*
Y930758D01*
G01Y936858D02*
Y948808D01*
G01X782010Y950995D02*
X782202Y950685D01*
X782432Y950478D01*
X782700Y950375D01*
X783007Y950478D01*
X783237Y950685D01*
X783467Y950995D01*
X783544Y951408D01*
Y953475D01*
G01X785149Y951667D02*
X785417Y952028D01*
X785647Y952235D01*
X785954Y952338D01*
X786222Y952235D01*
X786414Y952028D01*
X786567Y951718D01*
X786605Y951357D01*
X786567Y951047D01*
X786414Y950737D01*
X786184Y950478D01*
X785915Y950375D01*
X785609Y950478D01*
X785340Y950788D01*
X785187Y951253D01*
X785149Y951770D01*
X785225Y952442D01*
X785340Y952803D01*
X785532Y953165D01*
X785800Y953423D01*
X786069Y953475D01*
X786337Y953372D01*
X786529Y953113D01*
G01X788977Y953475D02*
X788670Y953372D01*
X788440Y953113D01*
X788287Y952803D01*
X788172Y952390D01*
X788134Y951925D01*
X788172Y951460D01*
X788287Y951047D01*
X788440Y950737D01*
X788670Y950478D01*
X788977Y950375D01*
X789284Y950478D01*
X789514Y950737D01*
X789667Y951047D01*
X789782Y951460D01*
X789820Y951925D01*
X789782Y952390D01*
X789667Y952803D01*
X789514Y953113D01*
X789284Y953372D01*
X788977Y953475D01*
G01X782227Y948808D02*
X792227D01*
G01X778724Y1069917D02*
G03X841534Y1066535I31314J-3382D01*
G01X835834Y1281456D02*
G03X778691Y1266446I-25796J-18071D01*
G01X782231Y1289907D02*
Y1293007D01*
G01X783841D02*
Y1289907D01*
G01Y1291457D02*
X782231D01*
G01X786136Y1289907D02*
X786404Y1289959D01*
X786711Y1290114D01*
X786903Y1290372D01*
X786979Y1290734D01*
X786903Y1291095D01*
X786673Y1291405D01*
X786328Y1291560D01*
X785944D01*
X785714Y1291664D01*
X785523Y1291922D01*
X785446Y1292284D01*
X785561Y1292645D01*
X785829Y1292904D01*
X786136Y1293007D01*
X786443Y1292904D01*
X786711Y1292645D01*
X786826Y1292284D01*
X786749Y1291922D01*
X786558Y1291664D01*
X786328Y1291560D01*
X785944D01*
X785599Y1291405D01*
X785369Y1291095D01*
X785293Y1290734D01*
X785369Y1290372D01*
X785561Y1290114D01*
X785868Y1289959D01*
X786136Y1289907D01*
G01X789696D02*
Y1293007D01*
X788278Y1290785D01*
X790194D01*
G01X773908Y1408025D02*
X774138Y1407663D01*
X774444Y1407457D01*
X774789Y1407405D01*
X775096Y1407457D01*
X775403Y1407715D01*
X775594Y1408025D01*
X775633Y1408335D01*
X775556Y1408697D01*
X775288Y1408955D01*
X775019Y1409058D01*
X774674D01*
G01X775019D02*
X775249Y1409213D01*
X775441Y1409472D01*
X775518Y1409782D01*
X775441Y1410092D01*
X775249Y1410350D01*
X774904Y1410505D01*
X774559Y1410453D01*
X774214Y1410247D01*
G01X778649Y1429032D02*
X784849D01*
G01X778649Y1425832D02*
Y1429032D01*
G01X784849Y1425832D02*
X778649D01*
G01X784849Y1429832D02*
X778649D01*
Y1433032D01*
X784849D01*
Y1429832D01*
G01X778649Y1441032D02*
X784849D01*
G01X778649Y1437832D02*
Y1441032D01*
G01X784849Y1437832D02*
X778649D01*
G01X781615Y1448050D02*
Y1454250D01*
G01X784815Y1448050D02*
X781615D01*
G01X776232Y1451470D02*
Y1448270D01*
G01X770032D02*
Y1451470D01*
G01X776232Y1448270D02*
X770032D01*
G01X778661Y1441845D02*
Y1445045D01*
G01X784861Y1441845D02*
X778661D01*
G01Y1445045D02*
X784861D01*
G01X769112Y1451302D02*
Y1445102D01*
G01X778649Y1437032D02*
X784849D01*
Y1433832D01*
X778649D01*
Y1437032D01*
G01X781615Y1454250D02*
X784815D01*
G01X776903Y1459666D02*
X783103D01*
G01X776903Y1456466D02*
Y1459666D01*
G01X783103Y1456466D02*
X776903D01*
G01X770110Y1452705D02*
Y1455905D01*
G01X776310Y1452705D02*
X770110D01*
G01X776310Y1455905D02*
Y1452705D01*
G01X770110Y1455905D02*
X776310D01*
G01X770032Y1451470D02*
X776232D01*
G01X767611Y1585218D02*
Y1582996D01*
X767764Y1582531D01*
X768071Y1582221D01*
X768454Y1582118D01*
X768837Y1582221D01*
X769144Y1582531D01*
X769297Y1582996D01*
Y1585218D01*
G01X770711Y1582738D02*
X770941Y1582376D01*
X771247Y1582170D01*
X771592Y1582118D01*
X771899Y1582170D01*
X772206Y1582428D01*
X772397Y1582738D01*
X772436Y1583048D01*
X772359Y1583410D01*
X772091Y1583668D01*
X771822Y1583771D01*
X771477D01*
G01X771822D02*
X772052Y1583926D01*
X772244Y1584185D01*
X772321Y1584495D01*
X772244Y1584805D01*
X772052Y1585063D01*
X771707Y1585218D01*
X771362Y1585166D01*
X771017Y1584960D01*
G01X775114Y1582118D02*
Y1585218D01*
X773696Y1582996D01*
X775612D01*
G01X777754Y1585218D02*
X777447Y1585115D01*
X777217Y1584856D01*
X777064Y1584546D01*
X776949Y1584133D01*
X776911Y1583668D01*
X776949Y1583203D01*
X777064Y1582790D01*
X777217Y1582480D01*
X777447Y1582221D01*
X777754Y1582118D01*
X778061Y1582221D01*
X778291Y1582480D01*
X778444Y1582790D01*
X778559Y1583203D01*
X778597Y1583668D01*
X778559Y1584133D01*
X778444Y1584546D01*
X778291Y1584856D01*
X778061Y1585115D01*
X777754Y1585218D01*
G01X775433Y1594097D02*
X778633D01*
G01X775433Y1587897D02*
Y1594097D01*
G01X778633Y1587897D02*
X775433D01*
G01X778633Y1594097D02*
Y1587897D01*
G01X779510Y1594097D02*
X782710D01*
G01Y1587897D02*
X779510D01*
G01X782710Y1594097D02*
Y1587897D01*
G01X779510D02*
Y1594097D01*
G01X782831Y1607440D02*
X774169D01*
G01Y1596560D02*
X782831D01*
G01X774169Y1604331D02*
X776500Y1602000D01*
G01X774169Y1607440D02*
Y1604331D01*
G01Y1599669D02*
Y1596560D01*
G01X776500Y1602000D02*
X774169Y1599669D01*
G01X773244Y1617870D02*
Y1624070D01*
X776444D01*
Y1617870D01*
X773244D01*
G01X769052Y1618442D02*
Y1612242D01*
G01X792013Y1626567D02*
X780045D01*
Y1611855D01*
X792013D01*
Y1626567D01*
G01X775422Y1634825D02*
Y1628625D01*
X772222D01*
Y1634825D01*
X775422D01*
G01X776758Y1628601D02*
Y1634801D01*
X779958D01*
Y1628601D01*
X776758D01*
G01X770188Y1639527D02*
Y1637305D01*
X770341Y1636840D01*
X770648Y1636530D01*
X771031Y1636427D01*
X771414Y1636530D01*
X771721Y1636840D01*
X771874Y1637305D01*
Y1639527D01*
G01X774591Y1636427D02*
Y1639527D01*
X773173Y1637305D01*
X775089D01*
G01X777691Y1636427D02*
Y1639527D01*
X776273Y1637305D01*
X778189D01*
G01X779488Y1637047D02*
X779718Y1636685D01*
X780024Y1636479D01*
X780369Y1636427D01*
X780676Y1636479D01*
X780983Y1636737D01*
X781174Y1637047D01*
X781213Y1637357D01*
X781136Y1637719D01*
X780868Y1637977D01*
X780599Y1638080D01*
X780254D01*
G01X780599D02*
X780829Y1638235D01*
X781021Y1638494D01*
X781098Y1638804D01*
X781021Y1639114D01*
X780829Y1639372D01*
X780484Y1639527D01*
X780139Y1639475D01*
X779794Y1639269D01*
G01X798156Y58593D02*
X798466Y58785D01*
X798673Y59015D01*
X798776Y59283D01*
X798673Y59590D01*
X798466Y59820D01*
X798156Y60050D01*
X797743Y60127D01*
X795676D01*
G01X798156Y61617D02*
X798518Y61847D01*
X798724Y62153D01*
X798776Y62498D01*
X798724Y62805D01*
X798466Y63112D01*
X798156Y63303D01*
X797846Y63342D01*
X797484Y63265D01*
X797226Y62997D01*
X797123Y62728D01*
Y62383D01*
G01Y62728D02*
X796968Y62958D01*
X796709Y63150D01*
X796399Y63227D01*
X796089Y63150D01*
X795831Y62958D01*
X795676Y62613D01*
X795728Y62268D01*
X795934Y61923D01*
G01X798776Y65483D02*
X798104Y65560D01*
X797536Y65675D01*
X797019Y65828D01*
X796451Y66020D01*
X795676Y66327D01*
Y64793D01*
G01X791671Y96067D02*
Y99267D01*
G01X797871Y96067D02*
X791671D01*
G01X797871Y99267D02*
Y96067D01*
G01X791671Y99267D02*
X797871D01*
G01X788410Y122172D02*
Y110172D01*
G01X782993Y109424D02*
Y103224D01*
G01X793687Y108095D02*
Y104895D01*
G01X787487Y108095D02*
X793687D01*
G01X787487Y104895D02*
Y108095D01*
G01X793687Y104895D02*
X787487D01*
G01Y100895D02*
Y104095D01*
G01X793687Y100895D02*
X787487D01*
G01X793687Y104095D02*
Y100895D01*
G01X787487Y104095D02*
X793687D01*
G01X794544Y108086D02*
X797744D01*
G01X794544Y101886D02*
Y108086D01*
G01X797744Y101886D02*
X794544D01*
G01X797744Y108086D02*
Y101886D01*
G01X785072Y132428D02*
Y126228D01*
G01X785251Y147537D02*
Y141337D01*
G01X788116Y136438D02*
Y133238D01*
G01Y140438D02*
Y137238D01*
G01X788462Y148437D02*
X791662D01*
G01X788462Y142237D02*
Y148437D01*
G01X791662Y142237D02*
X788462D01*
G01X791662Y148437D02*
Y142237D01*
G01X790900Y153707D02*
X793122D01*
X793587Y153860D01*
X793897Y154167D01*
X794000Y154550D01*
X793897Y154933D01*
X793587Y155240D01*
X793122Y155393D01*
X790900D01*
G01X793380Y156807D02*
X793742Y157037D01*
X793948Y157343D01*
X794000Y157688D01*
X793948Y157995D01*
X793690Y158302D01*
X793380Y158493D01*
X793070Y158532D01*
X792708Y158455D01*
X792450Y158187D01*
X792347Y157918D01*
Y157573D01*
G01Y157918D02*
X792192Y158148D01*
X791933Y158340D01*
X791623Y158417D01*
X791313Y158340D01*
X791055Y158148D01*
X790900Y157803D01*
X790952Y157458D01*
X791158Y157113D01*
G01X794000Y160673D02*
X793328Y160750D01*
X792760Y160865D01*
X792243Y161018D01*
X791675Y161210D01*
X790900Y161517D01*
Y159983D01*
G01Y163850D02*
X791003Y163543D01*
X791262Y163313D01*
X791572Y163160D01*
X791985Y163045D01*
X792450Y163007D01*
X792915Y163045D01*
X793328Y163160D01*
X793638Y163313D01*
X793897Y163543D01*
X794000Y163850D01*
X793897Y164157D01*
X793638Y164387D01*
X793328Y164540D01*
X792915Y164655D01*
X792450Y164693D01*
X791985Y164655D01*
X791572Y164540D01*
X791262Y164387D01*
X791003Y164157D01*
X790900Y163850D01*
G01X789598Y165304D02*
Y149950D01*
G01X792418Y203645D02*
Y197645D01*
G01X783595Y214506D02*
Y208306D01*
G01X790371Y208464D02*
Y205264D01*
G01X784171Y208464D02*
X790371D01*
G01X784171Y205264D02*
Y208464D01*
G01X790371Y205264D02*
X784171D01*
G01X785201Y226801D02*
X797405D01*
Y211497D01*
X785201D01*
Y226801D01*
G01X791597Y254969D02*
Y245521D01*
G01X789864Y231446D02*
X786664D01*
G01X789864Y237646D02*
Y231446D01*
G01X786664Y237646D02*
X789864D01*
G01X786664Y231446D02*
Y237646D01*
G01X801974Y231459D02*
X798774D01*
G01Y237659D02*
X801974D01*
G01X798774Y231459D02*
Y237659D01*
G01X784337Y237534D02*
Y231334D01*
G01X793739Y231434D02*
X790539D01*
G01X793739Y237634D02*
Y231434D01*
G01X790539Y237634D02*
X793739D01*
G01X790539Y231434D02*
Y237634D01*
G01X794774Y237659D02*
X797974D01*
G01X794774Y231459D02*
Y237659D01*
G01X797974Y231459D02*
X794774D01*
G01X797974Y237659D02*
Y231459D01*
G01X793400Y240081D02*
Y243281D01*
G01X799600Y240081D02*
X793400D01*
G01Y243281D02*
X799600D01*
G01X789542Y243678D02*
Y240478D01*
G01X783342Y243678D02*
X789542D01*
G01X783342Y240478D02*
Y243678D01*
G01X789542Y240478D02*
X783342D01*
G01X788179Y254969D02*
X791597D01*
G01X786179Y253245D02*
X788179Y254969D01*
G01X784179D02*
X786179Y253245D01*
G01X793004Y252199D02*
X799204D01*
G01X793004Y248999D02*
Y252199D01*
G01X799204Y248999D02*
X793004D01*
G01X785643Y308252D02*
Y305052D01*
G01X787013Y324749D02*
Y309749D01*
G01X788300Y313057D02*
X790522D01*
X790987Y313210D01*
X791297Y313517D01*
X791400Y313900D01*
X791297Y314283D01*
X790987Y314590D01*
X790522Y314743D01*
X788300D01*
G01X788817Y316272D02*
X788507Y316502D01*
X788352Y316770D01*
X788300Y317077D01*
X788403Y317460D01*
X788662Y317728D01*
X788972Y317805D01*
X789282Y317767D01*
X789540Y317613D01*
X790057Y316847D01*
X790418Y316502D01*
X790935Y316272D01*
X791400Y316195D01*
Y317805D01*
G01Y320023D02*
X790728Y320100D01*
X790160Y320215D01*
X789643Y320368D01*
X789075Y320560D01*
X788300Y320867D01*
Y319333D01*
G01X851575Y388583D02*
G02I-31496J0D01*
G01X783434Y429437D02*
Y417437D01*
G01X795945Y416400D02*
Y419500D01*
G01X797555D02*
Y416400D01*
G01Y417950D02*
X795945D01*
G01X799773Y416400D02*
X799850Y417072D01*
X799965Y417640D01*
X800118Y418157D01*
X800310Y418725D01*
X800617Y419500D01*
X799083D01*
G01X802298Y416762D02*
X802567Y416503D01*
X802873Y416400D01*
X803180Y416503D01*
X803448Y416813D01*
X803640Y417278D01*
X803717Y417743D01*
Y418312D01*
X803640Y418777D01*
X803448Y419190D01*
X803218Y419397D01*
X802950Y419500D01*
X802643Y419397D01*
X802413Y419190D01*
X802260Y418880D01*
X802183Y418467D01*
X802260Y418105D01*
X802452Y417743D01*
X802682Y417537D01*
X802950Y417485D01*
X803257Y417588D01*
X803487Y417847D01*
X803717Y418312D01*
G01X787024Y440910D02*
Y444110D01*
G01X793224Y440910D02*
X787024D01*
G01X793224Y444110D02*
Y440910D01*
G01X786192Y444098D02*
Y440898D01*
G01X787024Y444110D02*
X793224D01*
G01X787024Y448910D02*
Y452110D01*
G01X793224Y448910D02*
X787024D01*
G01X793224Y452110D02*
Y448910D01*
G01X787024Y452110D02*
X793224D01*
G01X787024Y444910D02*
Y448110D01*
G01X793224Y444910D02*
X787024D01*
G01X793224Y448110D02*
Y444910D01*
G01X787024Y448110D02*
X793224D01*
G01X786224Y452110D02*
Y448910D01*
G01Y448110D02*
Y444910D01*
G01X797233Y455600D02*
Y458700D01*
X798153D01*
X798460Y458545D01*
X798690Y458183D01*
X798767Y457770D01*
X798690Y457357D01*
X798498Y457047D01*
X798153Y456892D01*
X797233D01*
G01X800257Y458700D02*
Y456478D01*
X800410Y456013D01*
X800717Y455703D01*
X801100Y455600D01*
X801483Y455703D01*
X801790Y456013D01*
X801943Y456478D01*
Y458700D01*
G01X804200Y455600D02*
Y458700D01*
X803740Y458080D01*
G01Y455600D02*
X804660D01*
G01X807300Y458700D02*
X806993Y458597D01*
X806763Y458338D01*
X806610Y458028D01*
X806495Y457615D01*
X806457Y457150D01*
X806495Y456685D01*
X806610Y456272D01*
X806763Y455962D01*
X806993Y455703D01*
X807300Y455600D01*
X807607Y455703D01*
X807837Y455962D01*
X807990Y456272D01*
X808105Y456685D01*
X808143Y457150D01*
X808105Y457615D01*
X807990Y458028D01*
X807837Y458338D01*
X807607Y458597D01*
X807300Y458700D01*
G01X809672Y458183D02*
X809902Y458493D01*
X810170Y458648D01*
X810477Y458700D01*
X810860Y458597D01*
X811128Y458338D01*
X811205Y458028D01*
X811167Y457718D01*
X811013Y457460D01*
X810247Y456943D01*
X809902Y456582D01*
X809672Y456065D01*
X809595Y455600D01*
X811205D01*
G01X798200Y462983D02*
X795100D01*
Y463903D01*
X795255Y464210D01*
X795617Y464440D01*
X796030Y464517D01*
X796443Y464440D01*
X796753Y464248D01*
X796908Y463903D01*
Y462983D01*
G01X798200Y466007D02*
X795100D01*
Y466773D01*
X795255Y467080D01*
X795462Y467310D01*
X795772Y467502D01*
X796133Y467655D01*
X796650Y467693D01*
X797167Y467655D01*
X797528Y467502D01*
X797838Y467310D01*
X798045Y467080D01*
X798200Y466773D01*
Y466007D01*
G01X797735Y469107D02*
X797993Y469337D01*
X798148Y469605D01*
X798200Y469950D01*
X798097Y470295D01*
X797890Y470563D01*
X797528Y470755D01*
X797115Y470793D01*
X796702Y470717D01*
X796443Y470525D01*
X796237Y470257D01*
X796185Y469988D01*
X796237Y469720D01*
X796443Y469375D01*
X795100Y469490D01*
Y470525D01*
G01X798200Y473050D02*
X798148Y473318D01*
X797993Y473625D01*
X797735Y473817D01*
X797373Y473893D01*
X797012Y473817D01*
X796702Y473587D01*
X796547Y473242D01*
Y472858D01*
X796443Y472628D01*
X796185Y472437D01*
X795823Y472360D01*
X795462Y472475D01*
X795203Y472743D01*
X795100Y473050D01*
X795203Y473357D01*
X795462Y473625D01*
X795823Y473740D01*
X796185Y473663D01*
X796443Y473472D01*
X796547Y473242D01*
Y472858D01*
X796702Y472513D01*
X797012Y472283D01*
X797373Y472207D01*
X797735Y472283D01*
X797993Y472475D01*
X798148Y472782D01*
X798200Y473050D01*
G01X797771Y553612D02*
Y559812D01*
G01X800971Y553612D02*
X797771D01*
G01X786857Y546500D02*
Y544278D01*
X787010Y543813D01*
X787317Y543503D01*
X787700Y543400D01*
X788083Y543503D01*
X788390Y543813D01*
X788543Y544278D01*
Y546500D01*
G01X790072Y545983D02*
X790302Y546293D01*
X790570Y546448D01*
X790877Y546500D01*
X791260Y546397D01*
X791528Y546138D01*
X791605Y545828D01*
X791567Y545518D01*
X791413Y545260D01*
X790647Y544743D01*
X790302Y544382D01*
X790072Y543865D01*
X789995Y543400D01*
X791605D01*
G01X794360D02*
Y546500D01*
X792942Y544278D01*
X794858D01*
G01X796110Y563389D02*
Y548035D01*
G01X783432D02*
Y563389D01*
G01X795913Y548035D02*
X783432D01*
G01X800971Y560612D02*
X797771D01*
G01Y566812D02*
X800971D01*
G01X797771Y560612D02*
Y566812D01*
G01Y559812D02*
X800971D01*
G01X783432Y563389D02*
X796110D01*
G01X791013Y890244D02*
Y876344D01*
G01Y870244D02*
Y868294D01*
G01Y898294D02*
Y896344D01*
G01X792227Y920758D02*
Y918808D01*
G01Y940758D02*
Y926858D01*
G01Y948808D02*
Y946858D01*
G01X785433Y1071456D02*
Y1258464D01*
G01X841534Y1066535D02*
G03X788425Y1089446I-31496J0D01*
G01X800435Y1135604D02*
X797235D01*
G01D02*
Y1141804D01*
G01X795442D02*
Y1135604D01*
X792242D01*
Y1141804D01*
X795442D01*
G01X789366Y1156532D02*
X791588D01*
X792053Y1156685D01*
X792363Y1156992D01*
X792466Y1157375D01*
X792363Y1157758D01*
X792053Y1158065D01*
X791588Y1158218D01*
X789366D01*
G01X792466Y1160935D02*
X789366D01*
X791588Y1159517D01*
Y1161433D01*
G01X789883Y1162847D02*
X789573Y1163077D01*
X789418Y1163345D01*
X789366Y1163652D01*
X789469Y1164035D01*
X789728Y1164303D01*
X790038Y1164380D01*
X790348Y1164342D01*
X790606Y1164188D01*
X791123Y1163422D01*
X791484Y1163077D01*
X792001Y1162847D01*
X792466Y1162770D01*
Y1164380D01*
G01X791174Y1165947D02*
X790813Y1166215D01*
X790606Y1166445D01*
X790503Y1166752D01*
X790606Y1167020D01*
X790813Y1167212D01*
X791123Y1167365D01*
X791484Y1167403D01*
X791794Y1167365D01*
X792104Y1167212D01*
X792363Y1166982D01*
X792466Y1166713D01*
X792363Y1166407D01*
X792053Y1166138D01*
X791588Y1165985D01*
X791071Y1165947D01*
X790399Y1166023D01*
X790038Y1166138D01*
X789676Y1166330D01*
X789418Y1166598D01*
X789366Y1166867D01*
X789469Y1167135D01*
X789728Y1167327D01*
G01X797235Y1141804D02*
X800435D01*
G01X793432Y1161425D02*
X794625Y1160525D01*
X793432Y1159525D01*
G01Y1161525D02*
Y1164625D01*
X805834D01*
Y1156425D01*
X793432D01*
Y1159525D01*
G01X796316Y1180425D02*
Y1174225D01*
X793116D01*
Y1180425D01*
X796316D01*
G01X796942Y1180445D02*
Y1186645D01*
X800142D01*
Y1180445D01*
X796942D01*
G01X793559Y1187091D02*
Y1193291D01*
X796759D01*
Y1187091D01*
X793559D01*
G01X797018Y1201818D02*
X793818D01*
G01X797018Y1208018D02*
Y1201818D01*
G01X793818D02*
Y1208018D01*
G01X800830Y1208131D02*
Y1201931D01*
X797630D01*
Y1208131D01*
X800830D01*
G01X799924Y1199709D02*
Y1193509D01*
X796724D01*
Y1199709D01*
X799924D01*
G01X793818Y1208018D02*
X797018D01*
G01X787682Y1241200D02*
G03X841534Y1263386I22356J22185D01*
G01X791055Y1388336D02*
Y1386114D01*
X791208Y1385649D01*
X791515Y1385339D01*
X791898Y1385236D01*
X792281Y1385339D01*
X792588Y1385649D01*
X792741Y1386114D01*
Y1388336D01*
G01X795458Y1385236D02*
Y1388336D01*
X794040Y1386114D01*
X795956D01*
G01X798098Y1385236D02*
Y1388336D01*
X797638Y1387716D01*
G01Y1385236D02*
X798558D01*
G01X800355Y1385701D02*
X800585Y1385443D01*
X800853Y1385288D01*
X801198Y1385236D01*
X801543Y1385339D01*
X801811Y1385546D01*
X802003Y1385908D01*
X802041Y1386321D01*
X801965Y1386734D01*
X801773Y1386993D01*
X801505Y1387199D01*
X801236Y1387251D01*
X800968Y1387199D01*
X800623Y1386993D01*
X800738Y1388336D01*
X801773D01*
G01X798572Y1393078D02*
X795372D01*
G01D02*
Y1399278D01*
G01D02*
X798572D01*
G01D02*
Y1393078D01*
G01X784849Y1429032D02*
Y1425832D01*
G01X794744Y1438159D02*
X800944D01*
G01X794744Y1434959D02*
Y1438159D01*
G01X800944Y1434959D02*
X794744D01*
G01X784849Y1441032D02*
Y1437832D01*
G01X784815Y1454250D02*
Y1448050D01*
G01X784861Y1445045D02*
Y1441845D01*
G01X794491Y1462696D02*
Y1442478D01*
G01D02*
X822583D01*
G01X783103Y1459666D02*
Y1456466D01*
G01X822583Y1462696D02*
X794491D01*
G01X798301Y1468001D02*
Y1474201D01*
G01X801501Y1468001D02*
X798301D01*
G01Y1474201D02*
X801501D01*
G01X801968Y1490945D02*
G02X791083Y1467130I-31495J0D01*
G01X791011Y1514822D02*
G02X801968Y1490945I-20538J-23877D01*
G01X796693Y1576803D02*
Y1695110D01*
G01X1074331Y1576803D02*
X796693D01*
G01X790010Y1594913D02*
Y1601113D01*
G01X793210Y1594913D02*
X790010D01*
G01X793210Y1601113D02*
Y1594913D01*
G01X785847Y1594936D02*
Y1601136D01*
G01X789047Y1594936D02*
X785847D01*
G01X789047Y1601136D02*
Y1594936D01*
G01X784988Y1603844D02*
X784681Y1603896D01*
X784413Y1604102D01*
X784183Y1604412D01*
X784030Y1604774D01*
X783953Y1605187D01*
Y1605601D01*
X784030Y1606014D01*
X784183Y1606376D01*
X784413Y1606686D01*
X784681Y1606892D01*
X784988Y1606944D01*
X785295Y1606892D01*
X785563Y1606686D01*
X785793Y1606376D01*
X785946Y1606014D01*
X786023Y1605601D01*
Y1605187D01*
X785946Y1604774D01*
X785793Y1604412D01*
X785563Y1604102D01*
X785295Y1603896D01*
X784988Y1603844D01*
G01X785295Y1604671D02*
X785755Y1603844D01*
G01X788088D02*
Y1606944D01*
X787628Y1606324D01*
G01Y1603844D02*
X788548D01*
G01X790460Y1606427D02*
X790690Y1606737D01*
X790958Y1606892D01*
X791265Y1606944D01*
X791648Y1606841D01*
X791916Y1606582D01*
X791993Y1606272D01*
X791955Y1605962D01*
X791801Y1605704D01*
X791035Y1605187D01*
X790690Y1604826D01*
X790460Y1604309D01*
X790383Y1603844D01*
X791993D01*
G01X793445Y1604464D02*
X793675Y1604102D01*
X793981Y1603896D01*
X794326Y1603844D01*
X794633Y1603896D01*
X794940Y1604154D01*
X795131Y1604464D01*
X795170Y1604774D01*
X795093Y1605136D01*
X794825Y1605394D01*
X794556Y1605497D01*
X794211D01*
G01X794556D02*
X794786Y1605652D01*
X794978Y1605911D01*
X795055Y1606221D01*
X794978Y1606531D01*
X794786Y1606789D01*
X794441Y1606944D01*
X794096Y1606892D01*
X793751Y1606686D01*
G01X782831Y1596560D02*
Y1607440D01*
G01X790010Y1601113D02*
X793210D01*
G01X785847Y1601136D02*
X789047D01*
G01X792901Y1617700D02*
X795123D01*
X795588Y1617853D01*
X795898Y1618160D01*
X796001Y1618543D01*
X795898Y1618926D01*
X795588Y1619233D01*
X795123Y1619386D01*
X792901D01*
G01X796001Y1622103D02*
X792901D01*
X795123Y1620685D01*
Y1622601D01*
G01X796001Y1625203D02*
X792901D01*
X795123Y1623785D01*
Y1625701D01*
G01X796001Y1628303D02*
X792901D01*
X795123Y1626885D01*
Y1628801D01*
G01X796693Y1695110D02*
X1074331D01*
G01X802814Y57756D02*
Y111635D01*
G01X803110Y58150D02*
Y111635D01*
G01X809195Y57756D02*
X802814D01*
G01X808790Y58150D02*
X803110D01*
G01Y118848D02*
Y114048D01*
G01X802814Y118848D02*
Y114048D01*
G01X803110Y132607D02*
Y128340D01*
G01X802814Y132607D02*
Y128340D01*
G01Y125781D02*
Y121219D01*
G01X803110Y125781D02*
Y121219D01*
G01Y152756D02*
Y135410D01*
G01X802814Y153150D02*
Y135410D01*
G01Y153150D02*
X809195D01*
G01X803110Y152756D02*
X808790D01*
G01X806541Y189535D02*
X804115D01*
G01X803001Y195583D02*
Y184087D01*
G01X817000Y203583D02*
X813900D01*
Y204503D01*
X814055Y204810D01*
X814417Y205040D01*
X814830Y205117D01*
X815243Y205040D01*
X815553Y204848D01*
X815708Y204503D01*
Y203583D01*
G01X817000Y206607D02*
X813900D01*
Y207373D01*
X814055Y207680D01*
X814262Y207910D01*
X814572Y208102D01*
X814933Y208255D01*
X815450Y208293D01*
X815967Y208255D01*
X816328Y208102D01*
X816638Y207910D01*
X816845Y207680D01*
X817000Y207373D01*
Y206607D01*
G01Y210550D02*
X813900D01*
X814520Y210090D01*
G01X817000D02*
Y211010D01*
G01X813900Y213650D02*
X814003Y213343D01*
X814262Y213113D01*
X814572Y212960D01*
X814985Y212845D01*
X815450Y212807D01*
X815915Y212845D01*
X816328Y212960D01*
X816638Y213113D01*
X816897Y213343D01*
X817000Y213650D01*
X816897Y213957D01*
X816638Y214187D01*
X816328Y214340D01*
X815915Y214455D01*
X815450Y214493D01*
X814985Y214455D01*
X814572Y214340D01*
X814262Y214187D01*
X814003Y213957D01*
X813900Y213650D01*
G01X817000Y216673D02*
X816328Y216750D01*
X815760Y216865D01*
X815243Y217018D01*
X814675Y217210D01*
X813900Y217517D01*
Y215983D01*
G01X803836Y213243D02*
X800736D01*
Y214163D01*
X800891Y214470D01*
X801253Y214700D01*
X801666Y214777D01*
X802079Y214700D01*
X802389Y214508D01*
X802544Y214163D01*
Y213243D01*
G01X800736Y216267D02*
X802958D01*
X803423Y216420D01*
X803733Y216727D01*
X803836Y217110D01*
X803733Y217493D01*
X803423Y217800D01*
X802958Y217953D01*
X800736D01*
G01X802544Y219482D02*
X802183Y219750D01*
X801976Y219980D01*
X801873Y220287D01*
X801976Y220555D01*
X802183Y220747D01*
X802493Y220900D01*
X802854Y220938D01*
X803164Y220900D01*
X803474Y220747D01*
X803733Y220517D01*
X803836Y220248D01*
X803733Y219942D01*
X803423Y219673D01*
X802958Y219520D01*
X802441Y219482D01*
X801769Y219558D01*
X801408Y219673D01*
X801046Y219865D01*
X800788Y220133D01*
X800736Y220402D01*
X800839Y220670D01*
X801098Y220862D01*
G01X803836Y223310D02*
X800736D01*
X801356Y222850D01*
G01X803836D02*
Y223770D01*
G01X801974Y237659D02*
Y231459D01*
G01X799600Y243281D02*
Y240081D01*
G01X816800Y263183D02*
X813700D01*
Y264103D01*
X813855Y264410D01*
X814217Y264640D01*
X814630Y264717D01*
X815043Y264640D01*
X815353Y264448D01*
X815508Y264103D01*
Y263183D01*
G01X816800Y266207D02*
X813700D01*
Y266973D01*
X813855Y267280D01*
X814062Y267510D01*
X814372Y267702D01*
X814733Y267855D01*
X815250Y267893D01*
X815767Y267855D01*
X816128Y267702D01*
X816438Y267510D01*
X816645Y267280D01*
X816800Y266973D01*
Y266207D01*
G01X816180Y269307D02*
X816542Y269537D01*
X816748Y269843D01*
X816800Y270188D01*
X816748Y270495D01*
X816490Y270802D01*
X816180Y270993D01*
X815870Y271032D01*
X815508Y270955D01*
X815250Y270687D01*
X815147Y270418D01*
Y270073D01*
G01Y270418D02*
X814992Y270648D01*
X814733Y270840D01*
X814423Y270917D01*
X814113Y270840D01*
X813855Y270648D01*
X813700Y270303D01*
X813752Y269958D01*
X813958Y269613D01*
G01X816335Y272407D02*
X816593Y272637D01*
X816748Y272905D01*
X816800Y273250D01*
X816697Y273595D01*
X816490Y273863D01*
X816128Y274055D01*
X815715Y274093D01*
X815302Y274017D01*
X815043Y273825D01*
X814837Y273557D01*
X814785Y273288D01*
X814837Y273020D01*
X815043Y272675D01*
X813700Y272790D01*
Y273825D01*
G01X799204Y252199D02*
Y248999D01*
G01X810377Y303768D02*
Y306968D01*
G01X816577Y303768D02*
X810377D01*
G01Y306968D02*
X816577D01*
G01X810377Y307768D02*
Y310968D01*
G01X816577Y307768D02*
X810377D01*
G01Y310968D02*
X816577D01*
G01X802377Y303768D02*
Y306968D01*
G01X808577Y303768D02*
X802377D01*
G01X808577Y306968D02*
Y303768D01*
G01X802377Y306968D02*
X808577D01*
G01X802377Y307768D02*
Y310968D01*
G01X808577Y307768D02*
X802377D01*
G01X808577Y310968D02*
Y307768D01*
G01X802377Y310968D02*
X808577D01*
G01X810377Y311768D02*
Y314968D01*
G01X816577Y311768D02*
X810377D01*
G01Y314968D02*
X816577D01*
G01X802377Y311768D02*
Y314968D01*
G01X808577Y311768D02*
X802377D01*
G01X808577Y314968D02*
Y311768D01*
G01X802377Y314968D02*
X808577D01*
G01X810377Y315768D02*
Y318968D01*
G01X816577Y315768D02*
X810377D01*
G01Y318968D02*
X816577D01*
G01X810377Y319768D02*
Y322968D01*
G01X816577Y319768D02*
X810377D01*
G01Y322968D02*
X816577D01*
G01X810377Y323768D02*
Y326968D01*
G01X816577Y323768D02*
X810377D01*
G01Y326968D02*
X816577D01*
G01X810377Y327768D02*
Y330968D01*
G01X816577Y327768D02*
X810377D01*
G01X802377Y315768D02*
Y318968D01*
G01X808577Y315768D02*
X802377D01*
G01X808577Y318968D02*
Y315768D01*
G01X802377Y318968D02*
X808577D01*
G01X802377Y319768D02*
Y322968D01*
G01X808577Y319768D02*
X802377D01*
G01X808577Y322968D02*
Y319768D01*
G01X802377Y322968D02*
X808577D01*
G01X802377Y323768D02*
Y326968D01*
G01X808577Y323768D02*
X802377D01*
G01X808577Y326968D02*
Y323768D01*
G01X802377Y326968D02*
X808577D01*
G01X802377Y327768D02*
Y330968D01*
G01X808577Y327768D02*
X802377D01*
G01X808577Y330968D02*
Y327768D01*
G01X810377Y330968D02*
X816577D01*
G01X802377D02*
X808577D01*
G01X810377Y331768D02*
Y334968D01*
G01X816577Y331768D02*
X810377D01*
G01Y334968D02*
X816577D01*
G01X802377Y335768D02*
Y338968D01*
G01X808577Y335768D02*
X802377D01*
G01X808577Y338968D02*
Y335768D01*
G01X802377Y338968D02*
X808577D01*
G01X802377Y331768D02*
Y334968D01*
G01X808577Y331768D02*
X802377D01*
G01X808577Y334968D02*
Y331768D01*
G01X802377Y334968D02*
X808577D01*
G01X810377Y344768D02*
Y347968D01*
G01X816577Y344768D02*
X810377D01*
G01Y347968D02*
X816577D01*
G01X802377Y344768D02*
Y347968D01*
G01X808577Y344768D02*
X802377D01*
G01X808577Y347968D02*
Y344768D01*
G01X802377Y347968D02*
X808577D01*
G01X810377Y348768D02*
Y351968D01*
G01X816577Y348768D02*
X810377D01*
G01Y351968D02*
X816577D01*
G01X810374Y353141D02*
Y356341D01*
G01X816574Y353141D02*
X810374D01*
G01Y356341D02*
X816574D01*
G01X813262Y457326D02*
Y463326D01*
G01X825262Y457326D02*
X813262D01*
G01X805115Y459270D02*
Y461696D01*
G01X809211Y445934D02*
Y442734D01*
G01X803011Y445934D02*
X809211D01*
G01X803011Y442734D02*
Y445934D01*
G01X809211Y442734D02*
X803011D01*
G01X809211Y453934D02*
Y450734D01*
G01X803011Y453934D02*
X809211D01*
G01X803011Y450734D02*
Y453934D01*
G01X809211Y450734D02*
X803011D01*
G01Y446734D02*
Y449934D01*
G01X809211Y446734D02*
X803011D01*
G01X809211Y449934D02*
Y446734D01*
G01X803011Y449934D02*
X809211D01*
G01X823700Y445163D02*
X811926D01*
G01Y454925D02*
X823700D01*
G01X811926Y445163D02*
Y454925D01*
G01X813262Y463326D02*
X825262D01*
G01X811163Y462810D02*
X799667D01*
G01X811163Y492369D02*
Y462810D01*
G01X799667D02*
Y492369D01*
G01X813019Y473517D02*
Y485517D01*
G01X819019Y473517D02*
X813019D01*
G01Y485517D02*
X819019D01*
G01X805015Y496010D02*
Y493770D01*
G01X806640Y494983D02*
X803390D01*
G01X799667Y492369D02*
X811163D01*
G01X823026Y543007D02*
X807426D01*
X823026Y551977D01*
X807426D01*
G01Y563052D02*
Y567732D01*
G01Y565392D02*
X823026D01*
G01Y563052D02*
Y567732D01*
G01X808726Y587582D02*
X807946Y586412D01*
X807426Y585047D01*
Y583487D01*
X808206Y581732D01*
X809506Y580367D01*
X811066Y579392D01*
X813666Y578612D01*
X816006Y578417D01*
X818346Y578807D01*
X819906Y579392D01*
X821466Y580562D01*
X822506Y581927D01*
X823026Y583292D01*
Y584657D01*
X822506Y586022D01*
X821726Y587192D01*
X820686Y588167D01*
G01X819906Y596902D02*
X821726Y598072D01*
X822766Y599632D01*
X823026Y601387D01*
X822766Y602947D01*
X821466Y604507D01*
X819906Y605482D01*
X818346Y605677D01*
X816526Y605287D01*
X815226Y603922D01*
X814706Y602557D01*
Y600802D01*
G01Y602557D02*
X813926Y603727D01*
X812626Y604702D01*
X811066Y605092D01*
X809506Y604702D01*
X808206Y603727D01*
X807426Y601972D01*
X807686Y600217D01*
X808726Y598462D01*
G01X800971Y559812D02*
Y553612D01*
G01Y566812D02*
Y560612D01*
G01X815421Y733771D02*
X812221D01*
G01D02*
Y739971D01*
G01D02*
X815421D01*
G01X813424Y838519D02*
Y835319D01*
G01X807224Y838519D02*
X813424D01*
G01X807224Y835319D02*
Y838519D01*
G01X813424Y835319D02*
X807224D01*
G01Y839319D02*
Y842519D01*
G01X813424Y839319D02*
X807224D01*
G01X813424Y842519D02*
Y839319D01*
G01X807224Y842519D02*
X813424D01*
G01X808100Y849707D02*
X810322D01*
X810787Y849860D01*
X811097Y850167D01*
X811200Y850550D01*
X811097Y850933D01*
X810787Y851240D01*
X810322Y851393D01*
X808100D01*
G01X811200Y853650D02*
X811148Y853918D01*
X810993Y854225D01*
X810735Y854417D01*
X810373Y854493D01*
X810012Y854417D01*
X809702Y854187D01*
X809547Y853842D01*
Y853458D01*
X809443Y853228D01*
X809185Y853037D01*
X808823Y852960D01*
X808462Y853075D01*
X808203Y853343D01*
X808100Y853650D01*
X808203Y853957D01*
X808462Y854225D01*
X808823Y854340D01*
X809185Y854263D01*
X809443Y854072D01*
X809547Y853842D01*
Y853458D01*
X809702Y853113D01*
X810012Y852883D01*
X810373Y852807D01*
X810735Y852883D01*
X810993Y853075D01*
X811148Y853382D01*
X811200Y853650D01*
G01Y856750D02*
X811148Y857018D01*
X810993Y857325D01*
X810735Y857517D01*
X810373Y857593D01*
X810012Y857517D01*
X809702Y857287D01*
X809547Y856942D01*
Y856558D01*
X809443Y856328D01*
X809185Y856137D01*
X808823Y856060D01*
X808462Y856175D01*
X808203Y856443D01*
X808100Y856750D01*
X808203Y857057D01*
X808462Y857325D01*
X808823Y857440D01*
X809185Y857363D01*
X809443Y857172D01*
X809547Y856942D01*
Y856558D01*
X809702Y856213D01*
X810012Y855983D01*
X810373Y855907D01*
X810735Y855983D01*
X810993Y856175D01*
X811148Y856482D01*
X811200Y856750D01*
G01X821156Y857284D02*
X812888D01*
G01Y850484D02*
X821156D01*
G01X812888Y857284D02*
Y850484D01*
G01X806839Y874439D02*
X809061D01*
X809526Y874592D01*
X809836Y874899D01*
X809939Y875282D01*
X809836Y875665D01*
X809526Y875972D01*
X809061Y876125D01*
X806839D01*
G01X809319Y877539D02*
X809681Y877769D01*
X809887Y878075D01*
X809939Y878420D01*
X809887Y878727D01*
X809629Y879034D01*
X809319Y879225D01*
X809009Y879264D01*
X808647Y879187D01*
X808389Y878919D01*
X808286Y878650D01*
Y878305D01*
G01Y878650D02*
X808131Y878880D01*
X807872Y879072D01*
X807562Y879149D01*
X807252Y879072D01*
X806994Y878880D01*
X806839Y878535D01*
X806891Y878190D01*
X807097Y877845D01*
G01X809474Y880639D02*
X809732Y880869D01*
X809887Y881137D01*
X809939Y881482D01*
X809836Y881827D01*
X809629Y882095D01*
X809267Y882287D01*
X808854Y882325D01*
X808441Y882249D01*
X808182Y882057D01*
X807976Y881789D01*
X807924Y881520D01*
X807976Y881252D01*
X808182Y880907D01*
X806839Y881022D01*
Y882057D01*
G01X808647Y883854D02*
X808286Y884122D01*
X808079Y884352D01*
X807976Y884659D01*
X808079Y884927D01*
X808286Y885119D01*
X808596Y885272D01*
X808957Y885310D01*
X809267Y885272D01*
X809577Y885119D01*
X809836Y884889D01*
X809939Y884620D01*
X809836Y884314D01*
X809526Y884045D01*
X809061Y883892D01*
X808544Y883854D01*
X807872Y883930D01*
X807511Y884045D01*
X807149Y884237D01*
X806891Y884505D01*
X806839Y884774D01*
X806942Y885042D01*
X807201Y885234D01*
G01X813127Y874564D02*
Y887826D01*
G01X821591Y874564D02*
X813127D01*
G01X802226Y872451D02*
X802588Y872681D01*
X802794Y872987D01*
X802846Y873332D01*
X802794Y873639D01*
X802536Y873946D01*
X802226Y874137D01*
X801916Y874176D01*
X801554Y874099D01*
X801296Y873831D01*
X801193Y873562D01*
Y873217D01*
G01Y873562D02*
X801038Y873792D01*
X800779Y873984D01*
X800469Y874061D01*
X800159Y873984D01*
X799901Y873792D01*
X799746Y873447D01*
X799798Y873102D01*
X800004Y872757D01*
G01X817627Y866155D02*
X814427D01*
G01Y872355D02*
X817627D01*
G01X814427Y866155D02*
Y872355D01*
G01X813127Y887826D02*
X821591D01*
G01X810724Y895019D02*
X816924D01*
G01X810724Y891819D02*
Y895019D01*
G01X816924Y891819D02*
X810724D01*
G01X815224Y902519D02*
X821424D01*
G01X815224Y899319D02*
Y902519D01*
G01X821424Y899319D02*
X815224D01*
G01X803440Y922965D02*
X803802Y923195D01*
X804008Y923501D01*
X804060Y923846D01*
X804008Y924153D01*
X803750Y924460D01*
X803440Y924651D01*
X803130Y924690D01*
X802768Y924613D01*
X802510Y924345D01*
X802407Y924076D01*
Y923731D01*
G01Y924076D02*
X802252Y924306D01*
X801993Y924498D01*
X801683Y924575D01*
X801373Y924498D01*
X801115Y924306D01*
X800960Y923961D01*
X801012Y923616D01*
X801218Y923271D01*
G01X801223Y1099734D02*
Y1102834D01*
G01X802833D02*
Y1099734D01*
G01Y1101284D02*
X801223D01*
G01X804476Y1100096D02*
X804745Y1099837D01*
X805051Y1099734D01*
X805358Y1099837D01*
X805626Y1100147D01*
X805818Y1100612D01*
X805895Y1101077D01*
Y1101646D01*
X805818Y1102111D01*
X805626Y1102524D01*
X805396Y1102731D01*
X805128Y1102834D01*
X804821Y1102731D01*
X804591Y1102524D01*
X804438Y1102214D01*
X804361Y1101801D01*
X804438Y1101439D01*
X804630Y1101077D01*
X804860Y1100871D01*
X805128Y1100819D01*
X805435Y1100922D01*
X805665Y1101181D01*
X805895Y1101646D01*
G01X808228Y1099734D02*
X808496Y1099786D01*
X808803Y1099941D01*
X808995Y1100199D01*
X809071Y1100561D01*
X808995Y1100922D01*
X808765Y1101232D01*
X808420Y1101387D01*
X808036D01*
X807806Y1101491D01*
X807615Y1101749D01*
X807538Y1102111D01*
X807653Y1102472D01*
X807921Y1102731D01*
X808228Y1102834D01*
X808535Y1102731D01*
X808803Y1102472D01*
X808918Y1102111D01*
X808841Y1101749D01*
X808650Y1101491D01*
X808420Y1101387D01*
X808036D01*
X807691Y1101232D01*
X807461Y1100922D01*
X807385Y1100561D01*
X807461Y1100199D01*
X807653Y1099941D01*
X807960Y1099786D01*
X808228Y1099734D01*
G01X800435Y1141804D02*
Y1135604D01*
G01X808435D02*
X805235D01*
G01X808435Y1141804D02*
Y1135604D01*
G01X805235D02*
Y1141804D01*
G01X816435Y1135604D02*
X813235D01*
G01D02*
Y1141804D01*
G01X812435Y1135604D02*
X809235D01*
G01X812435Y1141804D02*
Y1135604D01*
G01X809235D02*
Y1141804D01*
G01X801235Y1135604D02*
Y1141804D01*
G01X804435Y1135604D02*
X801235D01*
G01X804435Y1141804D02*
Y1135604D01*
G01X807833Y1149643D02*
Y1161167D01*
G01X820037Y1149643D02*
X807833D01*
G01X805235Y1141804D02*
X808435D01*
G01X813235D02*
X816435D01*
G01X809235D02*
X812435D01*
G01X801235D02*
X804435D01*
G01X805612Y1144471D02*
X799412D01*
Y1147671D01*
X805612D01*
Y1144471D01*
G01X807833Y1161167D02*
X820037D01*
G01X813342Y1169520D02*
Y1172720D01*
G01X819542Y1169520D02*
X813342D01*
G01X806343D02*
Y1172720D01*
G01X812543Y1169520D02*
X806343D01*
G01X812543Y1172720D02*
Y1169520D01*
G01X815248Y1186726D02*
X818448D01*
G01X815248Y1180526D02*
Y1186726D01*
G01X818448Y1180526D02*
X815248D01*
G01X809929Y1186730D02*
X813129D01*
G01X809929Y1180530D02*
Y1186730D01*
G01X813129Y1180530D02*
X809929D01*
G01X813129Y1186730D02*
Y1180530D01*
G01X809901Y1179765D02*
X813101D01*
G01X809901Y1173565D02*
Y1179765D01*
G01X813101Y1173565D02*
X809901D01*
G01X813101Y1179765D02*
Y1173565D01*
G01X815226Y1179813D02*
X818426D01*
G01X815226Y1173613D02*
Y1179813D01*
G01X818426Y1173613D02*
X815226D01*
G01X813342Y1172720D02*
X819542D01*
G01X806343D02*
X812543D01*
G01X805901Y1179765D02*
X809101D01*
G01X805901Y1173565D02*
Y1179765D01*
G01X809101Y1173565D02*
X805901D01*
G01X809101Y1179765D02*
Y1173565D01*
G01X805929Y1186730D02*
X809129D01*
G01X805929Y1180530D02*
Y1186730D01*
G01X809129Y1180530D02*
X805929D01*
G01X809129Y1186730D02*
Y1180530D01*
G01X800958Y1180375D02*
Y1186575D01*
X804158D01*
Y1180375D01*
X800958D01*
G01X817087Y1193894D02*
X813887D01*
G01Y1200094D02*
X817087D01*
G01X813887Y1193894D02*
Y1200094D01*
G01X813087Y1193894D02*
X809887D01*
G01X813087Y1200094D02*
Y1193894D01*
G01X809887Y1200094D02*
X813087D01*
G01X809887Y1193894D02*
Y1200094D01*
G01X809087Y1193894D02*
X805887D01*
G01X809087Y1200094D02*
Y1193894D01*
G01X805887Y1200094D02*
X809087D01*
G01X805887Y1193894D02*
Y1200094D01*
G01X817089Y1201918D02*
X813889D01*
G01D02*
Y1208118D01*
G01X813089Y1201918D02*
X809889D01*
G01X813089Y1208118D02*
Y1201918D01*
G01X809889D02*
Y1208118D01*
G01X809089Y1201918D02*
X805889D01*
G01X809089Y1208118D02*
Y1201918D01*
G01X805889D02*
Y1208118D01*
G01X805204Y1201875D02*
X802004D01*
G01X805204Y1208075D02*
Y1201875D01*
G01X802004D02*
Y1208075D01*
G01X800733Y1193411D02*
Y1199611D01*
X803933D01*
Y1193411D01*
X800733D01*
G01X813889Y1208118D02*
X817089D01*
G01X809889D02*
X813089D01*
G01X805889D02*
X809089D01*
G01X812689Y1212811D02*
X810427Y1210549D01*
G01X808305Y1217195D02*
X812689Y1212811D01*
G01X806043Y1214933D02*
X808305Y1217195D01*
G01X810427Y1210549D02*
X806043Y1214933D01*
G01X811700Y1220590D02*
X813962Y1222852D01*
G01X816084Y1216206D02*
X811700Y1220590D01*
G01X815517Y1215639D02*
X813255Y1213377D01*
G01X811133Y1220023D02*
X815517Y1215639D01*
G01X808871Y1217761D02*
X811133Y1220023D01*
G01X813255Y1213377D02*
X808871Y1217761D01*
G01X808819Y1221417D02*
X806557Y1219155D01*
G01X804435Y1225801D02*
X808819Y1221417D01*
G01X806557Y1219155D02*
X802173Y1223539D01*
G01X805990Y1218590D02*
X803728Y1216328D01*
G01X801606Y1222974D02*
X805990Y1218590D01*
G01X799344Y1220712D02*
X801606Y1222974D01*
G01X803728Y1216328D02*
X799344Y1220712D01*
G01X802004Y1208075D02*
X805204D01*
G01X813962Y1222852D02*
X818346Y1218468D01*
G01X814529Y1223419D02*
X816791Y1225681D01*
G01X818913Y1219035D02*
X814529Y1223419D01*
G01X811648Y1224246D02*
X809386Y1221984D01*
G01X807264Y1228630D02*
X811648Y1224246D01*
G01X805002Y1226368D02*
X807264Y1228630D01*
G01X809386Y1221984D02*
X805002Y1226368D01*
G01X802173Y1223539D02*
X804435Y1225801D01*
G01X814477Y1227075D02*
X812215Y1224813D01*
G01X810093Y1231459D02*
X814477Y1227075D01*
G01X807831Y1229197D02*
X810093Y1231459D01*
G01X812215Y1224813D02*
X807831Y1229197D01*
G01X812548Y1382283D02*
X815748D01*
G01X812548Y1376083D02*
Y1382283D01*
G01X815748Y1376083D02*
X812548D01*
G01X807748D02*
X804548D01*
G01X807748Y1382283D02*
Y1376083D01*
G01X804548Y1382283D02*
X807748D01*
G01X804548Y1376083D02*
Y1382283D01*
G01X811748Y1376083D02*
X808548D01*
G01X811748Y1382283D02*
Y1376083D01*
G01X808548Y1382283D02*
X811748D01*
G01X808548Y1376083D02*
Y1382283D01*
G01X803558Y1384588D02*
Y1400788D01*
G01X814058Y1392688D02*
X816558Y1391188D01*
G01Y1394188D02*
X814058Y1392688D01*
G01X816558Y1384588D02*
X803558D01*
G01Y1400788D02*
X816558D01*
G01X805529Y1403169D02*
Y1406369D01*
G01X811729Y1403169D02*
X805529D01*
G01Y1406369D02*
X811729D01*
G01D02*
Y1403169D01*
G01X800944Y1438159D02*
Y1434959D01*
G01X807944D02*
X801744D01*
Y1438159D01*
X807944D01*
Y1434959D01*
G01X806363Y1464094D02*
Y1467194D01*
X807283D01*
X807590Y1467039D01*
X807820Y1466677D01*
X807897Y1466264D01*
X807820Y1465851D01*
X807628Y1465541D01*
X807283Y1465386D01*
X806363D01*
G01X809387Y1467194D02*
Y1464972D01*
X809540Y1464507D01*
X809847Y1464197D01*
X810230Y1464094D01*
X810613Y1464197D01*
X810920Y1464507D01*
X811073Y1464972D01*
Y1467194D01*
G01X813330Y1464094D02*
Y1467194D01*
X812870Y1466574D01*
G01Y1464094D02*
X813790D01*
G01X806609Y1467985D02*
X803409D01*
G01Y1474185D02*
X806609D01*
G01X803409Y1467985D02*
Y1474185D01*
G01X806609D02*
Y1467985D01*
G01X801501Y1474201D02*
Y1468001D01*
G01X809605Y1475016D02*
X803405D01*
Y1478216D01*
X809605D01*
Y1475016D01*
G01X803394Y1482754D02*
Y1485954D01*
G01X809594Y1482754D02*
X803394D01*
G01X809594Y1485954D02*
Y1482754D01*
G01X803394Y1485954D02*
X809594D01*
G01X815867Y1566409D02*
X816367Y1565609D01*
X816967Y1565076D01*
X817667Y1564809D01*
X818467Y1565076D01*
X819067Y1565609D01*
X819667Y1566409D01*
X819867Y1567476D01*
Y1572809D01*
G01X825867Y1564809D02*
Y1572809D01*
X824667Y1571209D01*
G01Y1564809D02*
X827067D01*
G01X808504Y1590307D02*
Y1683299D01*
G01X839762Y1590307D02*
X808504D01*
G01X1062520Y1642787D02*
X808504D01*
G01Y1683299D02*
X1062520D01*
G01X827863Y-60739D02*
Y-57639D01*
X828629D01*
X828936Y-57794D01*
X829166Y-58001D01*
X829358Y-58311D01*
X829511Y-58672D01*
X829549Y-59189D01*
X829511Y-59706D01*
X829358Y-60067D01*
X829166Y-60377D01*
X828936Y-60584D01*
X828629Y-60739D01*
X827863D01*
G01X832573D02*
X831039D01*
Y-57639D01*
X832573D01*
G01X831959Y-59137D02*
X831039D01*
G01X834906Y-57639D02*
X834599Y-57742D01*
X834369Y-58001D01*
X834216Y-58311D01*
X834101Y-58724D01*
X834063Y-59189D01*
X834101Y-59654D01*
X834216Y-60067D01*
X834369Y-60377D01*
X834599Y-60636D01*
X834906Y-60739D01*
X835213Y-60636D01*
X835443Y-60377D01*
X835596Y-60067D01*
X835711Y-59654D01*
X835749Y-59189D01*
X835711Y-58724D01*
X835596Y-58311D01*
X835443Y-58001D01*
X835213Y-57742D01*
X834906Y-57639D01*
G01X838006Y-60739D02*
Y-57639D01*
X837546Y-58259D01*
G01Y-60739D02*
X838466D01*
G01X840378D02*
Y-57639D01*
X841834D01*
G01X841298Y-59137D02*
X840378D01*
G01X843056Y-61772D02*
X845356D01*
G01X846578Y-58156D02*
X846808Y-57846D01*
X847076Y-57691D01*
X847383Y-57639D01*
X847766Y-57742D01*
X848034Y-58001D01*
X848111Y-58311D01*
X848073Y-58621D01*
X847919Y-58879D01*
X847153Y-59396D01*
X846808Y-59757D01*
X846578Y-60274D01*
X846501Y-60739D01*
X848111D01*
G01X827618Y57756D02*
Y104511D01*
G01X827322Y58150D02*
Y104511D01*
G01X827618Y57756D02*
X821237D01*
G01X827322Y58150D02*
X821642D01*
G01X827618Y111507D02*
Y107060D01*
G01X827322Y111507D02*
Y107060D01*
G01Y118680D02*
Y114087D01*
G01X827618Y118680D02*
Y114087D01*
G01X827322Y132859D02*
Y128325D01*
G01X827618Y132859D02*
Y128325D01*
G01Y125844D02*
Y121329D01*
G01X827322Y125844D02*
Y121329D01*
G01Y152756D02*
Y135560D01*
G01X827618Y153150D02*
Y135560D01*
G01X816268Y156615D02*
X817015Y155990D01*
X817855Y155615D01*
X818601D01*
X819348Y155990D01*
X819908Y156615D01*
X820188Y157490D01*
X820001Y158365D01*
X819535Y159115D01*
X818695Y159615D01*
X817575Y159865D01*
X816921Y160365D01*
X816641Y161240D01*
X816828Y162115D01*
X817295Y162740D01*
X817948Y163115D01*
X818601D01*
X819255Y162865D01*
X819815Y162240D01*
G01X823768Y156615D02*
X824515Y155990D01*
X825355Y155615D01*
X826101D01*
X826848Y155990D01*
X827408Y156615D01*
X827688Y157490D01*
X827501Y158365D01*
X827035Y159115D01*
X826195Y159615D01*
X825075Y159865D01*
X824421Y160365D01*
X824141Y161240D01*
X824328Y162115D01*
X824795Y162740D01*
X825448Y163115D01*
X826101D01*
X826755Y162865D01*
X827315Y162240D01*
G01X831175Y155615D02*
Y163115D01*
X833041D01*
X833788Y162740D01*
X834348Y162240D01*
X834815Y161490D01*
X835188Y160615D01*
X835281Y159365D01*
X835188Y158115D01*
X834815Y157240D01*
X834348Y156490D01*
X833788Y155990D01*
X833041Y155615D01*
X831175D01*
G01X840541D02*
X840728Y157240D01*
X841008Y158615D01*
X841381Y159865D01*
X841848Y161240D01*
X842595Y163115D01*
X838861D01*
G01X819718Y164436D02*
X834518D01*
G01X819718Y195440D02*
Y164436D01*
G01X821237Y153150D02*
X827618D01*
G01X821642Y152756D02*
X827322D01*
G01X834518Y195440D02*
X819718D01*
G01X823721Y199912D02*
Y202338D01*
G01X829769Y203452D02*
X818273D01*
G01X829769Y233011D02*
Y203452D01*
G01X818273D02*
Y233011D01*
G01X823621Y236652D02*
Y234412D01*
G01X825246Y235625D02*
X821996D01*
G01X818273Y233011D02*
X829769D01*
G01X831114Y250325D02*
Y234813D01*
G01D02*
X862206D01*
G01X823490Y259204D02*
Y261630D01*
G01X829538Y262744D02*
X818042D01*
G01X829538Y292303D02*
Y262744D01*
G01X818042D02*
Y292303D01*
G01X831293Y251936D02*
Y255036D01*
X832213D01*
X832520Y254881D01*
X832750Y254519D01*
X832827Y254106D01*
X832750Y253693D01*
X832558Y253383D01*
X832213Y253228D01*
X831293D01*
G01X834317Y251936D02*
Y255036D01*
X835083D01*
X835390Y254881D01*
X835620Y254674D01*
X835812Y254364D01*
X835965Y254003D01*
X836003Y253486D01*
X835965Y252969D01*
X835812Y252608D01*
X835620Y252298D01*
X835390Y252091D01*
X835083Y251936D01*
X834317D01*
G01X837532Y254519D02*
X837762Y254829D01*
X838030Y254984D01*
X838337Y255036D01*
X838720Y254933D01*
X838988Y254674D01*
X839065Y254364D01*
X839027Y254054D01*
X838873Y253796D01*
X838107Y253279D01*
X837762Y252918D01*
X837532Y252401D01*
X837455Y251936D01*
X839065D01*
G01X841360Y255036D02*
X841053Y254933D01*
X840823Y254674D01*
X840670Y254364D01*
X840555Y253951D01*
X840517Y253486D01*
X840555Y253021D01*
X840670Y252608D01*
X840823Y252298D01*
X841053Y252039D01*
X841360Y251936D01*
X841667Y252039D01*
X841897Y252298D01*
X842050Y252608D01*
X842165Y253021D01*
X842203Y253486D01*
X842165Y253951D01*
X842050Y254364D01*
X841897Y254674D01*
X841667Y254933D01*
X841360Y255036D01*
G01X862206Y250325D02*
X831114D01*
G01X831409Y271655D02*
Y283655D01*
G01X837409Y271655D02*
X831409D01*
G01Y283655D02*
X837409D01*
G01X823658Y297627D02*
Y295387D01*
G01X825283Y296600D02*
X822033D01*
G01X818042Y292303D02*
X829538D01*
G01X816577Y306968D02*
Y303768D01*
G01Y310968D02*
Y307768D01*
G01Y314968D02*
Y311768D01*
G01Y318968D02*
Y315768D01*
G01Y322968D02*
Y319768D01*
G01Y326968D02*
Y323768D01*
G01Y330968D02*
Y327768D01*
G01Y334968D02*
Y331768D01*
G01Y347968D02*
Y344768D01*
G01Y351968D02*
Y348768D01*
G01X816574Y356341D02*
Y353141D01*
G01X817283Y439789D02*
Y442989D01*
G01X823483Y439789D02*
X817283D01*
G01X823483Y442989D02*
Y439789D01*
G01X825262Y463326D02*
Y457326D01*
G01X826010Y454709D02*
Y457909D01*
G01X832210Y454709D02*
X826010D01*
G01Y457909D02*
X832210D01*
G01X817283Y442989D02*
X823483D01*
G01X826010Y446709D02*
Y449909D01*
G01X832210Y446709D02*
X826010D01*
G01Y449909D02*
X832210D01*
G01X826010Y450709D02*
Y453909D01*
G01X832210Y450709D02*
X826010D01*
G01Y453909D02*
X832210D01*
G01X823700Y454925D02*
Y445163D01*
G01X819019Y485517D02*
Y473517D01*
G01X829225Y460789D02*
Y463889D01*
X830145D01*
X830452Y463734D01*
X830682Y463372D01*
X830759Y462959D01*
X830682Y462546D01*
X830490Y462236D01*
X830145Y462081D01*
X829225D01*
G01X832249Y463889D02*
Y461667D01*
X832402Y461202D01*
X832709Y460892D01*
X833092Y460789D01*
X833475Y460892D01*
X833782Y461202D01*
X833935Y461667D01*
Y463889D01*
G01X835349Y461254D02*
X835579Y460996D01*
X835847Y460841D01*
X836192Y460789D01*
X836537Y460892D01*
X836805Y461099D01*
X836997Y461461D01*
X837035Y461874D01*
X836959Y462287D01*
X836767Y462546D01*
X836499Y462752D01*
X836230Y462804D01*
X835962Y462752D01*
X835617Y462546D01*
X835732Y463889D01*
X836767D01*
G01X838564Y463372D02*
X838794Y463682D01*
X839062Y463837D01*
X839369Y463889D01*
X839752Y463786D01*
X840020Y463527D01*
X840097Y463217D01*
X840059Y462907D01*
X839905Y462649D01*
X839139Y462132D01*
X838794Y461771D01*
X838564Y461254D01*
X838487Y460789D01*
X840097D01*
G01X839822Y478629D02*
Y466425D01*
X824518D01*
Y478629D01*
X839822D01*
G01X820086Y486216D02*
Y492216D01*
G01X832086Y486216D02*
X820086D01*
G01X830086Y485416D02*
Y482216D01*
G01X823886Y485416D02*
X830086D01*
G01X823886Y482216D02*
Y485416D01*
G01X830086Y482216D02*
X823886D01*
G01X823012Y475358D02*
X819812D01*
G01X823012Y481558D02*
Y475358D01*
G01X819812Y481558D02*
X823012D01*
G01X819812Y475358D02*
Y481558D01*
G01X820086Y492216D02*
X832086D01*
G01X832528Y551561D02*
X831748Y550391D01*
X831228Y549026D01*
Y547466D01*
X832008Y545711D01*
X833308Y544346D01*
X834868Y543371D01*
X837468Y542591D01*
X839808Y542396D01*
X842148Y542786D01*
X843708Y543371D01*
X845268Y544541D01*
X846308Y545906D01*
X846828Y547271D01*
Y548636D01*
X846308Y550001D01*
X845528Y551171D01*
X844488Y552146D01*
G01X838508Y566731D02*
X837728Y567511D01*
X836428Y568096D01*
X834608Y568486D01*
X833048Y568096D01*
X832008Y567316D01*
X831228Y565951D01*
Y560686D01*
X846828D01*
Y567121D01*
X845788Y568486D01*
X844228Y569266D01*
X842408Y569656D01*
X840588Y569266D01*
X839028Y568096D01*
X838508Y566731D01*
Y560686D01*
G01X831228Y579171D02*
X846828D01*
Y586971D01*
G01X852028Y595121D02*
Y606821D01*
G01X838508Y620431D02*
X837728Y621211D01*
X836428Y621796D01*
X834608Y622186D01*
X833048Y621796D01*
X832008Y621016D01*
X831228Y619651D01*
Y614386D01*
X846828D01*
Y620821D01*
X845788Y622186D01*
X844228Y622966D01*
X842408Y623356D01*
X840588Y622966D01*
X839028Y621796D01*
X838508Y620431D01*
Y614386D01*
G01X846828Y636771D02*
X846568Y635211D01*
X845528Y633846D01*
X843968Y632676D01*
X842148Y631896D01*
X840068Y631506D01*
X837988D01*
X835908Y631896D01*
X834088Y632676D01*
X832528Y633846D01*
X831488Y635211D01*
X831228Y636771D01*
X831488Y638331D01*
X832528Y639696D01*
X834088Y640866D01*
X835908Y641646D01*
X837988Y642036D01*
X840068D01*
X842148Y641646D01*
X843968Y640866D01*
X845528Y639696D01*
X846568Y638331D01*
X846828Y636771D01*
G01X831228Y654671D02*
X846828D01*
G01X831228Y650186D02*
Y659156D01*
G01X830684Y711914D02*
Y718114D01*
G01X833884Y711914D02*
X830684D01*
G01X825684Y711164D02*
X828884D01*
G01X825684Y704964D02*
Y711164D01*
G01X828884Y704964D02*
X825684D01*
G01X828884Y711164D02*
Y704964D01*
G01X825684Y711914D02*
Y718114D01*
G01X828884Y711914D02*
X825684D01*
G01X828884Y718114D02*
Y711914D01*
G01X827884Y724314D02*
Y737914D01*
G01X836684Y724314D02*
X827884D01*
G01X830684Y718114D02*
X833884D01*
G01X825684D02*
X828884D01*
G01X815421Y739971D02*
Y733771D01*
G01X827884Y737914D02*
X836684D01*
G01X832084Y739626D02*
X828884D01*
G01Y745826D02*
X832084D01*
G01X828884Y739626D02*
Y745826D01*
G01X828084Y739626D02*
X824884D01*
G01X828084Y745826D02*
Y739626D01*
G01X824884Y745826D02*
X828084D01*
G01X824884Y739626D02*
Y745826D01*
G01X815463Y740902D02*
Y744102D01*
G01X821663Y740902D02*
X815463D01*
G01X821663Y744102D02*
Y740902D01*
G01X815463Y744102D02*
X821663D01*
G01X825400Y764900D02*
Y768100D01*
G01X831600Y764900D02*
X825400D01*
G01Y760100D02*
X831600D01*
G01X825400Y756900D02*
Y760100D01*
G01X831600Y756900D02*
X825400D01*
G01Y764100D02*
X831600D01*
G01X825400Y760900D02*
Y764100D01*
G01X831600Y760900D02*
X825400D01*
G01Y768100D02*
X831600D01*
G01X825400Y782100D02*
X831600D01*
G01X825400Y778900D02*
Y782100D01*
G01X831600Y778900D02*
X825400D01*
G01Y778100D02*
X831600D01*
G01X825400Y774900D02*
Y778100D01*
G01X831600Y774900D02*
X825400D01*
G01Y782900D02*
Y786100D01*
G01X831600Y782900D02*
X825400D01*
G01Y786100D02*
X831600D01*
G01X825400Y796100D02*
X831600D01*
G01X825400Y792900D02*
Y796100D01*
G01X831600Y792900D02*
X825400D01*
G01Y796900D02*
Y800100D01*
G01X831600Y796900D02*
X825400D01*
G01Y800900D02*
Y804100D01*
G01X831600Y800900D02*
X825400D01*
G01Y804100D02*
X831600D01*
G01X825400Y800100D02*
X831600D01*
G01X825400Y814900D02*
Y818100D01*
G01X831600Y814900D02*
X825400D01*
G01Y814100D02*
X831600D01*
G01X825400Y810900D02*
Y814100D01*
G01X831600Y810900D02*
X825400D01*
G01X827781Y809677D02*
Y807455D01*
X827934Y806990D01*
X828241Y806680D01*
X828624Y806577D01*
X829007Y806680D01*
X829314Y806990D01*
X829467Y807455D01*
Y809677D01*
G01X831724Y806577D02*
Y809677D01*
X831264Y809057D01*
G01Y806577D02*
X832184D01*
G01X834824D02*
Y809677D01*
X834364Y809057D01*
G01Y806577D02*
X835284D01*
G01X837272Y806939D02*
X837541Y806680D01*
X837847Y806577D01*
X838154Y806680D01*
X838422Y806990D01*
X838614Y807455D01*
X838691Y807920D01*
Y808489D01*
X838614Y808954D01*
X838422Y809367D01*
X838192Y809574D01*
X837924Y809677D01*
X837617Y809574D01*
X837387Y809367D01*
X837234Y809057D01*
X837157Y808644D01*
X837234Y808282D01*
X837426Y807920D01*
X837656Y807714D01*
X837924Y807662D01*
X838231Y807765D01*
X838461Y808024D01*
X838691Y808489D01*
G01X825400Y818900D02*
Y822100D01*
G01X831600Y818900D02*
X825400D01*
G01Y822100D02*
X831600D01*
G01X825400Y818100D02*
X831600D01*
G01X823834Y831638D02*
Y828438D01*
G01X817634D02*
Y831638D01*
G01X823834Y828438D02*
X817634D01*
G01X834712Y825113D02*
X831512D01*
G01Y831313D02*
X834712D01*
G01X831512Y825113D02*
Y831313D01*
G01X824431Y835141D02*
X821231D01*
G01X824431Y841341D02*
Y835141D01*
G01X821231Y841341D02*
X824431D01*
G01X821231Y835141D02*
Y841341D01*
G01X834326Y838954D02*
X831126D01*
G01Y845154D02*
X834326D01*
G01X831126Y838954D02*
Y845154D01*
G01X817634Y831638D02*
X823834D01*
G01X831512Y838190D02*
X834712D01*
G01X831512Y831990D02*
Y838190D01*
G01X834712Y831990D02*
X831512D01*
G01X820431Y835141D02*
X817231D01*
G01X820431Y841341D02*
Y835141D01*
G01X817231Y841341D02*
X820431D01*
G01X817231Y835141D02*
Y841341D01*
G01X826896Y838534D02*
X829118D01*
X829583Y838687D01*
X829893Y838994D01*
X829996Y839377D01*
X829893Y839760D01*
X829583Y840067D01*
X829118Y840220D01*
X826896D01*
G01X829996Y842477D02*
X829944Y842745D01*
X829789Y843052D01*
X829531Y843244D01*
X829169Y843320D01*
X828808Y843244D01*
X828498Y843014D01*
X828343Y842669D01*
Y842285D01*
X828239Y842055D01*
X827981Y841864D01*
X827619Y841787D01*
X827258Y841902D01*
X826999Y842170D01*
X826896Y842477D01*
X826999Y842784D01*
X827258Y843052D01*
X827619Y843167D01*
X827981Y843090D01*
X828239Y842899D01*
X828343Y842669D01*
Y842285D01*
X828498Y841940D01*
X828808Y841710D01*
X829169Y841634D01*
X829531Y841710D01*
X829789Y841902D01*
X829944Y842209D01*
X829996Y842477D01*
G01X829634Y844925D02*
X829893Y845194D01*
X829996Y845500D01*
X829893Y845807D01*
X829583Y846075D01*
X829118Y846267D01*
X828653Y846344D01*
X828084D01*
X827619Y846267D01*
X827206Y846075D01*
X826999Y845845D01*
X826896Y845577D01*
X826999Y845270D01*
X827206Y845040D01*
X827516Y844887D01*
X827929Y844810D01*
X828291Y844887D01*
X828653Y845079D01*
X828859Y845309D01*
X828911Y845577D01*
X828808Y845884D01*
X828549Y846114D01*
X828084Y846344D01*
G01X833252Y857366D02*
X824984D01*
G01X831118Y853966D02*
X833252Y856100D01*
G01Y851832D02*
X831118Y853966D01*
G01X824984Y850566D02*
X833252D01*
G01X824984Y857366D02*
Y850566D01*
G01X821156Y856018D02*
Y857284D01*
G01X819022Y853884D02*
X821156Y856018D01*
G01Y851750D02*
X819022Y853884D01*
G01X821156Y850484D02*
Y851750D01*
G01X825131Y876204D02*
Y881335D01*
G01X833595Y876204D02*
X825131D01*
G01X821591Y879695D02*
Y874564D01*
G01X819820Y881195D02*
X821591Y879695D01*
G01X821627Y866155D02*
X818427D01*
G01X821627Y872355D02*
Y866155D01*
G01X818427Y872355D02*
X821627D01*
G01X818427Y866155D02*
Y872355D01*
G01X831280Y871964D02*
X834480D01*
G01X831280Y865764D02*
Y871964D01*
G01X834480Y865764D02*
X831280D01*
G01X827280Y871964D02*
X830480D01*
G01X827280Y865764D02*
Y871964D01*
G01X830480Y865764D02*
X827280D01*
G01X830480Y871964D02*
Y865764D01*
G01X817627Y872355D02*
Y866155D01*
G01X822814Y891832D02*
X825036D01*
X825501Y891985D01*
X825811Y892292D01*
X825914Y892675D01*
X825811Y893058D01*
X825501Y893365D01*
X825036Y893518D01*
X822814D01*
G01X825294Y894932D02*
X825656Y895162D01*
X825862Y895468D01*
X825914Y895813D01*
X825862Y896120D01*
X825604Y896427D01*
X825294Y896618D01*
X824984Y896657D01*
X824622Y896580D01*
X824364Y896312D01*
X824261Y896043D01*
Y895698D01*
G01Y896043D02*
X824106Y896273D01*
X823847Y896465D01*
X823537Y896542D01*
X823227Y896465D01*
X822969Y896273D01*
X822814Y895928D01*
X822866Y895583D01*
X823072Y895238D01*
G01X822814Y898875D02*
X822917Y898568D01*
X823176Y898338D01*
X823486Y898185D01*
X823899Y898070D01*
X824364Y898032D01*
X824829Y898070D01*
X825242Y898185D01*
X825552Y898338D01*
X825811Y898568D01*
X825914Y898875D01*
X825811Y899182D01*
X825552Y899412D01*
X825242Y899565D01*
X824829Y899680D01*
X824364Y899718D01*
X823899Y899680D01*
X823486Y899565D01*
X823176Y899412D01*
X822917Y899182D01*
X822814Y898875D01*
G01X823331Y901247D02*
X823021Y901477D01*
X822866Y901745D01*
X822814Y902052D01*
X822917Y902435D01*
X823176Y902703D01*
X823486Y902780D01*
X823796Y902742D01*
X824054Y902588D01*
X824571Y901822D01*
X824932Y901477D01*
X825449Y901247D01*
X825914Y901170D01*
Y902780D01*
G01X825131Y881335D02*
X826902Y882835D01*
G01X825131Y889466D02*
X833595D01*
G01X825131Y884335D02*
Y889466D01*
G01X826902Y882835D02*
X825131Y884335D01*
G01X821591Y882695D02*
X819820Y881195D01*
G01X821591Y887826D02*
Y882695D01*
G01X827043Y891489D02*
Y897689D01*
G01X830243Y891489D02*
X827043D01*
G01X830243Y897689D02*
Y891489D01*
G01X821229Y891030D02*
X818029D01*
G01X821229Y897230D02*
Y891030D01*
G01X818029D02*
Y897230D01*
G01X831043Y891489D02*
Y897689D01*
G01X834243Y891489D02*
X831043D01*
G01X816924Y895019D02*
Y891819D01*
G01X827043Y897689D02*
X830243D01*
G01X818029Y897230D02*
X821229D01*
G01X831043Y897689D02*
X834243D01*
G01X821424Y902519D02*
Y899319D01*
G01X827309Y906943D02*
Y913143D01*
G01X830509D02*
Y906943D01*
G01D02*
X827309D01*
G01X831309D02*
Y913143D01*
G01X834509Y906943D02*
X831309D01*
G01X828587Y931305D02*
Y925105D01*
X825387D01*
Y931305D01*
X828587D01*
G01X829313Y925077D02*
Y931277D01*
X832513D01*
Y925077D01*
X829313D01*
G01X827309Y913143D02*
X830509D01*
G01X831309D02*
X834509D01*
G01X833009Y917693D02*
X829809D01*
G01D02*
Y923893D01*
G01D02*
X833009D01*
G01X829009D02*
Y917693D01*
G01D02*
X825809D01*
G01D02*
Y923893D01*
G01D02*
X829009D01*
G01X821593Y939156D02*
X823815D01*
X824280Y939309D01*
X824590Y939616D01*
X824693Y939999D01*
X824590Y940382D01*
X824280Y940689D01*
X823815Y940842D01*
X821593D01*
G01X824693Y943099D02*
X821593D01*
X822213Y942639D01*
G01X824693D02*
Y943559D01*
G01X822110Y945471D02*
X821800Y945701D01*
X821645Y945969D01*
X821593Y946276D01*
X821696Y946659D01*
X821955Y946927D01*
X822265Y947004D01*
X822575Y946966D01*
X822833Y946812D01*
X823350Y946046D01*
X823711Y945701D01*
X824228Y945471D01*
X824693Y945394D01*
Y947004D01*
G01X824073Y948456D02*
X824435Y948686D01*
X824641Y948992D01*
X824693Y949337D01*
X824641Y949644D01*
X824383Y949951D01*
X824073Y950142D01*
X823763Y950181D01*
X823401Y950104D01*
X823143Y949836D01*
X823040Y949567D01*
Y949222D01*
G01Y949567D02*
X822885Y949797D01*
X822626Y949989D01*
X822316Y950066D01*
X822006Y949989D01*
X821748Y949797D01*
X821593Y949452D01*
X821645Y949107D01*
X821851Y948762D01*
G01X841065Y938580D02*
X828861D01*
G01X831963Y944342D02*
X828861Y947342D01*
G01Y941240D02*
X831963Y944342D01*
G01X828861Y938580D02*
Y941240D01*
G01X818877Y931971D02*
Y935171D01*
G01D02*
X825077D01*
G01D02*
Y931971D01*
G01D02*
X818877D01*
G01X828861Y950104D02*
X841065D01*
G01X828861Y947342D02*
Y950104D01*
G01X826823Y957594D02*
Y963794D01*
G01X830023Y957594D02*
X826823D01*
G01X830023Y963794D02*
Y957594D01*
G01X834023D02*
X830823D01*
G01D02*
Y963794D01*
G01X826823D02*
X830023D01*
G01X830823D02*
X834023D01*
G01X821235Y1135604D02*
Y1141804D01*
G01X824435Y1135604D02*
X821235D01*
G01X824435Y1141804D02*
Y1135604D01*
G01X820435D02*
X817235D01*
G01X820435Y1141804D02*
Y1135604D01*
G01X817235D02*
Y1141804D01*
G01X816435D02*
Y1135604D01*
G01X820037Y1152405D02*
Y1149643D01*
G01X816935Y1155405D02*
X820037Y1152405D01*
G01Y1158507D02*
X816935Y1155405D01*
G01X824844Y1145412D02*
X821644D01*
G01X824844Y1151612D02*
Y1145412D01*
G01X821644Y1151612D02*
X824844D01*
G01X821644Y1145412D02*
Y1151612D01*
G01X821235Y1141804D02*
X824435D01*
G01X817235D02*
X820435D01*
G01X820037Y1161167D02*
Y1158507D01*
G01X824820Y1163692D02*
X821620D01*
G01X824820Y1169892D02*
Y1163692D01*
G01X821620Y1169892D02*
X824820D01*
G01X821620Y1163692D02*
Y1169892D01*
G01X819542Y1172720D02*
Y1169520D01*
G01X818448Y1186726D02*
Y1180526D01*
G01X819226Y1179813D02*
X822426D01*
G01X819226Y1173613D02*
Y1179813D01*
G01X822426Y1173613D02*
X819226D01*
G01X822426Y1179813D02*
Y1173613D01*
G01X819216Y1186763D02*
X822416D01*
G01X819216Y1180563D02*
Y1186763D01*
G01X822416Y1180563D02*
X819216D01*
G01X822416Y1186763D02*
Y1180563D01*
G01X818426Y1179813D02*
Y1173613D01*
G01X817087Y1200094D02*
Y1193894D01*
G01X817089Y1208118D02*
Y1201918D01*
G01X825089D02*
X821889D01*
G01X825089Y1208118D02*
Y1201918D01*
G01X821889D02*
Y1208118D01*
G01X821087Y1193894D02*
X817887D01*
G01X821087Y1200094D02*
Y1193894D01*
G01X817887Y1200094D02*
X821087D01*
G01X817887Y1193894D02*
Y1200094D01*
G01X825087Y1193894D02*
X821887D01*
G01X825087Y1200094D02*
Y1193894D01*
G01X821887Y1200094D02*
X825087D01*
G01X821887Y1193894D02*
Y1200094D01*
G01X821089Y1201918D02*
X817889D01*
G01X821089Y1208118D02*
Y1201918D01*
G01X817889D02*
Y1208118D01*
G01X818346Y1218468D02*
X816084Y1216206D01*
G01X821175Y1221297D02*
X818913Y1219035D01*
G01X816791Y1225681D02*
X821175Y1221297D01*
G01X821889Y1208118D02*
X825089D01*
G01X817889D02*
X821089D01*
G01X824003Y1224125D02*
X821741Y1221863D01*
G01X819619Y1228509D02*
X824003Y1224125D01*
G01X817357Y1226247D02*
X819619Y1228509D01*
G01X821741Y1221863D02*
X817357Y1226247D01*
G01X815748Y1382283D02*
Y1376083D01*
G01X831994Y1392193D02*
Y1399693D01*
G01X835914D02*
Y1392193D01*
G01Y1395943D02*
X831994D01*
G01X839494Y1393193D02*
X840241Y1392568D01*
X841081Y1392193D01*
X841827D01*
X842574Y1392568D01*
X843134Y1393193D01*
X843414Y1394068D01*
X843227Y1394943D01*
X842761Y1395693D01*
X841921Y1396193D01*
X840801Y1396443D01*
X840147Y1396943D01*
X839867Y1397818D01*
X840054Y1398693D01*
X840521Y1399318D01*
X841174Y1399693D01*
X841827D01*
X842481Y1399443D01*
X843041Y1398818D01*
G01X851007Y1399068D02*
X850447Y1399443D01*
X849794Y1399693D01*
X849047D01*
X848207Y1399318D01*
X847554Y1398693D01*
X847087Y1397943D01*
X846714Y1396693D01*
X846621Y1395568D01*
X846807Y1394443D01*
X847087Y1393693D01*
X847647Y1392943D01*
X848301Y1392443D01*
X848954Y1392193D01*
X849607D01*
X850261Y1392443D01*
X850821Y1392818D01*
X851287Y1393318D01*
G01X853654Y1389693D02*
X859254D01*
G01X861527Y1392193D02*
Y1399693D01*
X863954Y1393443D01*
X866381Y1399693D01*
Y1392193D01*
G01X871454D02*
X870894Y1392318D01*
X870334Y1392818D01*
X869961Y1393693D01*
X869774Y1394693D01*
X869961Y1395693D01*
X870334Y1396568D01*
X870894Y1397068D01*
X871454Y1397193D01*
X872014Y1397068D01*
X872574Y1396568D01*
X872947Y1395693D01*
X873041Y1394693D01*
X872947Y1393693D01*
X872574Y1392818D01*
X872014Y1392318D01*
X871454Y1392193D01*
G01X880634Y1399693D02*
Y1392193D01*
G01Y1393318D02*
X880261Y1392693D01*
X879701Y1392318D01*
X879047Y1392193D01*
X878301Y1392443D01*
X877741Y1393068D01*
X877367Y1393818D01*
X877274Y1394693D01*
X877367Y1395568D01*
X877741Y1396318D01*
X878301Y1396943D01*
X879047Y1397193D01*
X879701Y1397068D01*
X880167Y1396818D01*
X880634Y1396318D01*
G01X884867Y1397193D02*
Y1393693D01*
X885241Y1392818D01*
X885801Y1392318D01*
X886454Y1392193D01*
X887107Y1392318D01*
X887667Y1392818D01*
X888041Y1393693D01*
G01Y1392193D02*
Y1397193D01*
G01X893954Y1392193D02*
Y1399693D01*
G01X900054Y1395568D02*
X903041D01*
X902761Y1396443D01*
X902294Y1396943D01*
X901641Y1397193D01*
X900987Y1397068D01*
X900427Y1396693D01*
X900054Y1395818D01*
X899867Y1395068D01*
Y1394318D01*
X900054Y1393568D01*
X900521Y1392818D01*
X901081Y1392318D01*
X901734Y1392193D01*
X902387Y1392443D01*
X903041Y1393193D01*
G01X816558Y1391188D02*
Y1384588D01*
G01Y1400788D02*
Y1394188D01*
G01X829604Y1439249D02*
Y1442449D01*
G01X835804Y1439249D02*
X829604D01*
G01Y1442449D02*
X835804D01*
G01X829604Y1447249D02*
Y1450449D01*
G01X835804Y1447249D02*
X829604D01*
G01Y1446449D02*
X835804D01*
G01X829604Y1443249D02*
Y1446449D01*
G01X835804Y1443249D02*
X829604D01*
G01X822583Y1442478D02*
Y1462696D01*
G01X830510Y1460861D02*
X824310D01*
G01X830510Y1464061D02*
Y1460861D01*
G01X824310Y1464061D02*
X830510D01*
G01X824310Y1460861D02*
Y1464061D01*
G01X829604Y1450449D02*
X835804D01*
G01X829622Y1452925D02*
Y1456125D01*
G01X835822Y1452925D02*
X829622D01*
G01Y1456125D02*
X835822D01*
G01X843543Y74540D02*
Y77740D01*
G01X849743Y74540D02*
X843543D01*
G01Y77740D02*
X849743D01*
G01X843543Y78540D02*
Y81740D01*
G01X849743Y78540D02*
X843543D01*
G01Y81740D02*
X849743D01*
G01X843543Y82540D02*
Y85740D01*
G01X849743Y82540D02*
X843543D01*
G01X835154Y86929D02*
X831954D01*
G01X835154Y93129D02*
Y86929D01*
G01X831954Y93129D02*
X835154D01*
G01X831954Y86929D02*
Y93129D01*
G01X843543Y85740D02*
X849743D01*
G01X839154Y86929D02*
X835954D01*
G01X839154Y93129D02*
Y86929D01*
G01X835954Y93129D02*
X839154D01*
G01X835954Y86929D02*
Y93129D01*
G01X847163Y86929D02*
X843963D01*
G01X847163Y93129D02*
Y86929D01*
G01X843963Y93129D02*
X847163D01*
G01X843963Y86929D02*
Y93129D01*
G01X833150Y97026D02*
Y103226D01*
G01X836350Y97026D02*
X833150D01*
G01X836350Y103226D02*
Y97026D01*
G01X843154Y86929D02*
X839954D01*
G01X843154Y93129D02*
Y86929D01*
G01X839954Y93129D02*
X843154D01*
G01X839954Y86929D02*
Y93129D01*
G01X839233Y96673D02*
Y102873D01*
G01X842433Y96673D02*
X839233D01*
G01X842433Y102873D02*
Y96673D01*
G01X843233D02*
Y102873D01*
G01X846433Y96673D02*
X843233D01*
G01X846433Y102873D02*
Y96673D01*
G01X833150Y103226D02*
X836350D01*
G01X839233Y102873D02*
X842433D01*
G01X843233D02*
X846433D01*
G01X834518Y164436D02*
Y195440D01*
G01X843484Y171473D02*
X840284D01*
G01X843484Y177673D02*
Y171473D01*
G01X840284Y177673D02*
X843484D01*
G01X840284Y171473D02*
Y177673D01*
G01X839484Y171473D02*
X836284D01*
G01X839484Y177673D02*
Y171473D01*
G01X836284Y177673D02*
X839484D01*
G01X836284Y171473D02*
Y177673D01*
G01X846507Y170297D02*
Y167097D01*
G01X840307Y170297D02*
X846507D01*
G01X840307Y167097D02*
Y170297D01*
G01X846507Y167097D02*
X840307D01*
G01X843711Y182730D02*
X840511D01*
G01X843711Y188930D02*
Y182730D01*
G01X840511Y188930D02*
X843711D01*
G01X840511Y182730D02*
Y188930D01*
G01X846702Y193541D02*
Y190341D01*
G01X840502Y193541D02*
X846702D01*
G01X840502Y190341D02*
Y193541D01*
G01X846702Y190341D02*
X840502D01*
G01X831831Y213035D02*
Y225035D01*
G01X837831Y213035D02*
X831831D01*
G01X837831Y225035D02*
Y213035D01*
G01X847140Y201184D02*
Y204284D01*
X848060D01*
X848367Y204129D01*
X848597Y203767D01*
X848674Y203354D01*
X848597Y202941D01*
X848405Y202631D01*
X848060Y202476D01*
X847140D01*
G01X850164Y204284D02*
Y202062D01*
X850317Y201597D01*
X850624Y201287D01*
X851007Y201184D01*
X851390Y201287D01*
X851697Y201597D01*
X851850Y202062D01*
Y204284D01*
G01X853264Y201804D02*
X853494Y201442D01*
X853800Y201236D01*
X854145Y201184D01*
X854452Y201236D01*
X854759Y201494D01*
X854950Y201804D01*
X854989Y202114D01*
X854912Y202476D01*
X854644Y202734D01*
X854375Y202837D01*
X854030D01*
G01X854375D02*
X854605Y202992D01*
X854797Y203251D01*
X854874Y203561D01*
X854797Y203871D01*
X854605Y204129D01*
X854260Y204284D01*
X853915Y204232D01*
X853570Y204026D01*
G01X857130Y201184D02*
X857207Y201856D01*
X857322Y202424D01*
X857475Y202941D01*
X857667Y203509D01*
X857974Y204284D01*
X856440D01*
G01X860987Y220252D02*
Y208048D01*
X845683D01*
Y220252D01*
X860987D01*
G01X838671Y226621D02*
Y232621D01*
G01X850671Y226621D02*
X838671D01*
G01X831831Y225035D02*
X837831D01*
G01X842650Y215082D02*
X839450D01*
G01X842650Y221282D02*
Y215082D01*
G01X839450Y221282D02*
X842650D01*
G01X839450Y215082D02*
Y221282D01*
G01X842471Y225921D02*
X848671D01*
G01X842471Y222721D02*
Y225921D01*
G01X848671Y222721D02*
X842471D01*
G01X838671Y232621D02*
X850671D01*
G01X839339Y258010D02*
Y264210D01*
G01X842539Y258010D02*
X839339D01*
G01X842539Y264210D02*
Y258010D01*
G01X847339D02*
Y264210D01*
G01X850539Y258010D02*
X847339D01*
G01X846539D02*
X843339D01*
G01X846539Y264210D02*
Y258010D01*
G01X843339D02*
Y264210D01*
G01X837409Y283655D02*
Y271655D01*
G01X839339Y264210D02*
X842539D01*
G01X847339D02*
X850539D01*
G01X843339D02*
X846539D01*
G01X840298Y267653D02*
Y279427D01*
G01X850060Y267653D02*
X840298D01*
G01X841592Y283383D02*
X838392D01*
G01X841592Y289583D02*
Y283383D01*
G01X838392Y289583D02*
X841592D01*
G01X838392Y283383D02*
Y289583D01*
G01X845592Y283383D02*
X842392D01*
G01X845592Y289583D02*
Y283383D01*
G01X842392Y289583D02*
X845592D01*
G01X842392Y283383D02*
Y289583D01*
G01X846392Y283383D02*
Y289583D01*
X849592D01*
Y283383D01*
X846392D01*
G01X840298Y279427D02*
X850060D01*
G01X836219Y307817D02*
X852735D01*
G01X836219Y338919D02*
Y307817D01*
G01X835884Y343435D02*
Y341213D01*
X836037Y340748D01*
X836344Y340438D01*
X836727Y340335D01*
X837110Y340438D01*
X837417Y340748D01*
X837570Y341213D01*
Y343435D01*
G01X838984Y340955D02*
X839214Y340593D01*
X839520Y340387D01*
X839865Y340335D01*
X840172Y340387D01*
X840479Y340645D01*
X840670Y340955D01*
X840709Y341265D01*
X840632Y341627D01*
X840364Y341885D01*
X840095Y341988D01*
X839750D01*
G01X840095D02*
X840325Y342143D01*
X840517Y342402D01*
X840594Y342712D01*
X840517Y343022D01*
X840325Y343280D01*
X839980Y343435D01*
X839635Y343383D01*
X839290Y343177D01*
G01X842084Y340955D02*
X842314Y340593D01*
X842620Y340387D01*
X842965Y340335D01*
X843272Y340387D01*
X843579Y340645D01*
X843770Y340955D01*
X843809Y341265D01*
X843732Y341627D01*
X843464Y341885D01*
X843195Y341988D01*
X842850D01*
G01X843195D02*
X843425Y342143D01*
X843617Y342402D01*
X843694Y342712D01*
X843617Y343022D01*
X843425Y343280D01*
X843080Y343435D01*
X842735Y343383D01*
X842390Y343177D01*
G01X846027Y343435D02*
X845720Y343332D01*
X845490Y343073D01*
X845337Y342763D01*
X845222Y342350D01*
X845184Y341885D01*
X845222Y341420D01*
X845337Y341007D01*
X845490Y340697D01*
X845720Y340438D01*
X846027Y340335D01*
X846334Y340438D01*
X846564Y340697D01*
X846717Y341007D01*
X846832Y341420D01*
X846870Y341885D01*
X846832Y342350D01*
X846717Y342763D01*
X846564Y343073D01*
X846334Y343332D01*
X846027Y343435D01*
G01X850028Y338919D02*
X844477Y333368D01*
G01X838926Y338919D02*
X836219D01*
G01X844477Y333368D02*
X838926Y338919D01*
G01X832879Y421963D02*
X863883D01*
G01X832879Y436763D02*
Y421963D01*
G01X847698Y410137D02*
X844498D01*
G01X847698Y416337D02*
Y410137D01*
G01X844498Y416337D02*
X847698D01*
G01X844498Y410137D02*
Y416337D01*
G01X863883Y436763D02*
X832879D01*
G01X832210Y457909D02*
Y454709D01*
G01Y449909D02*
Y446709D01*
G01Y453909D02*
Y450709D01*
G01X843654Y459782D02*
Y462982D01*
G01X849854Y459782D02*
X843654D01*
G01Y462982D02*
X849854D01*
G01X843654Y467782D02*
Y470982D01*
G01X849854Y467782D02*
X843654D01*
G01Y470982D02*
X849854D01*
G01X843654Y466982D02*
X849854D01*
G01X843654Y463782D02*
Y466982D01*
G01X849854Y463782D02*
X843654D01*
G01Y474982D02*
X849854D01*
Y471782D01*
X843654D01*
Y474982D01*
G01X832086Y492216D02*
Y486216D01*
G01X843654Y480782D02*
Y483982D01*
G01X849854Y480782D02*
X843654D01*
G01Y483982D02*
X849854D01*
G01X843654Y475782D02*
Y478982D01*
G01X849854Y475782D02*
X843654D01*
G01Y478982D02*
X849854D01*
G01X846684Y711914D02*
Y718114D01*
G01X849884Y711914D02*
X846684D01*
G01X833884Y718114D02*
Y711914D01*
G01X837690Y711144D02*
X840890D01*
G01X837690Y704944D02*
Y711144D01*
G01X840890Y704944D02*
X837690D01*
G01X840890Y711144D02*
Y704944D01*
G01X841684Y711164D02*
X844884D01*
G01X841684Y704964D02*
Y711164D01*
G01X844884Y704964D02*
X841684D01*
G01X844884Y711164D02*
Y704964D01*
G01X837690Y711894D02*
Y718094D01*
G01X840890Y711894D02*
X837690D01*
G01X840890Y718094D02*
Y711894D01*
G01X841684Y711914D02*
Y718114D01*
G01X844884Y711914D02*
X841684D01*
G01X844884Y718114D02*
Y711914D01*
G01X852684Y724314D02*
X843884D01*
G01D02*
Y737914D01*
G01X838100Y725907D02*
X840322D01*
X840787Y726060D01*
X841097Y726367D01*
X841200Y726750D01*
X841097Y727133D01*
X840787Y727440D01*
X840322Y727593D01*
X838100D01*
G01X840580Y729007D02*
X840942Y729237D01*
X841148Y729543D01*
X841200Y729888D01*
X841148Y730195D01*
X840890Y730502D01*
X840580Y730693D01*
X840270Y730732D01*
X839908Y730655D01*
X839650Y730387D01*
X839547Y730118D01*
Y729773D01*
G01Y730118D02*
X839392Y730348D01*
X839133Y730540D01*
X838823Y730617D01*
X838513Y730540D01*
X838255Y730348D01*
X838100Y730003D01*
X838152Y729658D01*
X838358Y729313D01*
G01X840735Y732107D02*
X840993Y732337D01*
X841148Y732605D01*
X841200Y732950D01*
X841097Y733295D01*
X840890Y733563D01*
X840528Y733755D01*
X840115Y733793D01*
X839702Y733717D01*
X839443Y733525D01*
X839237Y733257D01*
X839185Y732988D01*
X839237Y732720D01*
X839443Y732375D01*
X838100Y732490D01*
Y733525D01*
G01X838617Y735322D02*
X838307Y735552D01*
X838152Y735820D01*
X838100Y736127D01*
X838203Y736510D01*
X838462Y736778D01*
X838772Y736855D01*
X839082Y736817D01*
X839340Y736663D01*
X839857Y735897D01*
X840218Y735552D01*
X840735Y735322D01*
X841200Y735245D01*
Y736855D01*
G01X836684Y732114D02*
Y737914D01*
G01Y724314D02*
Y730114D01*
G01X835184Y731114D02*
X836684Y732114D01*
G01Y730114D02*
X835184Y731114D01*
G01X846684Y718114D02*
X849884D01*
G01X837690Y718094D02*
X840890D01*
G01X841684Y718114D02*
X844884D01*
G01X843884Y737914D02*
X852684D01*
G01X836084Y739626D02*
X832884D01*
G01X836084Y745826D02*
Y739626D01*
G01X832884Y745826D02*
X836084D01*
G01X832884Y739626D02*
Y745826D01*
G01X848084Y739626D02*
X844884D01*
G01Y745826D02*
X848084D01*
G01X844884Y739626D02*
Y745826D01*
G01X840084Y739626D02*
X836884D01*
G01X840084Y745826D02*
Y739626D01*
G01X836884Y745826D02*
X840084D01*
G01X836884Y739626D02*
Y745826D01*
G01X844084Y739626D02*
X840884D01*
G01X844084Y745826D02*
Y739626D01*
G01X840884Y745826D02*
X844084D01*
G01X840884Y739626D02*
Y745826D01*
G01X832084D02*
Y739626D01*
G01X831600Y768100D02*
Y764900D01*
G01Y760100D02*
Y756900D01*
G01Y764100D02*
Y760900D01*
G01X839528Y755092D02*
Y752870D01*
X839681Y752405D01*
X839988Y752095D01*
X840371Y751992D01*
X840754Y752095D01*
X841061Y752405D01*
X841214Y752870D01*
Y755092D01*
G01X843471Y751992D02*
Y755092D01*
X843011Y754472D01*
G01Y751992D02*
X843931D01*
G01X845843Y754575D02*
X846073Y754885D01*
X846341Y755040D01*
X846648Y755092D01*
X847031Y754989D01*
X847299Y754730D01*
X847376Y754420D01*
X847338Y754110D01*
X847184Y753852D01*
X846418Y753335D01*
X846073Y752974D01*
X845843Y752457D01*
X845766Y751992D01*
X847376D01*
G01X848943Y754575D02*
X849173Y754885D01*
X849441Y755040D01*
X849748Y755092D01*
X850131Y754989D01*
X850399Y754730D01*
X850476Y754420D01*
X850438Y754110D01*
X850284Y753852D01*
X849518Y753335D01*
X849173Y752974D01*
X848943Y752457D01*
X848866Y751992D01*
X850476D01*
G01X850700Y768004D02*
Y755996D01*
X840300D01*
Y768004D01*
X843500D01*
X845500Y765937D01*
X847500Y768004D01*
X850700D01*
G01X831600Y782100D02*
Y778900D01*
G01Y778100D02*
Y774900D01*
G01X850700Y786004D02*
Y773996D01*
X840300D01*
Y786004D01*
X843500D01*
X845500Y783937D01*
X847500Y786004D01*
X850700D01*
G01X831600Y786100D02*
Y782900D01*
G01Y796100D02*
Y792900D01*
G01Y800100D02*
Y796900D01*
G01X840307Y790100D02*
Y787878D01*
X840460Y787413D01*
X840767Y787103D01*
X841150Y787000D01*
X841533Y787103D01*
X841840Y787413D01*
X841993Y787878D01*
Y790100D01*
G01X844250Y787000D02*
Y790100D01*
X843790Y789480D01*
G01Y787000D02*
X844710D01*
G01X846622Y789583D02*
X846852Y789893D01*
X847120Y790048D01*
X847427Y790100D01*
X847810Y789997D01*
X848078Y789738D01*
X848155Y789428D01*
X848117Y789118D01*
X847963Y788860D01*
X847197Y788343D01*
X846852Y787982D01*
X846622Y787465D01*
X846545Y787000D01*
X848155D01*
G01X850450D02*
Y790100D01*
X849990Y789480D01*
G01Y787000D02*
X850910D01*
G01X850700Y804004D02*
Y791996D01*
X840300D01*
Y804004D01*
X843500D01*
X845500Y801937D01*
X847500Y804004D01*
X850700D01*
G01X831600Y804100D02*
Y800900D01*
G01Y818100D02*
Y814900D01*
G01Y814100D02*
Y810900D01*
G01X847139Y807957D02*
Y805735D01*
X847292Y805270D01*
X847599Y804960D01*
X847982Y804857D01*
X848365Y804960D01*
X848672Y805270D01*
X848825Y805735D01*
Y807957D01*
G01X851082Y804857D02*
Y807957D01*
X850622Y807337D01*
G01Y804857D02*
X851542D01*
G01X853454Y807440D02*
X853684Y807750D01*
X853952Y807905D01*
X854259Y807957D01*
X854642Y807854D01*
X854910Y807595D01*
X854987Y807285D01*
X854949Y806975D01*
X854795Y806717D01*
X854029Y806200D01*
X853684Y805839D01*
X853454Y805322D01*
X853377Y804857D01*
X854987D01*
G01X857282Y807957D02*
X856975Y807854D01*
X856745Y807595D01*
X856592Y807285D01*
X856477Y806872D01*
X856439Y806407D01*
X856477Y805942D01*
X856592Y805529D01*
X856745Y805219D01*
X856975Y804960D01*
X857282Y804857D01*
X857589Y804960D01*
X857819Y805219D01*
X857972Y805529D01*
X858087Y805942D01*
X858125Y806407D01*
X858087Y806872D01*
X857972Y807285D01*
X857819Y807595D01*
X857589Y807854D01*
X857282Y807957D01*
G01X850700Y822004D02*
Y809996D01*
X840300D01*
Y822004D01*
X843500D01*
X845500Y819937D01*
X847500Y822004D01*
X850700D01*
G01X831600Y822100D02*
Y818900D01*
G01X836742Y825859D02*
Y829059D01*
G01X842942Y825859D02*
X836742D01*
G01X842942Y829059D02*
Y825859D01*
G01X836742Y829059D02*
X842942D01*
G01X844540Y826086D02*
Y829286D01*
G01X850740Y826086D02*
X844540D01*
G01Y829286D02*
X850740D01*
G01X834712Y831313D02*
Y825113D01*
G01X847385Y829958D02*
X841185D01*
Y833158D01*
X847385D01*
Y829958D01*
G01X834326Y845154D02*
Y838954D01*
G01X840916Y838353D02*
X834716D01*
Y841553D01*
X840916D01*
Y838353D01*
G01X839164Y842190D02*
Y845390D01*
G01X845364Y842190D02*
X839164D01*
G01X845364Y845390D02*
Y842190D01*
G01X839164Y845390D02*
X845364D01*
G01X839164Y845890D02*
Y849090D01*
G01X845364Y845890D02*
X839164D01*
G01X845364Y849090D02*
Y845890D01*
G01X841209Y833859D02*
Y837059D01*
G01X847409Y833859D02*
X841209D01*
G01X847409Y837059D02*
Y833859D01*
G01X841209Y837059D02*
X847409D01*
G01X834712Y838190D02*
Y831990D01*
G01X847457Y837692D02*
X841257D01*
Y840892D01*
X847457D01*
Y837692D01*
G01X839164Y849090D02*
X845364D01*
G01X841209Y849859D02*
Y853059D01*
G01X847409Y849859D02*
X841209D01*
G01X847409Y853059D02*
Y849859D01*
G01X841209Y853059D02*
X847409D01*
G01X838637Y861813D02*
Y865013D01*
G01X844837Y861813D02*
X838637D01*
G01X844837Y865013D02*
Y861813D01*
G01X834805Y858892D02*
Y865092D01*
G01X838005Y858892D02*
X834805D01*
G01X838005Y865092D02*
Y858892D01*
G01X838764Y853795D02*
Y856995D01*
G01X844964Y853795D02*
X838764D01*
G01X844964Y856995D02*
Y853795D01*
G01X838764Y856995D02*
X844964D01*
G01X833252Y856100D02*
Y857366D01*
G01Y850566D02*
Y851832D01*
G01X833595Y889466D02*
Y876204D01*
G01X838637Y865013D02*
X844837D01*
G01X834805Y865092D02*
X838005D01*
G01X844558Y881059D02*
Y877859D01*
G01X838358D02*
Y881059D01*
G01X844558Y877859D02*
X838358D01*
G01X838637Y865813D02*
Y869013D01*
G01X844837Y865813D02*
X838637D01*
G01X844837Y869013D02*
Y865813D01*
G01X838637Y869013D02*
X844837D01*
G01X847345Y877107D02*
Y873907D01*
G01X841145Y877107D02*
X847345D01*
G01X841145Y873907D02*
Y877107D01*
G01X847345Y873907D02*
X841145D01*
G01X837911Y872488D02*
X834711D01*
G01X837911Y878688D02*
Y872488D01*
G01X834711Y878688D02*
X837911D01*
G01X834711Y872488D02*
Y878688D01*
G01X844868Y873059D02*
Y869859D01*
G01X838668Y873059D02*
X844868D01*
G01X838668Y869859D02*
Y873059D01*
G01X844868Y869859D02*
X838668D01*
G01X834480Y871964D02*
Y865764D01*
G01X838358Y881059D02*
X844558D01*
G01Y885059D02*
Y881859D01*
G01X838358Y885059D02*
X844558D01*
G01X838358Y881859D02*
Y885059D01*
G01X844558Y881859D02*
X838358D01*
G01X845778Y894164D02*
Y890964D01*
G01X839578Y894164D02*
X845778D01*
G01X839578Y890964D02*
Y894164D01*
G01X845778Y890964D02*
X839578D01*
G01X844465Y889090D02*
Y885890D01*
G01X838265Y889090D02*
X844465D01*
G01X838265Y885890D02*
Y889090D01*
G01X844465Y885890D02*
X838265D01*
G01X834243Y897689D02*
Y891489D01*
G01X840400Y903100D02*
X843600D01*
G01Y896900D02*
X840400D01*
G01X843600Y903100D02*
Y896900D01*
G01X840400D02*
Y903100D01*
G01X847028Y907989D02*
Y914189D01*
G01X850228Y907989D02*
X847028D01*
G01X839600Y903100D02*
Y899900D01*
G01X833400Y903100D02*
X839600D01*
G01X833400Y899900D02*
Y903100D01*
G01X839600Y899900D02*
X833400D01*
G01X847600Y903100D02*
Y896900D01*
X844400D01*
Y903100D01*
X847600D01*
G01X843346Y906943D02*
Y913143D01*
X846546D01*
Y906943D01*
X843346D01*
G01X839309D02*
Y913143D01*
G01X842509D02*
Y906943D01*
G01D02*
X839309D01*
G01X835309D02*
Y913143D01*
G01X838509D02*
Y906943D01*
G01D02*
X835309D01*
G01X834509Y913143D02*
Y906943D01*
G01X840429Y931277D02*
Y925077D01*
G01X837229D02*
Y931277D01*
G01X840429Y925077D02*
X837229D01*
G01X836429Y931277D02*
Y925077D01*
G01X833229D02*
Y931277D01*
G01X836429Y925077D02*
X833229D01*
G01X847028Y914189D02*
X850228D01*
G01X850805Y931309D02*
Y925109D01*
X847605D01*
Y931309D01*
X850805D01*
G01X843795Y925077D02*
Y931277D01*
X846995D01*
Y925077D01*
X843795D01*
G01X839309Y913143D02*
X842509D01*
G01X835309D02*
X838509D01*
G01X842664Y923693D02*
Y917493D01*
G01D02*
X839464D01*
G01D02*
Y923693D01*
G01D02*
X842664D01*
G01X838835D02*
Y917493D01*
G01D02*
X835635D01*
G01D02*
Y923693D01*
G01D02*
X838835D01*
G01X833009Y923893D02*
Y917693D01*
G01X841065Y950104D02*
Y938580D01*
G01X837229Y931277D02*
X840429D01*
G01X833229D02*
X836429D01*
G01X838023Y957594D02*
X834823D01*
G01X838023Y963794D02*
Y957594D01*
G01X834823D02*
Y963794D01*
G01X834023D02*
Y957594D01*
G01X838823D02*
Y963794D01*
G01X842023Y957594D02*
X838823D01*
G01X842023Y963794D02*
Y957594D01*
G01X834823Y963794D02*
X838023D01*
G01X838823D02*
X842023D01*
G01X831792Y1151986D02*
X834014D01*
X834479Y1152139D01*
X834789Y1152446D01*
X834892Y1152829D01*
X834789Y1153212D01*
X834479Y1153519D01*
X834014Y1153672D01*
X831792D01*
G01X834272Y1155086D02*
X834634Y1155316D01*
X834840Y1155622D01*
X834892Y1155967D01*
X834840Y1156274D01*
X834582Y1156581D01*
X834272Y1156772D01*
X833962Y1156811D01*
X833600Y1156734D01*
X833342Y1156466D01*
X833239Y1156197D01*
Y1155852D01*
G01Y1156197D02*
X833084Y1156427D01*
X832825Y1156619D01*
X832515Y1156696D01*
X832205Y1156619D01*
X831947Y1156427D01*
X831792Y1156082D01*
X831844Y1155737D01*
X832050Y1155392D01*
G01X834892Y1159029D02*
X831792D01*
X832412Y1158569D01*
G01X834892D02*
Y1159489D01*
G01Y1162589D02*
X831792D01*
X834014Y1161171D01*
Y1163087D01*
G01X846385Y1242573D02*
Y1245673D01*
G01X847995D02*
Y1242573D01*
G01Y1244123D02*
X846385D01*
G01X850290Y1242573D02*
Y1245673D01*
X849830Y1245053D01*
G01Y1242573D02*
X850750D01*
G01X852547Y1243193D02*
X852777Y1242831D01*
X853083Y1242625D01*
X853428Y1242573D01*
X853735Y1242625D01*
X854042Y1242883D01*
X854233Y1243193D01*
X854272Y1243503D01*
X854195Y1243865D01*
X853927Y1244123D01*
X853658Y1244226D01*
X853313D01*
G01X853658D02*
X853888Y1244381D01*
X854080Y1244640D01*
X854157Y1244950D01*
X854080Y1245260D01*
X853888Y1245518D01*
X853543Y1245673D01*
X853198Y1245621D01*
X852853Y1245415D01*
G01X855762Y1245156D02*
X855992Y1245466D01*
X856260Y1245621D01*
X856567Y1245673D01*
X856950Y1245570D01*
X857218Y1245311D01*
X857295Y1245001D01*
X857257Y1244691D01*
X857103Y1244433D01*
X856337Y1243916D01*
X855992Y1243555D01*
X855762Y1243038D01*
X855685Y1242573D01*
X857295D01*
G01X846831Y1442459D02*
Y1439259D01*
G01X840631Y1442459D02*
X846831D01*
G01X840631Y1439259D02*
Y1442459D01*
G01X846831Y1439259D02*
X840631D01*
G01X835804Y1442449D02*
Y1439249D01*
G01Y1450449D02*
Y1447249D01*
G01Y1446449D02*
Y1443249D01*
G01X846844Y1447359D02*
X840644D01*
Y1450559D01*
X846844D01*
Y1447359D01*
G01Y1443359D02*
X840644D01*
Y1446559D01*
X846844D01*
Y1443359D01*
G01Y1459559D02*
Y1456359D01*
G01X840644Y1459559D02*
X846844D01*
G01X840644Y1456359D02*
Y1459559D01*
G01X846844Y1456359D02*
X840644D01*
G01Y1460359D02*
Y1463559D01*
G01X846844Y1460359D02*
X840644D01*
G01X846844Y1463559D02*
Y1460359D01*
G01X840644Y1463559D02*
X846844D01*
G01X835822Y1456125D02*
Y1452925D01*
G01X845343Y1465839D02*
Y1468939D01*
X846263D01*
X846570Y1468784D01*
X846800Y1468422D01*
X846877Y1468009D01*
X846800Y1467596D01*
X846608Y1467286D01*
X846263Y1467131D01*
X845343D01*
G01X848367Y1468939D02*
Y1466717D01*
X848520Y1466252D01*
X848827Y1465942D01*
X849210Y1465839D01*
X849593Y1465942D01*
X849900Y1466252D01*
X850053Y1466717D01*
Y1468939D01*
G01X851582Y1468422D02*
X851812Y1468732D01*
X852080Y1468887D01*
X852387Y1468939D01*
X852770Y1468836D01*
X853038Y1468577D01*
X853115Y1468267D01*
X853077Y1467957D01*
X852923Y1467699D01*
X852157Y1467182D01*
X851812Y1466821D01*
X851582Y1466304D01*
X851505Y1465839D01*
X853115D01*
G01X836079Y1565322D02*
Y1572822D01*
X838319D01*
X839066Y1572447D01*
X839626Y1571572D01*
X839813Y1570572D01*
X839626Y1569572D01*
X839159Y1568822D01*
X838319Y1568447D01*
X836079D01*
G01X845446Y1565322D02*
X844886Y1565447D01*
X844326Y1565947D01*
X843953Y1566822D01*
X843766Y1567822D01*
X843953Y1568822D01*
X844326Y1569697D01*
X844886Y1570197D01*
X845446Y1570322D01*
X846006Y1570197D01*
X846566Y1569697D01*
X846939Y1568822D01*
X847033Y1567822D01*
X846939Y1566822D01*
X846566Y1565947D01*
X846006Y1565447D01*
X845446Y1565322D01*
G01X850613Y1570322D02*
X851733Y1565322D01*
X852946Y1570322D01*
X854159Y1565322D01*
X855279Y1570322D01*
G01X859046Y1568697D02*
X862033D01*
X861753Y1569572D01*
X861286Y1570072D01*
X860633Y1570322D01*
X859979Y1570197D01*
X859419Y1569822D01*
X859046Y1568947D01*
X858859Y1568197D01*
Y1567447D01*
X859046Y1566697D01*
X859513Y1565947D01*
X860073Y1565447D01*
X860726Y1565322D01*
X861379Y1565572D01*
X862033Y1566322D01*
G01X866639Y1565322D02*
Y1570322D01*
G01Y1569322D02*
X867106Y1569822D01*
X867573Y1570197D01*
X868226Y1570322D01*
X868693Y1570197D01*
X869253Y1569822D01*
G01X884999Y1572197D02*
X884439Y1572572D01*
X883786Y1572822D01*
X883039D01*
X882199Y1572447D01*
X881546Y1571822D01*
X881079Y1571072D01*
X880706Y1569822D01*
X880613Y1568697D01*
X880799Y1567572D01*
X881079Y1566822D01*
X881639Y1566072D01*
X882293Y1565572D01*
X882946Y1565322D01*
X883599D01*
X884253Y1565572D01*
X884813Y1565947D01*
X885279Y1566447D01*
G01X890446Y1565322D02*
X889699Y1565447D01*
X889046Y1565947D01*
X888486Y1566697D01*
X888113Y1567572D01*
X887926Y1568572D01*
Y1569572D01*
X888113Y1570572D01*
X888486Y1571447D01*
X889046Y1572197D01*
X889699Y1572697D01*
X890446Y1572822D01*
X891193Y1572697D01*
X891846Y1572197D01*
X892406Y1571447D01*
X892779Y1570572D01*
X892966Y1569572D01*
Y1568572D01*
X892779Y1567572D01*
X892406Y1566697D01*
X891846Y1565947D01*
X891193Y1565447D01*
X890446Y1565322D01*
G01X895799D02*
Y1572822D01*
X900093Y1565322D01*
Y1572822D01*
G01X903299Y1565322D02*
Y1572822D01*
X907593Y1565322D01*
Y1572822D01*
G01X910146Y1562822D02*
X915746D01*
G01X918579Y1572822D02*
Y1565322D01*
X922313D01*
G01X849812Y1590307D02*
X846262D01*
G01X875041Y67523D02*
X862837D01*
G01D02*
Y70183D01*
G01X863534Y59613D02*
X869734D01*
G01X863534Y56413D02*
Y59613D01*
G01X869734Y56413D02*
X863534D01*
G01X860409Y70181D02*
Y66981D01*
G01X854209D02*
Y70181D01*
G01X860409Y66981D02*
X854209D01*
G01X862837Y79047D02*
X875041D01*
G01X862837Y76285D02*
Y79047D01*
G01X865939Y73285D02*
X862837Y76285D01*
G01Y70183D02*
X865939Y73285D01*
G01X849743Y77740D02*
Y74540D01*
G01Y81740D02*
Y78540D01*
G01Y85740D02*
Y82540D01*
G01X854209Y70181D02*
X860409D01*
G01Y82181D02*
Y78981D01*
G01X854209Y82181D02*
X860409D01*
G01X854209Y78981D02*
Y82181D01*
G01X860409Y78981D02*
X854209D01*
G01X854254Y74987D02*
Y78187D01*
G01X860454Y74987D02*
X854254D01*
G01X860454Y78187D02*
Y74987D01*
G01X854254Y78187D02*
X860454D01*
G01X854254Y70987D02*
Y74187D01*
G01X860454Y70987D02*
X854254D01*
G01X860454Y74187D02*
Y70987D01*
G01X854254Y74187D02*
X860454D01*
G01X861244Y93476D02*
X864444D01*
G01X861244Y87276D02*
Y93476D01*
G01X864444Y87276D02*
X861244D01*
G01X848737Y95950D02*
Y102150D01*
G01X851937Y95950D02*
X848737D01*
G01X851937Y102150D02*
Y95950D01*
G01X853401Y95913D02*
Y111267D01*
G01X865882Y95913D02*
X853401D01*
G01X859752Y116088D02*
X865952D01*
G01X859752Y112888D02*
Y116088D01*
G01X865952Y112888D02*
X859752D01*
G01X848737Y102150D02*
X851937D01*
G01X848737Y109762D02*
X851937D01*
G01X848737Y103562D02*
Y109762D01*
G01X851937Y103562D02*
X848737D01*
G01X851937Y109762D02*
Y103562D01*
G01X853401Y111267D02*
X866079D01*
G01X849857Y174900D02*
Y172678D01*
X850010Y172213D01*
X850317Y171903D01*
X850700Y171800D01*
X851083Y171903D01*
X851390Y172213D01*
X851543Y172678D01*
Y174900D01*
G01X853072Y173092D02*
X853340Y173453D01*
X853570Y173660D01*
X853877Y173763D01*
X854145Y173660D01*
X854337Y173453D01*
X854490Y173143D01*
X854528Y172782D01*
X854490Y172472D01*
X854337Y172162D01*
X854107Y171903D01*
X853838Y171800D01*
X853532Y171903D01*
X853263Y172213D01*
X853110Y172678D01*
X853072Y173195D01*
X853148Y173867D01*
X853263Y174228D01*
X853455Y174590D01*
X853723Y174848D01*
X853992Y174900D01*
X854260Y174797D01*
X854452Y174538D01*
G01X856172Y174383D02*
X856402Y174693D01*
X856670Y174848D01*
X856977Y174900D01*
X857360Y174797D01*
X857628Y174538D01*
X857705Y174228D01*
X857667Y173918D01*
X857513Y173660D01*
X856747Y173143D01*
X856402Y172782D01*
X856172Y172265D01*
X856095Y171800D01*
X857705D01*
G01X860024Y178897D02*
Y176944D01*
G01X848212D02*
Y178897D01*
G01X850165Y176944D02*
X848212D01*
G01X860024D02*
X858071D01*
G01X848212Y188756D02*
X850165D01*
G01X848212Y186803D02*
Y188756D01*
G01X860024D02*
Y186803D01*
G01X858071Y188756D02*
X860024D01*
G01X857071Y195020D02*
Y198220D01*
G01X863271Y195020D02*
X857071D01*
G01X863271Y198220D02*
Y195020D01*
G01X857071Y198220D02*
X863271D01*
G01X850671Y232621D02*
Y226621D01*
G01X848671Y225921D02*
Y222721D01*
G01X862206Y234813D02*
Y250325D01*
G01X850539Y264210D02*
Y258010D01*
G01X857250Y264635D02*
X872762D01*
G01X857250Y295727D02*
Y264635D01*
G01X855618Y273701D02*
X852418D01*
G01X855618Y279901D02*
Y273701D01*
G01X852418D02*
Y279901D01*
G01X850060Y279427D02*
Y267653D01*
G01X852418Y279901D02*
X855618D01*
G01X854200Y283033D02*
X851100D01*
Y283953D01*
X851255Y284260D01*
X851617Y284490D01*
X852030Y284567D01*
X852443Y284490D01*
X852753Y284298D01*
X852908Y283953D01*
Y283033D01*
G01X851100Y286057D02*
X853322D01*
X853787Y286210D01*
X854097Y286517D01*
X854200Y286900D01*
X854097Y287283D01*
X853787Y287590D01*
X853322Y287743D01*
X851100D01*
G01X854200Y290000D02*
X851100D01*
X851720Y289540D01*
G01X854200D02*
Y290460D01*
G01Y293100D02*
X851100D01*
X851720Y292640D01*
G01X854200D02*
Y293560D01*
G01X851100Y296200D02*
X851203Y295893D01*
X851462Y295663D01*
X851772Y295510D01*
X852185Y295395D01*
X852650Y295357D01*
X853115Y295395D01*
X853528Y295510D01*
X853838Y295663D01*
X854097Y295893D01*
X854200Y296200D01*
X854097Y296507D01*
X853838Y296737D01*
X853528Y296890D01*
X853115Y297005D01*
X852650Y297043D01*
X852185Y297005D01*
X851772Y296890D01*
X851462Y296737D01*
X851203Y296507D01*
X851100Y296200D01*
G01X872762Y295727D02*
X857250D01*
G01X852735Y307817D02*
Y338919D01*
G01X860645Y338854D02*
Y342054D01*
G01X866845Y338854D02*
X860645D01*
G01Y342054D02*
X866845D01*
G01X852735Y338919D02*
X850028D01*
G01X856986Y375400D02*
Y381600D01*
G01X860186Y375400D02*
X856986D01*
G01X860186Y381600D02*
Y375400D01*
G01X852486D02*
Y381600D01*
G01X855686Y375400D02*
X852486D01*
G01X855686Y381600D02*
Y375400D01*
G01X864686D02*
X861486D01*
G01D02*
Y381600D01*
G01X856986D02*
X860186D01*
G01X852486D02*
X855686D01*
G01X861486D02*
X864686D01*
G01X856986Y392100D02*
X860186D01*
G01X856986Y385900D02*
Y392100D01*
G01X860186Y385900D02*
X856986D01*
G01X860186Y392100D02*
Y385900D01*
G01X852486Y392100D02*
X855686D01*
G01X852486Y385900D02*
Y392100D01*
G01X855686Y385900D02*
X852486D01*
G01X855686Y392100D02*
Y385900D01*
G01X861486Y392100D02*
X864686D01*
G01X861486Y385900D02*
Y392100D01*
G01X864686Y385900D02*
X861486D01*
G01X849100Y402457D02*
X851322D01*
X851787Y402610D01*
X852097Y402917D01*
X852200Y403300D01*
X852097Y403683D01*
X851787Y403990D01*
X851322Y404143D01*
X849100D01*
G01X852200Y406400D02*
X852148Y406668D01*
X851993Y406975D01*
X851735Y407167D01*
X851373Y407243D01*
X851012Y407167D01*
X850702Y406937D01*
X850547Y406592D01*
Y406208D01*
X850443Y405978D01*
X850185Y405787D01*
X849823Y405710D01*
X849462Y405825D01*
X849203Y406093D01*
X849100Y406400D01*
X849203Y406707D01*
X849462Y406975D01*
X849823Y407090D01*
X850185Y407013D01*
X850443Y406822D01*
X850547Y406592D01*
Y406208D01*
X850702Y405863D01*
X851012Y405633D01*
X851373Y405557D01*
X851735Y405633D01*
X851993Y405825D01*
X852148Y406132D01*
X852200Y406400D01*
G01X849617Y408772D02*
X849307Y409002D01*
X849152Y409270D01*
X849100Y409577D01*
X849203Y409960D01*
X849462Y410228D01*
X849772Y410305D01*
X850082Y410267D01*
X850340Y410113D01*
X850857Y409347D01*
X851218Y409002D01*
X851735Y408772D01*
X852200Y408695D01*
Y410305D01*
G01X854345Y396620D02*
Y398573D01*
G01Y408432D02*
X856298D01*
G01X854345Y406479D02*
Y408432D01*
G01X856298Y396620D02*
X854345D01*
G01X863883Y421963D02*
Y436763D01*
G01X848874Y413160D02*
Y416360D01*
G01X855074Y413160D02*
X848874D01*
G01X855074Y416360D02*
Y413160D01*
G01X848874Y416360D02*
X855074D01*
G01X860131Y412933D02*
Y416133D01*
G01X866331Y412933D02*
X860131D01*
G01Y416133D02*
X866331D01*
G01X848874Y417160D02*
Y420360D01*
G01X855074Y417160D02*
X848874D01*
G01X855074Y420360D02*
Y417160D01*
G01X848874Y420360D02*
X855074D01*
G01X865470Y432593D02*
X867896D01*
G01X855882Y458175D02*
Y470175D01*
G01X861882Y458175D02*
X855882D01*
G01X861882Y470175D02*
Y458175D01*
G01X855882Y470175D02*
X861882D01*
G01X863882Y458175D02*
Y470175D01*
G01X869882Y458175D02*
X863882D01*
G01Y470175D02*
X869882D01*
G01X849854Y462982D02*
Y459782D01*
G01Y470982D02*
Y467782D01*
G01Y466982D02*
Y463782D01*
G01Y483982D02*
Y480782D01*
G01Y478982D02*
Y475782D01*
G01X862354Y489703D02*
Y492903D01*
G01X868554Y489703D02*
X862354D01*
G01Y485703D02*
Y488903D01*
G01X868554Y485703D02*
X862354D01*
G01Y488903D02*
X868554D01*
G01X862354Y480903D02*
X868554D01*
G01X862354Y477703D02*
Y480903D01*
G01X868554Y477703D02*
X862354D01*
G01Y481703D02*
Y484903D01*
G01X868554Y481703D02*
X862354D01*
G01Y484903D02*
X868554D01*
G01X862354Y492903D02*
X868554D01*
G01X861307Y681300D02*
Y679078D01*
X861460Y678613D01*
X861767Y678303D01*
X862150Y678200D01*
X862533Y678303D01*
X862840Y678613D01*
X862993Y679078D01*
Y681300D01*
G01X864407Y678820D02*
X864637Y678458D01*
X864943Y678252D01*
X865288Y678200D01*
X865595Y678252D01*
X865902Y678510D01*
X866093Y678820D01*
X866132Y679130D01*
X866055Y679492D01*
X865787Y679750D01*
X865518Y679853D01*
X865173D01*
G01X865518D02*
X865748Y680008D01*
X865940Y680267D01*
X866017Y680577D01*
X865940Y680887D01*
X865748Y681145D01*
X865403Y681300D01*
X865058Y681248D01*
X864713Y681042D01*
G01X867622Y679492D02*
X867890Y679853D01*
X868120Y680060D01*
X868427Y680163D01*
X868695Y680060D01*
X868887Y679853D01*
X869040Y679543D01*
X869078Y679182D01*
X869040Y678872D01*
X868887Y678562D01*
X868657Y678303D01*
X868388Y678200D01*
X868082Y678303D01*
X867813Y678613D01*
X867660Y679078D01*
X867622Y679595D01*
X867698Y680267D01*
X867813Y680628D01*
X868005Y680990D01*
X868273Y681248D01*
X868542Y681300D01*
X868810Y681197D01*
X869002Y680938D01*
G01X871450Y681300D02*
X871143Y681197D01*
X870913Y680938D01*
X870760Y680628D01*
X870645Y680215D01*
X870607Y679750D01*
X870645Y679285D01*
X870760Y678872D01*
X870913Y678562D01*
X871143Y678303D01*
X871450Y678200D01*
X871757Y678303D01*
X871987Y678562D01*
X872140Y678872D01*
X872255Y679285D01*
X872293Y679750D01*
X872255Y680215D01*
X872140Y680628D01*
X871987Y680938D01*
X871757Y681197D01*
X871450Y681300D01*
G01X856561Y682470D02*
Y695470D01*
G01X872761Y682470D02*
X856561D01*
G01X863161Y695470D02*
X864661Y692970D01*
G01X856561Y695470D02*
X863161D01*
G01X859161Y699570D02*
Y702770D01*
G01X865361Y699570D02*
X859161D01*
G01X851280Y687514D02*
X848080D01*
G01X851280Y693714D02*
Y687514D01*
G01X848080Y693714D02*
X851280D01*
G01X848080Y687514D02*
Y693714D01*
G01X849884Y718114D02*
Y711914D01*
G01X859161Y702770D02*
X865361D01*
G01X850684Y711164D02*
X853884D01*
G01X850684Y704964D02*
Y711164D01*
G01X853884Y704964D02*
X850684D01*
G01X853884Y711164D02*
Y704964D01*
G01X850684Y711914D02*
Y718114D01*
G01X853884Y711914D02*
X850684D01*
G01X853884Y718114D02*
Y711914D01*
G01X859161Y714770D02*
X865361D01*
G01X859161Y711570D02*
Y714770D01*
G01X865361Y711570D02*
X859161D01*
G01Y706770D02*
X865361D01*
G01X859161Y703570D02*
Y706770D01*
G01X865361Y703570D02*
X859161D01*
G01Y710770D02*
X865361D01*
Y707570D01*
X859161D01*
Y710770D01*
G01X854042Y723366D02*
X856264D01*
X856729Y723519D01*
X857039Y723826D01*
X857142Y724209D01*
X857039Y724592D01*
X856729Y724899D01*
X856264Y725052D01*
X854042D01*
G01X856522Y726466D02*
X856884Y726696D01*
X857090Y727002D01*
X857142Y727347D01*
X857090Y727654D01*
X856832Y727961D01*
X856522Y728152D01*
X856212Y728191D01*
X855850Y728114D01*
X855592Y727846D01*
X855489Y727577D01*
Y727232D01*
G01Y727577D02*
X855334Y727807D01*
X855075Y727999D01*
X854765Y728076D01*
X854455Y727999D01*
X854197Y727807D01*
X854042Y727462D01*
X854094Y727117D01*
X854300Y726772D01*
G01X856677Y729566D02*
X856935Y729796D01*
X857090Y730064D01*
X857142Y730409D01*
X857039Y730754D01*
X856832Y731022D01*
X856470Y731214D01*
X856057Y731252D01*
X855644Y731176D01*
X855385Y730984D01*
X855179Y730716D01*
X855127Y730447D01*
X855179Y730179D01*
X855385Y729834D01*
X854042Y729949D01*
Y730984D01*
G01X857142Y733509D02*
X854042D01*
X854662Y733049D01*
G01X857142D02*
Y733969D01*
G01X851184Y731114D02*
X852684Y732114D01*
G01Y730114D02*
X851184Y731114D01*
G01X852684Y724314D02*
Y730114D01*
G01Y732114D02*
Y737914D01*
G01X850684Y718114D02*
X853884D01*
G01X858961Y721070D02*
Y724270D01*
G01X865161Y721070D02*
X858961D01*
G01Y724270D02*
X865161D01*
G01X856084Y739626D02*
X852884D01*
G01X856084Y745826D02*
Y739626D01*
G01X852884Y745826D02*
X856084D01*
G01X852884Y739626D02*
Y745826D01*
G01X848084D02*
Y739626D01*
G01X852084D02*
X848884D01*
G01X852084Y745826D02*
Y739626D01*
G01X848884Y745826D02*
X852084D01*
G01X848884Y739626D02*
Y745826D01*
G01X859900Y766400D02*
Y769600D01*
G01X866100Y766400D02*
X859900D01*
G01Y754400D02*
Y757600D01*
G01X866100Y754400D02*
X859900D01*
G01Y757600D02*
X866100D01*
G01X859900Y758400D02*
Y761600D01*
G01X866100Y758400D02*
X859900D01*
G01Y761600D02*
X866100D01*
G01X859900Y762400D02*
Y765600D01*
G01X866100Y762400D02*
X859900D01*
G01Y765600D02*
X866100D01*
G01X859900Y769600D02*
X866100D01*
G01X859900Y776400D02*
Y779600D01*
G01X866100Y776400D02*
X859900D01*
G01Y779600D02*
X866100D01*
G01X859900Y780400D02*
Y783600D01*
G01X866100Y780400D02*
X859900D01*
G01Y772400D02*
Y775600D01*
G01X866100Y772400D02*
X859900D01*
G01Y775600D02*
X866100D01*
G01X859900Y787600D02*
X866100D01*
G01X859900Y784400D02*
Y787600D01*
G01X866100Y784400D02*
X859900D01*
G01Y783600D02*
X866100D01*
G01X859900Y798400D02*
Y801600D01*
G01X866100Y798400D02*
X859900D01*
G01Y790400D02*
Y793600D01*
G01X866100Y790400D02*
X859900D01*
G01Y793600D02*
X866100D01*
G01X859900Y794400D02*
Y797600D01*
G01X866100Y794400D02*
X859900D01*
G01Y797600D02*
X866100D01*
G01X859900Y805600D02*
X866100D01*
G01X859900Y802400D02*
Y805600D01*
G01X866100Y802400D02*
X859900D01*
G01Y801600D02*
X866100D01*
G01X859900Y812400D02*
Y815600D01*
G01X866100Y812400D02*
X859900D01*
G01Y808400D02*
Y811600D01*
G01X866100Y808400D02*
X859900D01*
G01Y811600D02*
X866100D01*
G01X859900Y823600D02*
X866100D01*
G01X859900Y820400D02*
Y823600D01*
G01X866100Y820400D02*
X859900D01*
G01Y815600D02*
X866100D01*
G01X852231Y825868D02*
Y829068D01*
G01X858431Y825868D02*
X852231D01*
G01X858431Y829068D02*
Y825868D01*
G01X852231Y829068D02*
X858431D01*
G01X859900Y816400D02*
Y819600D01*
G01X866100Y816400D02*
X859900D01*
G01Y819600D02*
X866100D01*
G01X850740Y829286D02*
Y826086D01*
G01X858328Y829869D02*
X852128D01*
Y833069D01*
X858328D01*
Y829869D01*
G01X852159Y833859D02*
Y837059D01*
G01X858359Y833859D02*
X852159D01*
G01X858359Y837059D02*
Y833859D01*
G01X852159Y837059D02*
X858359D01*
G01Y845059D02*
Y841859D01*
G01X852159Y845059D02*
X858359D01*
G01X852159Y841859D02*
Y845059D01*
G01X858359Y841859D02*
X852159D01*
G01X858359Y849059D02*
Y845859D01*
G01X852159D02*
Y849059D01*
G01X858359Y845859D02*
X852159D01*
G01X858359Y837859D02*
X852159D01*
Y841059D01*
X858359D01*
Y837859D01*
G01Y865059D02*
Y861859D01*
G01X852159D02*
Y865059D01*
G01X858359Y861859D02*
X852159D01*
G01X858359Y861059D02*
Y857859D01*
G01X852159Y861059D02*
X858359D01*
G01X852159Y857859D02*
Y861059D01*
G01X858359Y857859D02*
X852159D01*
G01X858359Y857059D02*
Y853859D01*
G01X852159Y857059D02*
X858359D01*
G01X852159Y853859D02*
Y857059D01*
G01X858359Y853859D02*
X852159D01*
G01X858359Y853059D02*
Y849859D01*
G01X852159Y853059D02*
X858359D01*
G01X852159Y849859D02*
Y853059D01*
G01X858359Y849859D02*
X852159D01*
G01Y849059D02*
X858359D01*
G01X852159Y865059D02*
X858359D01*
G01Y869059D02*
Y865859D01*
G01X852159Y869059D02*
X858359D01*
G01X852159Y865859D02*
Y869059D01*
G01X858359Y865859D02*
X852159D01*
G01X858359Y881059D02*
Y877859D01*
G01X852159D02*
Y881059D01*
G01X858359Y877859D02*
X852159D01*
G01X858359Y877059D02*
Y873859D01*
G01X852159Y877059D02*
X858359D01*
G01X852159Y873859D02*
Y877059D01*
G01X858359Y873859D02*
X852159D01*
G01X858359Y873059D02*
Y869859D01*
G01X852159Y873059D02*
X858359D01*
G01X852159Y869859D02*
Y873059D01*
G01X858359Y869859D02*
X852159D01*
G01Y881059D02*
X858359D01*
G01Y894559D02*
Y891359D01*
G01X852159Y894559D02*
X858359D01*
G01X852159Y891359D02*
Y894559D01*
G01X858359Y891359D02*
X852159D01*
G01X858359Y885059D02*
Y881859D01*
G01X852159Y885059D02*
X858359D01*
G01X852159Y881859D02*
Y885059D01*
G01X858359Y881859D02*
X852159D01*
G01X858359Y889359D02*
Y886159D01*
G01X852159Y889359D02*
X858359D01*
G01X852159Y886159D02*
Y889359D01*
G01X858359Y886159D02*
X852159D01*
G01X855028Y907989D02*
Y914189D01*
G01X858228Y907989D02*
X855028D01*
G01X858228Y914189D02*
Y907989D01*
G01X863028D02*
Y914189D01*
G01X866228Y907989D02*
X863028D01*
G01X854228D02*
X851028D01*
G01X854228Y914189D02*
Y907989D01*
G01X851028D02*
Y914189D01*
G01X862228Y907989D02*
X859028D01*
G01X862228Y914189D02*
Y907989D01*
G01X859028D02*
Y914189D01*
G01X850228D02*
Y907989D01*
G01X855028Y914189D02*
X858228D01*
G01X863028D02*
X866228D01*
G01X851028D02*
X854228D01*
G01X859028D02*
X862228D01*
G01X869135Y982834D02*
X863135D01*
Y994834D01*
X869135D01*
Y982834D01*
G01X862242D02*
X856242D01*
Y994834D01*
X862242D01*
Y982834D01*
G01X855117D02*
X849117D01*
Y994834D01*
X855117D01*
Y982834D01*
G01X854088Y1018753D02*
Y1012553D01*
X850888D01*
Y1018753D01*
X854088D01*
G01X859484D02*
Y1012553D01*
X856284D01*
Y1018753D01*
X859484D01*
G01X865607D02*
Y1012553D01*
X862407D01*
Y1018753D01*
X865607D01*
G01X859956Y1031032D02*
X877658D01*
G01X859956Y1044459D02*
Y1031032D01*
G01Y1070332D02*
Y1057006D01*
G01X858664Y1055132D02*
X878950D01*
G01X858664Y1046232D02*
Y1055132D01*
G01X878950Y1046232D02*
X858664D01*
G01X877658Y1070332D02*
X859956D01*
G01X863849Y1075554D02*
X878649D01*
G01X863849Y1106558D02*
Y1075554D01*
G01X878649Y1106558D02*
X863849D01*
G01X855837Y1121936D02*
Y1114809D01*
X874491D01*
X877491Y1117809D01*
Y1121936D01*
G01X874491Y1136463D02*
X855837D01*
Y1129336D01*
G01X859751Y1141395D02*
Y1195331D01*
G01X877345Y1141395D02*
X859751D01*
G01Y1195331D02*
X877345D01*
G01X859347Y1350107D02*
Y1353207D01*
G01X860957D02*
Y1350107D01*
G01Y1351657D02*
X859347D01*
G01X863252Y1350107D02*
Y1353207D01*
X862792Y1352587D01*
G01Y1350107D02*
X863712D01*
G01X866812D02*
Y1353207D01*
X865394Y1350985D01*
X867310D01*
G01X868609Y1350727D02*
X868839Y1350365D01*
X869145Y1350159D01*
X869490Y1350107D01*
X869797Y1350159D01*
X870104Y1350417D01*
X870295Y1350727D01*
X870334Y1351037D01*
X870257Y1351399D01*
X869989Y1351657D01*
X869720Y1351760D01*
X869375D01*
G01X869720D02*
X869950Y1351915D01*
X870142Y1352174D01*
X870219Y1352484D01*
X870142Y1352794D01*
X869950Y1353052D01*
X869605Y1353207D01*
X869260Y1353155D01*
X868915Y1352949D01*
G01X854562Y1462698D02*
Y1442480D01*
G01D02*
X874780D01*
G01X851144Y1449659D02*
X847944D01*
G01X851144Y1455859D02*
Y1449659D01*
G01X847944Y1455859D02*
X851144D01*
G01X847944Y1449659D02*
Y1455859D01*
G01X874780Y1462698D02*
X854562D01*
G01X874812Y1590307D02*
X856212D01*
G01X872551Y42000D02*
Y45100D01*
G01X874161D02*
Y42000D01*
G01Y43550D02*
X872551D01*
G01X875728Y43292D02*
X875996Y43653D01*
X876226Y43860D01*
X876533Y43963D01*
X876801Y43860D01*
X876993Y43653D01*
X877146Y43343D01*
X877184Y42982D01*
X877146Y42672D01*
X876993Y42362D01*
X876763Y42103D01*
X876494Y42000D01*
X876188Y42103D01*
X875919Y42413D01*
X875766Y42878D01*
X875728Y43395D01*
X875804Y44067D01*
X875919Y44428D01*
X876111Y44790D01*
X876379Y45048D01*
X876648Y45100D01*
X876916Y44997D01*
X877108Y44738D01*
G01X878713Y42620D02*
X878943Y42258D01*
X879249Y42052D01*
X879594Y42000D01*
X879901Y42052D01*
X880208Y42310D01*
X880399Y42620D01*
X880438Y42930D01*
X880361Y43292D01*
X880093Y43550D01*
X879824Y43653D01*
X879479D01*
G01X879824D02*
X880054Y43808D01*
X880246Y44067D01*
X880323Y44377D01*
X880246Y44687D01*
X880054Y44945D01*
X879709Y45100D01*
X879364Y45048D01*
X879019Y44842D01*
G01X876300Y67907D02*
X878522D01*
X878987Y68060D01*
X879297Y68367D01*
X879400Y68750D01*
X879297Y69133D01*
X878987Y69440D01*
X878522Y69593D01*
X876300D01*
G01X879400Y71850D02*
X876300D01*
X876920Y71390D01*
G01X879400D02*
Y72310D01*
G01X878780Y74107D02*
X879142Y74337D01*
X879348Y74643D01*
X879400Y74988D01*
X879348Y75295D01*
X879090Y75602D01*
X878780Y75793D01*
X878470Y75832D01*
X878108Y75755D01*
X877850Y75487D01*
X877747Y75218D01*
Y74873D01*
G01Y75218D02*
X877592Y75448D01*
X877333Y75640D01*
X877023Y75717D01*
X876713Y75640D01*
X876455Y75448D01*
X876300Y75103D01*
X876352Y74758D01*
X876558Y74413D01*
G01X878780Y77207D02*
X879142Y77437D01*
X879348Y77743D01*
X879400Y78088D01*
X879348Y78395D01*
X879090Y78702D01*
X878780Y78893D01*
X878470Y78932D01*
X878108Y78855D01*
X877850Y78587D01*
X877747Y78318D01*
Y77973D01*
G01Y78318D02*
X877592Y78548D01*
X877333Y78740D01*
X877023Y78817D01*
X876713Y78740D01*
X876455Y78548D01*
X876300Y78203D01*
X876352Y77858D01*
X876558Y77513D01*
G01X875041Y79047D02*
Y67523D01*
G01X869734Y59613D02*
Y56413D01*
G01X864444Y93476D02*
Y87276D01*
G01X873893Y87204D02*
X870693D01*
G01X873893Y93404D02*
Y87204D01*
G01X870693Y93404D02*
X873893D01*
G01X870693Y87204D02*
Y93404D01*
G01X877800Y87299D02*
X874600D01*
G01X877800Y93499D02*
Y87299D01*
G01X874600Y93499D02*
X877800D01*
G01X874600Y87299D02*
Y93499D01*
G01X869944Y87276D02*
X866744D01*
G01X869944Y93476D02*
Y87276D01*
G01X866744Y93476D02*
X869944D01*
G01X866744Y87276D02*
Y93476D01*
G01X867500Y98707D02*
X869722D01*
X870187Y98860D01*
X870497Y99167D01*
X870600Y99550D01*
X870497Y99933D01*
X870187Y100240D01*
X869722Y100393D01*
X867500D01*
G01X870600Y103110D02*
X867500D01*
X869722Y101692D01*
Y103608D01*
G01X867500Y105750D02*
X867603Y105443D01*
X867862Y105213D01*
X868172Y105060D01*
X868585Y104945D01*
X869050Y104907D01*
X869515Y104945D01*
X869928Y105060D01*
X870238Y105213D01*
X870497Y105443D01*
X870600Y105750D01*
X870497Y106057D01*
X870238Y106287D01*
X869928Y106440D01*
X869515Y106555D01*
X869050Y106593D01*
X868585Y106555D01*
X868172Y106440D01*
X867862Y106287D01*
X867603Y106057D01*
X867500Y105750D01*
G01X870135Y108007D02*
X870393Y108237D01*
X870548Y108505D01*
X870600Y108850D01*
X870497Y109195D01*
X870290Y109463D01*
X869928Y109655D01*
X869515Y109693D01*
X869102Y109617D01*
X868843Y109425D01*
X868637Y109157D01*
X868585Y108888D01*
X868637Y108620D01*
X868843Y108275D01*
X867500Y108390D01*
Y109425D01*
G01X866079Y111267D02*
Y95913D01*
G01X865952Y116088D02*
Y112888D01*
G01X864395Y179065D02*
Y182265D01*
G01X870595Y179065D02*
X864395D01*
G01X870595Y182265D02*
Y179065D01*
G01X864395Y171065D02*
Y174265D01*
G01X870595Y171065D02*
X864395D01*
G01X870595Y174265D02*
Y171065D01*
G01X864395Y174265D02*
X870595D01*
G01X864395Y175065D02*
Y178265D01*
G01X870595Y175065D02*
X864395D01*
G01X870595Y178265D02*
Y175065D01*
G01X864395Y178265D02*
X870595D01*
G01X864395Y167065D02*
Y170265D01*
G01X870595Y167065D02*
X864395D01*
G01X870595Y170265D02*
Y167065D01*
G01X864395Y170265D02*
X870595D01*
G01X872931Y195825D02*
Y202025D01*
G01X876131Y195825D02*
X872931D01*
G01X876131Y202025D02*
Y195825D01*
G01X864395Y182265D02*
X870595D01*
G01X864395Y183065D02*
Y186265D01*
G01X870595Y183065D02*
X864395D01*
G01X870595Y186265D02*
Y183065D01*
G01X864395Y186265D02*
X870595D01*
G01X864395Y187065D02*
Y190265D01*
G01X870595Y187065D02*
X864395D01*
G01X870595Y190265D02*
Y187065D01*
G01X864395Y190265D02*
X870595D01*
G01Y194265D02*
Y191065D01*
G01X864395Y194265D02*
X870595D01*
G01X864395Y191065D02*
Y194265D01*
G01X870595Y191065D02*
X864395D01*
G01X870595Y198265D02*
Y195065D01*
G01X864395D02*
Y198265D01*
G01X870595Y195065D02*
X864395D01*
G01X880100Y195825D02*
X876900D01*
G01X880100Y202025D02*
Y195825D01*
G01X876900D02*
Y202025D01*
G01X872931D02*
X876131D01*
G01X864395Y198265D02*
X870595D01*
G01X864490Y207264D02*
Y210464D01*
G01X870690Y207264D02*
X864490D01*
G01X870690Y210464D02*
Y207264D01*
G01X864490Y210464D02*
X870690D01*
G01Y206464D02*
Y203264D01*
G01X864490Y206464D02*
X870690D01*
G01X864490Y203264D02*
Y206464D01*
G01X870690Y203264D02*
X864490D01*
G01X876900Y202025D02*
X880100D01*
G01X864490Y214464D02*
X870690D01*
Y211264D01*
X864490D01*
Y214464D01*
G01Y202464D02*
X870690D01*
Y199264D01*
X864490D01*
Y202464D01*
G01Y215264D02*
Y218464D01*
G01X870690Y215264D02*
X864490D01*
G01X870690Y218464D02*
Y215264D01*
G01X864490Y218464D02*
X870690D01*
G01X864490Y220264D02*
Y223464D01*
G01X870690Y220264D02*
X864490D01*
G01X870690Y223464D02*
Y220264D01*
G01X864490Y223464D02*
X870690D01*
G01X881340Y255609D02*
X878140D01*
G01Y261809D02*
X881340D01*
G01X878140Y255609D02*
Y261809D01*
G01X877000Y264783D02*
X873900D01*
Y265703D01*
X874055Y266010D01*
X874417Y266240D01*
X874830Y266317D01*
X875243Y266240D01*
X875553Y266048D01*
X875708Y265703D01*
Y264783D01*
G01X877000Y267807D02*
X873900D01*
Y268573D01*
X874055Y268880D01*
X874262Y269110D01*
X874572Y269302D01*
X874933Y269455D01*
X875450Y269493D01*
X875967Y269455D01*
X876328Y269302D01*
X876638Y269110D01*
X876845Y268880D01*
X877000Y268573D01*
Y267807D01*
G01Y271750D02*
X873900D01*
X874520Y271290D01*
G01X877000D02*
Y272210D01*
G01X873900Y274850D02*
X874003Y274543D01*
X874262Y274313D01*
X874572Y274160D01*
X874985Y274045D01*
X875450Y274007D01*
X875915Y274045D01*
X876328Y274160D01*
X876638Y274313D01*
X876897Y274543D01*
X877000Y274850D01*
X876897Y275157D01*
X876638Y275387D01*
X876328Y275540D01*
X875915Y275655D01*
X875450Y275693D01*
X874985Y275655D01*
X874572Y275540D01*
X874262Y275387D01*
X874003Y275157D01*
X873900Y274850D01*
G01X877000Y278410D02*
X873900D01*
X876122Y276992D01*
Y278908D01*
G01X872762Y264635D02*
Y295727D01*
G01X870877Y307768D02*
Y310968D01*
G01X877077Y307768D02*
X870877D01*
G01X877077Y310968D02*
Y307768D01*
G01X870877Y310968D02*
X877077D01*
G01X870877Y303768D02*
Y306968D01*
G01X877077Y303768D02*
X870877D01*
G01X877077Y306968D02*
Y303768D01*
G01X870877Y306968D02*
X877077D01*
G01X878877Y310968D02*
X885077D01*
G01X878877Y307768D02*
Y310968D01*
G01X885077Y307768D02*
X878877D01*
G01Y306968D02*
X885077D01*
G01X878877Y303768D02*
Y306968D01*
G01X885077Y303768D02*
X878877D01*
G01X870877Y311768D02*
Y314968D01*
G01X877077Y311768D02*
X870877D01*
G01X877077Y314968D02*
Y311768D01*
G01X870877Y314968D02*
X877077D01*
G01X878877D02*
X885077D01*
G01X878877Y311768D02*
Y314968D01*
G01X885077Y311768D02*
X878877D01*
G01Y327768D02*
Y330968D01*
G01X885077Y327768D02*
X878877D01*
G01Y326968D02*
X885077D01*
G01X878877Y323768D02*
Y326968D01*
G01X885077Y323768D02*
X878877D01*
G01Y322968D02*
X885077D01*
G01X878877Y319768D02*
Y322968D01*
G01X885077Y319768D02*
X878877D01*
G01Y318968D02*
X885077D01*
G01X878877Y315768D02*
Y318968D01*
G01X885077Y315768D02*
X878877D01*
G01X870877Y327768D02*
Y330968D01*
G01X877077Y327768D02*
X870877D01*
G01X877077Y330968D02*
Y327768D01*
G01X870877Y323768D02*
Y326968D01*
G01X877077Y323768D02*
X870877D01*
G01X877077Y326968D02*
Y323768D01*
G01X870877Y326968D02*
X877077D01*
G01X870877Y319768D02*
Y322968D01*
G01X877077Y319768D02*
X870877D01*
G01X877077Y322968D02*
Y319768D01*
G01X870877Y322968D02*
X877077D01*
G01X870877Y315768D02*
Y318968D01*
G01X877077Y315768D02*
X870877D01*
G01X877077Y318968D02*
Y315768D01*
G01X870877Y318968D02*
X877077D01*
G01X866845Y342054D02*
Y338854D01*
G01X878877Y330968D02*
X885077D01*
G01X870877D02*
X877077D01*
G01X877184Y338942D02*
Y335742D01*
G01X870984Y338942D02*
X877184D01*
G01X870984Y335742D02*
Y338942D01*
G01X877184Y335742D02*
X870984D01*
G01X878877Y338942D02*
X885077D01*
G01X878877Y335742D02*
Y338942D01*
G01X885077Y335742D02*
X878877D01*
G01X870877Y331768D02*
Y334968D01*
G01X877077Y331768D02*
X870877D01*
G01X877077Y334968D02*
Y331768D01*
G01X870877Y334968D02*
X877077D01*
G01X878877D02*
X885077D01*
G01X878877Y331768D02*
Y334968D01*
G01X885077Y331768D02*
X878877D01*
G01Y339742D02*
Y342942D01*
G01X885077Y339742D02*
X878877D01*
G01Y342942D02*
X885077D01*
G01X878877Y343742D02*
Y346942D01*
G01X885077Y343742D02*
X878877D01*
G01Y346942D02*
X885077D01*
G01X869686Y375400D02*
X866486D01*
G01X869686Y381600D02*
Y375400D01*
G01X866486D02*
Y381600D01*
G01X864686D02*
Y375400D01*
G01X866486Y381600D02*
X869686D01*
G01X879136Y390380D02*
X882336D01*
G01X879136Y384180D02*
Y390380D01*
G01X882336Y384180D02*
X879136D01*
G01X878336D02*
X875136D01*
G01X878336Y390380D02*
Y384180D01*
G01X875136Y390380D02*
X878336D01*
G01X875136Y384180D02*
Y390380D01*
G01X869186Y385900D02*
X865986D01*
G01X869186Y392100D02*
Y385900D01*
G01X865986Y392100D02*
X869186D01*
G01X865986Y385900D02*
Y392100D01*
G01X864686D02*
Y385900D01*
G01X874336Y390380D02*
Y384180D01*
X871136D01*
Y390380D01*
X874336D01*
G01X866157Y396620D02*
X864204D01*
G01X866157Y398573D02*
Y396620D01*
G01Y408432D02*
Y406479D01*
G01X864204Y408432D02*
X866157D01*
G01X872237Y396447D02*
X869137D01*
Y397367D01*
X869292Y397674D01*
X869654Y397904D01*
X870067Y397981D01*
X870480Y397904D01*
X870790Y397712D01*
X870945Y397367D01*
Y396447D01*
G01X869137Y399471D02*
X871359D01*
X871824Y399624D01*
X872134Y399931D01*
X872237Y400314D01*
X872134Y400697D01*
X871824Y401004D01*
X871359Y401157D01*
X869137D01*
G01X869654Y402686D02*
X869344Y402916D01*
X869189Y403184D01*
X869137Y403491D01*
X869240Y403874D01*
X869499Y404142D01*
X869809Y404219D01*
X870119Y404181D01*
X870377Y404027D01*
X870894Y403261D01*
X871255Y402916D01*
X871772Y402686D01*
X872237Y402609D01*
Y404219D01*
G01Y406514D02*
X872185Y406782D01*
X872030Y407089D01*
X871772Y407281D01*
X871410Y407357D01*
X871049Y407281D01*
X870739Y407051D01*
X870584Y406706D01*
Y406322D01*
X870480Y406092D01*
X870222Y405901D01*
X869860Y405824D01*
X869499Y405939D01*
X869240Y406207D01*
X869137Y406514D01*
X869240Y406821D01*
X869499Y407089D01*
X869860Y407204D01*
X870222Y407127D01*
X870480Y406936D01*
X870584Y406706D01*
Y406322D01*
X870739Y405977D01*
X871049Y405747D01*
X871410Y405671D01*
X871772Y405747D01*
X872030Y405939D01*
X872185Y406246D01*
X872237Y406514D01*
G01X885810Y395327D02*
X873606D01*
Y410631D01*
X885810D01*
Y395327D01*
G01X878593Y424483D02*
X890593D01*
G01X878593Y418483D02*
Y424483D01*
G01X890593Y418483D02*
X878593D01*
G01X870942Y409942D02*
X867742D01*
G01X870942Y416142D02*
Y409942D01*
G01X867742Y416142D02*
X870942D01*
G01X867742Y409942D02*
Y416142D01*
G01X866331Y416133D02*
Y412933D01*
G01X869583Y439600D02*
Y442700D01*
X870503D01*
X870810Y442545D01*
X871040Y442183D01*
X871117Y441770D01*
X871040Y441357D01*
X870848Y441047D01*
X870503Y440892D01*
X869583D01*
G01X872607Y439600D02*
Y442700D01*
X873373D01*
X873680Y442545D01*
X873910Y442338D01*
X874102Y442028D01*
X874255Y441667D01*
X874293Y441150D01*
X874255Y440633D01*
X874102Y440272D01*
X873910Y439962D01*
X873680Y439755D01*
X873373Y439600D01*
X872607D01*
G01X876550D02*
X876818Y439652D01*
X877125Y439807D01*
X877317Y440065D01*
X877393Y440427D01*
X877317Y440788D01*
X877087Y441098D01*
X876742Y441253D01*
X876358D01*
X876128Y441357D01*
X875937Y441615D01*
X875860Y441977D01*
X875975Y442338D01*
X876243Y442597D01*
X876550Y442700D01*
X876857Y442597D01*
X877125Y442338D01*
X877240Y441977D01*
X877163Y441615D01*
X876972Y441357D01*
X876742Y441253D01*
X876358D01*
X876013Y441098D01*
X875783Y440788D01*
X875707Y440427D01*
X875783Y440065D01*
X875975Y439807D01*
X876282Y439652D01*
X876550Y439600D01*
G01X878807Y440220D02*
X879037Y439858D01*
X879343Y439652D01*
X879688Y439600D01*
X879995Y439652D01*
X880302Y439910D01*
X880493Y440220D01*
X880532Y440530D01*
X880455Y440892D01*
X880187Y441150D01*
X879918Y441253D01*
X879573D01*
G01X879918D02*
X880148Y441408D01*
X880340Y441667D01*
X880417Y441977D01*
X880340Y442287D01*
X880148Y442545D01*
X879803Y442700D01*
X879458Y442648D01*
X879113Y442442D01*
G01X869010Y426545D02*
Y438041D01*
G01X898569Y426545D02*
X869010D01*
G01Y438041D02*
X898569D01*
G01X891549Y445501D02*
X880053D01*
G01D02*
Y475060D01*
G01X871882Y458175D02*
Y470175D01*
G01X877882Y458175D02*
X871882D01*
G01X877882Y470175D02*
Y458175D01*
G01X871882Y470175D02*
X877882D01*
G01X869882D02*
Y458175D01*
G01X873721Y489561D02*
X873414Y489613D01*
X873146Y489819D01*
X872916Y490129D01*
X872763Y490491D01*
X872686Y490904D01*
Y491318D01*
X872763Y491731D01*
X872916Y492093D01*
X873146Y492403D01*
X873414Y492609D01*
X873721Y492661D01*
X874028Y492609D01*
X874296Y492403D01*
X874526Y492093D01*
X874679Y491731D01*
X874756Y491318D01*
Y490904D01*
X874679Y490491D01*
X874526Y490129D01*
X874296Y489819D01*
X874028Y489613D01*
X873721Y489561D01*
G01X874028Y490388D02*
X874488Y489561D01*
G01X876093Y492144D02*
X876323Y492454D01*
X876591Y492609D01*
X876898Y492661D01*
X877281Y492558D01*
X877549Y492299D01*
X877626Y491989D01*
X877588Y491679D01*
X877434Y491421D01*
X876668Y490904D01*
X876323Y490543D01*
X876093Y490026D01*
X876016Y489561D01*
X877626D01*
G01X879921D02*
Y492661D01*
X879461Y492041D01*
G01Y489561D02*
X880381D01*
G01X882178Y490026D02*
X882408Y489768D01*
X882676Y489613D01*
X883021Y489561D01*
X883366Y489664D01*
X883634Y489871D01*
X883826Y490233D01*
X883864Y490646D01*
X883788Y491059D01*
X883596Y491318D01*
X883328Y491524D01*
X883059Y491576D01*
X882791Y491524D01*
X882446Y491318D01*
X882561Y492661D01*
X883596D01*
G01X878454Y488027D02*
X881872D01*
G01X876454Y486303D02*
X878454Y488027D01*
G01X874454D02*
X876454Y486303D01*
G01X871036Y488027D02*
X874454D01*
G01X871036Y478579D02*
Y488027D01*
G01X881872Y478579D02*
X871036D01*
G01X880053Y475060D02*
X891549D01*
G01X868554Y492903D02*
Y489703D01*
G01Y488903D02*
Y485703D01*
G01Y480903D02*
Y477703D01*
G01Y484903D02*
Y481703D01*
G01X874168Y556303D02*
Y553103D01*
G01X867968D02*
Y556303D01*
G01X874168Y553103D02*
X867968D01*
G01X867813Y548171D02*
Y551371D01*
G01X874013Y548171D02*
X867813D01*
G01X874013Y551371D02*
Y548171D01*
G01X867813Y551371D02*
X874013D01*
G01X874168Y560303D02*
Y557103D01*
G01X867968Y560303D02*
X874168D01*
G01X867968Y557103D02*
Y560303D01*
G01X874168Y557103D02*
X867968D01*
G01Y556303D02*
X874168D01*
G01X867968Y561103D02*
Y564303D01*
G01X874168Y561103D02*
X867968D01*
G01X874168Y564303D02*
Y561103D01*
G01X867968Y564303D02*
X874168D01*
G01X867968Y569103D02*
Y572303D01*
G01X874168Y569103D02*
X867968D01*
G01X874168Y572303D02*
Y569103D01*
G01X867968Y565103D02*
Y568303D01*
G01X874168Y565103D02*
X867968D01*
G01X874168Y568303D02*
Y565103D01*
G01X867968Y568303D02*
X874168D01*
G01X867968Y572303D02*
X874168D01*
G01X867968Y577103D02*
Y580303D01*
G01X874168Y577103D02*
X867968D01*
G01X874168Y580303D02*
Y577103D01*
G01X867968Y580303D02*
X874168D01*
G01X867968Y581228D02*
Y584428D01*
G01X874168Y581228D02*
X867968D01*
G01X874168Y584428D02*
Y581228D01*
G01X867968Y584428D02*
X874168D01*
G01Y576303D02*
Y573103D01*
G01X867968Y576303D02*
X874168D01*
G01X867968Y573103D02*
Y576303D01*
G01X874168Y573103D02*
X867968D01*
G01X874168Y588428D02*
Y585228D01*
G01X867968D02*
Y588428D01*
G01X874168Y585228D02*
X867968D01*
G01Y588428D02*
X874168D01*
G01X879107Y600100D02*
Y597878D01*
X879260Y597413D01*
X879567Y597103D01*
X879950Y597000D01*
X880333Y597103D01*
X880640Y597413D01*
X880793Y597878D01*
Y600100D01*
G01X883050Y597000D02*
Y600100D01*
X882590Y599480D01*
G01Y597000D02*
X883510D01*
G01X886150D02*
Y600100D01*
X885690Y599480D01*
G01Y597000D02*
X886610D01*
G01X889173D02*
X889250Y597672D01*
X889365Y598240D01*
X889518Y598757D01*
X889710Y599325D01*
X890017Y600100D01*
X888483D01*
G01X872761Y695470D02*
Y682470D01*
G01X882500Y675065D02*
X880074D01*
G01X866161Y695470D02*
X872761D01*
G01X864661Y692970D02*
X866161Y695470D01*
G01X873594Y699988D02*
Y696788D01*
G01X867394Y699988D02*
X873594D01*
G01X867394Y696788D02*
Y699988D01*
G01X873594Y696788D02*
X867394D01*
G01X877161Y688570D02*
X883361D01*
G01X877161Y685370D02*
Y688570D01*
G01X883361Y685370D02*
X877161D01*
G01Y693370D02*
Y696570D01*
G01X883361Y693370D02*
X877161D01*
G01Y696570D02*
X883361D01*
G01X877161Y689370D02*
Y692570D01*
G01X883361Y689370D02*
X877161D01*
G01Y692570D02*
X883361D01*
G01X877161Y700570D02*
X883361D01*
G01X877161Y697370D02*
Y700570D01*
G01X883361Y697370D02*
X877161D01*
G01X865361Y702770D02*
Y699570D01*
G01X873350Y704600D02*
X873043Y704652D01*
X872775Y704858D01*
X872545Y705168D01*
X872392Y705530D01*
X872315Y705943D01*
Y706357D01*
X872392Y706770D01*
X872545Y707132D01*
X872775Y707442D01*
X873043Y707648D01*
X873350Y707700D01*
X873657Y707648D01*
X873925Y707442D01*
X874155Y707132D01*
X874308Y706770D01*
X874385Y706357D01*
Y705943D01*
X874308Y705530D01*
X874155Y705168D01*
X873925Y704858D01*
X873657Y704652D01*
X873350Y704600D01*
G01X873657Y705427D02*
X874117Y704600D01*
G01X875607Y705065D02*
X875837Y704807D01*
X876105Y704652D01*
X876450Y704600D01*
X876795Y704703D01*
X877063Y704910D01*
X877255Y705272D01*
X877293Y705685D01*
X877217Y706098D01*
X877025Y706357D01*
X876757Y706563D01*
X876488Y706615D01*
X876220Y706563D01*
X875875Y706357D01*
X875990Y707700D01*
X877025D01*
G01X879550Y704600D02*
X879818Y704652D01*
X880125Y704807D01*
X880317Y705065D01*
X880393Y705427D01*
X880317Y705788D01*
X880087Y706098D01*
X879742Y706253D01*
X879358D01*
X879128Y706357D01*
X878937Y706615D01*
X878860Y706977D01*
X878975Y707338D01*
X879243Y707597D01*
X879550Y707700D01*
X879857Y707597D01*
X880125Y707338D01*
X880240Y706977D01*
X880163Y706615D01*
X879972Y706357D01*
X879742Y706253D01*
X879358D01*
X879013Y706098D01*
X878783Y705788D01*
X878707Y705427D01*
X878783Y705065D01*
X878975Y704807D01*
X879282Y704652D01*
X879550Y704600D01*
G01X876392Y717501D02*
X874061Y715170D01*
G01X879501Y717501D02*
X876392D01*
G01X879501Y708839D02*
Y717501D01*
G01X868621Y708839D02*
X879501D01*
G01X868621Y717501D02*
Y708839D01*
G01X871730Y717501D02*
X868621D01*
G01X874061Y715170D02*
X871730Y717501D01*
G01X865361Y714770D02*
Y711570D01*
G01Y706770D02*
Y703570D01*
G01X865161Y724270D02*
Y721070D01*
G01X868534Y733719D02*
Y731497D01*
X868687Y731032D01*
X868994Y730722D01*
X869377Y730619D01*
X869760Y730722D01*
X870067Y731032D01*
X870220Y731497D01*
Y733719D01*
G01X871634Y731239D02*
X871864Y730877D01*
X872170Y730671D01*
X872515Y730619D01*
X872822Y730671D01*
X873129Y730929D01*
X873320Y731239D01*
X873359Y731549D01*
X873282Y731911D01*
X873014Y732169D01*
X872745Y732272D01*
X872400D01*
G01X872745D02*
X872975Y732427D01*
X873167Y732686D01*
X873244Y732996D01*
X873167Y733306D01*
X872975Y733564D01*
X872630Y733719D01*
X872285Y733667D01*
X871940Y733461D01*
G01X874849Y731911D02*
X875117Y732272D01*
X875347Y732479D01*
X875654Y732582D01*
X875922Y732479D01*
X876114Y732272D01*
X876267Y731962D01*
X876305Y731601D01*
X876267Y731291D01*
X876114Y730981D01*
X875884Y730722D01*
X875615Y730619D01*
X875309Y730722D01*
X875040Y731032D01*
X874887Y731497D01*
X874849Y732014D01*
X874925Y732686D01*
X875040Y733047D01*
X875232Y733409D01*
X875500Y733667D01*
X875769Y733719D01*
X876037Y733616D01*
X876229Y733357D01*
G01X877949Y733202D02*
X878179Y733512D01*
X878447Y733667D01*
X878754Y733719D01*
X879137Y733616D01*
X879405Y733357D01*
X879482Y733047D01*
X879444Y732737D01*
X879290Y732479D01*
X878524Y731962D01*
X878179Y731601D01*
X877949Y731084D01*
X877872Y730619D01*
X879482D01*
G01X868327Y720288D02*
Y728950D01*
G01X880127Y720288D02*
X868327D01*
G01X880127Y728950D02*
Y720288D01*
G01X868327Y728950D02*
X880127D01*
G01X869988Y764515D02*
Y772715D01*
G01X882390Y764515D02*
X869988D01*
G01X866100Y769600D02*
Y766400D01*
G01Y757600D02*
Y754400D01*
G01Y761600D02*
Y758400D01*
G01Y765600D02*
Y762400D01*
G01X869988Y772715D02*
X882390D01*
G01X866100Y779600D02*
Y776400D01*
G01Y783600D02*
Y780400D01*
G01Y775600D02*
Y772400D01*
G01Y787600D02*
Y784400D01*
G01X871628Y792627D02*
Y795827D01*
G01X877828Y792627D02*
X871628D01*
G01Y795827D02*
X877828D01*
G01D02*
Y792627D01*
G01X866100Y801600D02*
Y798400D01*
G01Y793600D02*
Y790400D01*
G01Y797600D02*
Y794400D01*
G01Y805600D02*
Y802400D01*
G01X877516Y801790D02*
X874316D01*
G01X877516Y807990D02*
Y801790D01*
G01X874316Y807990D02*
X877516D01*
G01X874316Y801790D02*
Y807990D01*
G01Y811940D02*
Y818140D01*
G01X877516Y811940D02*
X874316D01*
G01X877516Y818140D02*
Y811940D01*
G01X881516D02*
X878316D01*
G01D02*
Y818140D01*
G01X866100Y815600D02*
Y812400D01*
G01Y811600D02*
Y808400D01*
G01Y823600D02*
Y820400D01*
G01X874316Y818140D02*
X877516D01*
G01X878316D02*
X881516D01*
G01X866100Y819600D02*
Y816400D01*
G01X877629Y886827D02*
Y835253D01*
G01D02*
X929203D01*
G01Y886827D02*
X877629D01*
G01X878228Y907989D02*
X875028D01*
G01X878228Y914189D02*
Y907989D01*
G01X875028D02*
Y914189D01*
G01X871028Y907989D02*
Y914189D01*
G01X874228Y907989D02*
X871028D01*
G01X874228Y914189D02*
Y907989D01*
G01X879028D02*
Y914189D01*
G01X882228Y907989D02*
X879028D01*
G01X870228D02*
X867028D01*
G01X870228Y914189D02*
Y907989D01*
G01X867028D02*
Y914189D01*
G01X866228D02*
Y907989D01*
G01X875028Y914189D02*
X878228D01*
G01X871028D02*
X874228D01*
G01X879028D02*
X882228D01*
G01X867028D02*
X870228D01*
G01X878140Y939601D02*
Y945801D01*
G01X881340Y939601D02*
X878140D01*
G01Y945801D02*
X881340D01*
G01X868748Y1005830D02*
Y995630D01*
X864148D01*
Y1005830D01*
X868748D01*
G01X873689D02*
Y995630D01*
X869089D01*
Y1005830D01*
X873689D01*
G01X878579D02*
Y995630D01*
X873979D01*
Y1005830D01*
X878579D01*
G01X883578D02*
Y995630D01*
X878978D01*
Y1005830D01*
X883578D01*
G01X872001Y1018753D02*
Y1012553D01*
X868801D01*
Y1018753D01*
X872001D01*
G01X877554D02*
Y1012553D01*
X874354D01*
Y1018753D01*
X877554D01*
G01X883054D02*
Y1012553D01*
X879854D01*
Y1018753D01*
X883054D01*
G01X877658Y1031032D02*
Y1044297D01*
G01Y1057049D02*
Y1070332D01*
G01X878950Y1055132D02*
Y1046232D01*
G01X878649Y1075554D02*
Y1106558D01*
G01X877491Y1129336D02*
Y1133463D01*
X874491Y1136463D01*
G01X869683Y1197100D02*
Y1200200D01*
X870603D01*
X870910Y1200045D01*
X871140Y1199683D01*
X871217Y1199270D01*
X871140Y1198857D01*
X870948Y1198547D01*
X870603Y1198392D01*
X869683D01*
G01X872707Y1200200D02*
Y1197978D01*
X872860Y1197513D01*
X873167Y1197203D01*
X873550Y1197100D01*
X873933Y1197203D01*
X874240Y1197513D01*
X874393Y1197978D01*
Y1200200D01*
G01X876650Y1197100D02*
Y1200200D01*
X876190Y1199580D01*
G01Y1197100D02*
X877110D01*
G01X879673D02*
X879750Y1197772D01*
X879865Y1198340D01*
X880018Y1198857D01*
X880210Y1199425D01*
X880517Y1200200D01*
X878983D01*
G01X877500Y1203200D02*
X875000D01*
X875500Y1202880D01*
G01X877500D02*
Y1203520D01*
G01X877208Y1204947D02*
X877417Y1205133D01*
X877500Y1205347D01*
X877417Y1205560D01*
X877167Y1205747D01*
X876792Y1205880D01*
X876417Y1205933D01*
X875958D01*
X875583Y1205880D01*
X875250Y1205747D01*
X875083Y1205587D01*
X875000Y1205400D01*
X875083Y1205187D01*
X875250Y1205027D01*
X875500Y1204920D01*
X875833Y1204867D01*
X876125Y1204920D01*
X876417Y1205053D01*
X876583Y1205213D01*
X876625Y1205400D01*
X876542Y1205613D01*
X876333Y1205773D01*
X875958Y1205933D01*
G01X874417Y1206102D02*
X871217D01*
G01X874417Y1212302D02*
Y1206102D01*
G01X871217Y1212302D02*
X874417D01*
G01X871217Y1206102D02*
Y1212302D01*
G01X875166Y1214337D02*
X872666D01*
X873166Y1214017D01*
G01X875166D02*
Y1214657D01*
G01Y1216537D02*
X872666D01*
X873166Y1216217D01*
G01X875166D02*
Y1216857D01*
G01X875999Y1217937D02*
Y1219537D01*
G01X875166Y1220937D02*
X872666D01*
X873166Y1220617D01*
G01X875166D02*
Y1221257D01*
G01Y1223137D02*
X875124Y1223324D01*
X874999Y1223537D01*
X874791Y1223670D01*
X874499Y1223724D01*
X874208Y1223670D01*
X873958Y1223510D01*
X873833Y1223270D01*
Y1223004D01*
X873749Y1222844D01*
X873541Y1222710D01*
X873249Y1222657D01*
X872958Y1222737D01*
X872749Y1222924D01*
X872666Y1223137D01*
X872749Y1223350D01*
X872958Y1223537D01*
X873249Y1223617D01*
X873541Y1223564D01*
X873749Y1223430D01*
X873833Y1223270D01*
Y1223004D01*
X873958Y1222764D01*
X874208Y1222604D01*
X874499Y1222550D01*
X874791Y1222604D01*
X874999Y1222737D01*
X875124Y1222950D01*
X875166Y1223137D01*
G01X877831Y1207037D02*
Y1206766D01*
X881633D01*
G01X885940Y1233491D02*
X873940D01*
G01D02*
Y1239491D01*
G01X885940Y1226591D02*
X873940D01*
G01Y1232591D02*
X885940D01*
G01X873940Y1226591D02*
Y1232591D01*
G01X883933Y1222908D02*
X877831D01*
Y1222437D01*
G01X873940Y1239491D02*
X885940D01*
G01Y1240391D02*
X873940D01*
G01Y1246391D02*
X885940D01*
G01X873940Y1240391D02*
Y1246391D01*
G01X885940Y1247291D02*
X873940D01*
G01Y1253291D02*
X885940D01*
G01X873940Y1247291D02*
Y1253291D01*
G01X874780Y1442480D02*
Y1462698D01*
G01X892854Y144690D02*
Y154138D01*
G01X903690Y144690D02*
X892854D01*
G01X895435Y139647D02*
Y142847D01*
G01X901635Y139647D02*
X895435D01*
G01Y142847D02*
X901635D01*
G01X888456Y139647D02*
Y142847D01*
G01X894656Y139647D02*
X888456D01*
G01X894656Y142847D02*
Y139647D01*
G01X888456Y142847D02*
X894656D01*
G01X884486Y145940D02*
Y149140D01*
G01X890686Y145940D02*
X884486D01*
G01X890686Y149140D02*
Y145940D01*
G01X884486Y149140D02*
X890686D01*
G01X895210Y159535D02*
X894903Y159587D01*
X894635Y159793D01*
X894405Y160103D01*
X894252Y160465D01*
X894175Y160878D01*
Y161292D01*
X894252Y161705D01*
X894405Y162067D01*
X894635Y162377D01*
X894903Y162583D01*
X895210Y162635D01*
X895517Y162583D01*
X895785Y162377D01*
X896015Y162067D01*
X896168Y161705D01*
X896245Y161292D01*
Y160878D01*
X896168Y160465D01*
X896015Y160103D01*
X895785Y159793D01*
X895517Y159587D01*
X895210Y159535D01*
G01X895517Y160362D02*
X895977Y159535D01*
G01X897582Y162118D02*
X897812Y162428D01*
X898080Y162583D01*
X898387Y162635D01*
X898770Y162532D01*
X899038Y162273D01*
X899115Y161963D01*
X899077Y161653D01*
X898923Y161395D01*
X898157Y160878D01*
X897812Y160517D01*
X897582Y160000D01*
X897505Y159535D01*
X899115D01*
G01X900682Y162118D02*
X900912Y162428D01*
X901180Y162583D01*
X901487Y162635D01*
X901870Y162532D01*
X902138Y162273D01*
X902215Y161963D01*
X902177Y161653D01*
X902023Y161395D01*
X901257Y160878D01*
X900912Y160517D01*
X900682Y160000D01*
X900605Y159535D01*
X902215D01*
G01X904970D02*
Y162635D01*
X903552Y160413D01*
X905468D01*
G01X896272Y154138D02*
X898272Y152414D01*
G01X892854Y154138D02*
X896272D01*
G01X890686Y153140D02*
Y149940D01*
G01X884486Y153140D02*
X890686D01*
G01X884486Y149940D02*
Y153140D01*
G01X890686Y149940D02*
X884486D01*
G01X895387Y210738D02*
Y218238D01*
X898933D01*
G01X897627Y214613D02*
X895387D01*
G01X903540Y218238D02*
X905780D01*
G01X904660D02*
Y210738D01*
G01X903540D02*
X905780D01*
G01X912160D02*
X911413Y210863D01*
X910760Y211363D01*
X910200Y212113D01*
X909827Y212988D01*
X909640Y213988D01*
Y214988D01*
X909827Y215988D01*
X910200Y216863D01*
X910760Y217613D01*
X911413Y218113D01*
X912160Y218238D01*
X912907Y218113D01*
X913560Y217613D01*
X914120Y216863D01*
X914493Y215988D01*
X914680Y214988D01*
Y213988D01*
X914493Y212988D01*
X914120Y212113D01*
X913560Y211363D01*
X912907Y210863D01*
X912160Y210738D01*
G01X894766Y225866D02*
X892903D01*
Y227156D01*
G01Y230356D02*
Y275256D01*
G01X920566Y225866D02*
X895966D01*
G01X929537Y222638D02*
Y282874D01*
X889183D01*
Y222638D01*
X929537D01*
G01X881340Y261809D02*
Y255609D01*
G01X892903Y278356D02*
Y279646D01*
X894766D01*
G01X895816D02*
X920566D01*
G01X885077Y310968D02*
Y307768D01*
G01Y306968D02*
Y303768D01*
G01Y314968D02*
Y311768D01*
G01Y330968D02*
Y327768D01*
G01Y326968D02*
Y323768D01*
G01Y322968D02*
Y319768D01*
G01Y318968D02*
Y315768D01*
G01Y338942D02*
Y335742D01*
G01Y334968D02*
Y331768D01*
G01Y342942D02*
Y339742D01*
G01Y346942D02*
Y343742D01*
G01X886787Y339937D02*
Y343137D01*
G01X892987Y339937D02*
X886787D01*
G01X892987Y343137D02*
Y339937D01*
G01X886787Y343137D02*
X892987D01*
G01X892136Y390380D02*
X895336D01*
G01X892136Y384180D02*
Y390380D01*
G01X895336Y384180D02*
X892136D01*
G01X895336Y390380D02*
Y384180D01*
G01X887136Y390380D02*
X890336D01*
G01X887136Y384180D02*
Y390380D01*
G01X890336Y384180D02*
X887136D01*
G01X890336Y390380D02*
Y384180D01*
G01X882336Y390380D02*
Y384180D01*
G01X899336D02*
X896136D01*
G01Y390380D02*
X899336D01*
G01X896136Y384180D02*
Y390380D01*
G01X886336D02*
Y384180D01*
X883136D01*
Y390380D01*
X886336D01*
G01X892179Y405643D02*
Y417643D01*
G01X898179Y405643D02*
X892179D01*
G01X891479Y407643D02*
X888279D01*
G01X891479Y413843D02*
Y407643D01*
G01X888279D02*
Y413843D01*
G01X890593Y424483D02*
Y418483D01*
G01X892179Y417643D02*
X898179D01*
G01X897753Y423525D02*
X895513D01*
G01X896726Y421900D02*
Y425150D01*
G01X880640Y413664D02*
Y416864D01*
G01X886840Y413664D02*
X880640D01*
G01X886840Y416864D02*
Y413664D01*
G01X880640Y416864D02*
X886840D01*
G01X888279Y413843D02*
X891479D01*
G01X885501Y441961D02*
Y444387D01*
G01X896000Y446183D02*
X892900D01*
Y447103D01*
X893055Y447410D01*
X893417Y447640D01*
X893830Y447717D01*
X894243Y447640D01*
X894553Y447448D01*
X894708Y447103D01*
Y446183D01*
G01X896000Y449207D02*
X892900D01*
Y449973D01*
X893055Y450280D01*
X893262Y450510D01*
X893572Y450702D01*
X893933Y450855D01*
X894450Y450893D01*
X894967Y450855D01*
X895328Y450702D01*
X895638Y450510D01*
X895845Y450280D01*
X896000Y449973D01*
Y449207D01*
G01Y453150D02*
X892900D01*
X893520Y452690D01*
G01X896000D02*
Y453610D01*
G01Y456250D02*
X895948Y456518D01*
X895793Y456825D01*
X895535Y457017D01*
X895173Y457093D01*
X894812Y457017D01*
X894502Y456787D01*
X894347Y456442D01*
Y456058D01*
X894243Y455828D01*
X893985Y455637D01*
X893623Y455560D01*
X893262Y455675D01*
X893003Y455943D01*
X892900Y456250D01*
X893003Y456557D01*
X893262Y456825D01*
X893623Y456940D01*
X893985Y456863D01*
X894243Y456672D01*
X894347Y456442D01*
Y456058D01*
X894502Y455713D01*
X894812Y455483D01*
X895173Y455407D01*
X895535Y455483D01*
X895793Y455675D01*
X895948Y455982D01*
X896000Y456250D01*
G01X891549Y475060D02*
Y445501D01*
G01X898091Y460278D02*
X894891D01*
G01Y466478D02*
X898091D01*
G01X894891Y460278D02*
Y466478D01*
G01X881872Y488027D02*
Y478579D01*
G01X885401Y478701D02*
Y476461D01*
G01X887026Y477674D02*
X883776D01*
G01X890554Y487903D02*
Y484703D01*
G01X884354Y487903D02*
X890554D01*
G01X884354Y484703D02*
Y487903D01*
G01X890554Y484703D02*
X884354D01*
G01X898031Y534968D02*
X894831D01*
G01D02*
Y541168D01*
G01X891331Y534968D02*
Y541168D01*
G01X894531Y534968D02*
X891331D01*
G01X894531Y541168D02*
Y534968D01*
G01X884331D02*
Y541168D01*
G01X887531Y534968D02*
X884331D01*
G01X887531Y541168D02*
Y534968D01*
G01X887831D02*
Y541168D01*
G01X891031Y534968D02*
X887831D01*
G01X891031Y541168D02*
Y534968D01*
G01X890900Y531233D02*
X897100D01*
G01X890900Y528033D02*
Y531233D01*
G01X897100Y528033D02*
X890900D01*
G01X894831Y541168D02*
X898031D01*
G01X891331D02*
X894531D01*
G01X884331D02*
X887531D01*
G01X887831D02*
X891031D01*
G01X884240Y563545D02*
X886288D01*
G01X884240Y565593D02*
Y563545D01*
G01Y595041D02*
Y592993D01*
G01X886288Y595041D02*
X884240D01*
G01X893533Y611068D02*
X890333D01*
G01X893533Y617268D02*
Y611068D01*
G01X890333Y617268D02*
X893533D01*
G01X890333Y611068D02*
Y617268D01*
G01X894333D02*
X897533D01*
G01X894333Y611068D02*
Y617268D01*
G01X897533Y611068D02*
X894333D01*
G01X886107Y677400D02*
Y680500D01*
X886873D01*
X887180Y680345D01*
X887410Y680138D01*
X887602Y679828D01*
X887755Y679467D01*
X887793Y678950D01*
X887755Y678433D01*
X887602Y678072D01*
X887410Y677762D01*
X887180Y677555D01*
X886873Y677400D01*
X886107D01*
G01X889322Y679983D02*
X889552Y680293D01*
X889820Y680448D01*
X890127Y680500D01*
X890510Y680397D01*
X890778Y680138D01*
X890855Y679828D01*
X890817Y679518D01*
X890663Y679260D01*
X889897Y678743D01*
X889552Y678382D01*
X889322Y677865D01*
X889245Y677400D01*
X890855D01*
G01X892307Y678020D02*
X892537Y677658D01*
X892843Y677452D01*
X893188Y677400D01*
X893495Y677452D01*
X893802Y677710D01*
X893993Y678020D01*
X894032Y678330D01*
X893955Y678692D01*
X893687Y678950D01*
X893418Y679053D01*
X893073D01*
G01X893418D02*
X893648Y679208D01*
X893840Y679467D01*
X893917Y679777D01*
X893840Y680087D01*
X893648Y680345D01*
X893303Y680500D01*
X892958Y680448D01*
X892613Y680242D01*
G01X891810Y682434D02*
Y686372D01*
G01X892204Y684403D02*
X894172Y682434D01*
G01Y686372D02*
X892204Y684403D01*
G01X894172Y682434D02*
Y686372D01*
G01X884991Y681603D02*
Y687203D01*
G01X899491Y681603D02*
X884991D01*
G01X886491Y681703D02*
Y687103D01*
G01X885991D02*
Y681703D01*
G01X885491D02*
Y687103D01*
G01X883361Y688570D02*
Y685370D01*
G01Y696570D02*
Y693370D01*
G01Y692570D02*
Y689370D01*
G01Y700570D02*
Y697370D01*
G01X884991Y687203D02*
X899491D01*
G01X885734Y702886D02*
Y700664D01*
X885887Y700199D01*
X886194Y699889D01*
X886577Y699786D01*
X886960Y699889D01*
X887267Y700199D01*
X887420Y700664D01*
Y702886D01*
G01X888834Y700406D02*
X889064Y700044D01*
X889370Y699838D01*
X889715Y699786D01*
X890022Y699838D01*
X890329Y700096D01*
X890520Y700406D01*
X890559Y700716D01*
X890482Y701078D01*
X890214Y701336D01*
X889945Y701439D01*
X889600D01*
G01X889945D02*
X890175Y701594D01*
X890367Y701853D01*
X890444Y702163D01*
X890367Y702473D01*
X890175Y702731D01*
X889830Y702886D01*
X889485Y702834D01*
X889140Y702628D01*
G01X891934Y700251D02*
X892164Y699993D01*
X892432Y699838D01*
X892777Y699786D01*
X893122Y699889D01*
X893390Y700096D01*
X893582Y700458D01*
X893620Y700871D01*
X893544Y701284D01*
X893352Y701543D01*
X893084Y701749D01*
X892815Y701801D01*
X892547Y701749D01*
X892202Y701543D01*
X892317Y702886D01*
X893352D01*
G01X895225Y700148D02*
X895494Y699889D01*
X895800Y699786D01*
X896107Y699889D01*
X896375Y700199D01*
X896567Y700664D01*
X896644Y701129D01*
Y701698D01*
X896567Y702163D01*
X896375Y702576D01*
X896145Y702783D01*
X895877Y702886D01*
X895570Y702783D01*
X895340Y702576D01*
X895187Y702266D01*
X895110Y701853D01*
X895187Y701491D01*
X895379Y701129D01*
X895609Y700923D01*
X895877Y700871D01*
X896184Y700974D01*
X896414Y701233D01*
X896644Y701698D01*
G01X886070Y698450D02*
Y689788D01*
G01X898984Y698450D02*
X886070D01*
G01Y689788D02*
X898984D01*
G01X888361Y720170D02*
Y716970D01*
G01X882161D02*
Y720170D01*
G01X888361Y716970D02*
X882161D01*
G01X896750Y706200D02*
X896443Y706252D01*
X896175Y706458D01*
X895945Y706768D01*
X895792Y707130D01*
X895715Y707543D01*
Y707957D01*
X895792Y708370D01*
X895945Y708732D01*
X896175Y709042D01*
X896443Y709248D01*
X896750Y709300D01*
X897057Y709248D01*
X897325Y709042D01*
X897555Y708732D01*
X897708Y708370D01*
X897785Y707957D01*
Y707543D01*
X897708Y707130D01*
X897555Y706768D01*
X897325Y706458D01*
X897057Y706252D01*
X896750Y706200D01*
G01X897057Y707027D02*
X897517Y706200D01*
G01X899007Y706665D02*
X899237Y706407D01*
X899505Y706252D01*
X899850Y706200D01*
X900195Y706303D01*
X900463Y706510D01*
X900655Y706872D01*
X900693Y707285D01*
X900617Y707698D01*
X900425Y707957D01*
X900157Y708163D01*
X899888Y708215D01*
X899620Y708163D01*
X899275Y707957D01*
X899390Y709300D01*
X900425D01*
G01X902222Y707492D02*
X902490Y707853D01*
X902720Y708060D01*
X903027Y708163D01*
X903295Y708060D01*
X903487Y707853D01*
X903640Y707543D01*
X903678Y707182D01*
X903640Y706872D01*
X903487Y706562D01*
X903257Y706303D01*
X902988Y706200D01*
X902682Y706303D01*
X902413Y706613D01*
X902260Y707078D01*
X902222Y707595D01*
X902298Y708267D01*
X902413Y708628D01*
X902605Y708990D01*
X902873Y709248D01*
X903142Y709300D01*
X903410Y709197D01*
X903602Y708938D01*
G01X891024Y712930D02*
Y725010D01*
G01X903498Y712930D02*
X891024D01*
G01X882161Y725578D02*
Y728778D01*
G01X888361Y725578D02*
X882161D01*
G01X888361Y728778D02*
Y725578D01*
G01X882161Y728778D02*
X888361D01*
G01X882161Y720170D02*
X888361D01*
G01X882161Y721170D02*
Y724370D01*
G01X888361Y721170D02*
X882161D01*
G01X888361Y724370D02*
Y721170D01*
G01X882161Y724370D02*
X888361D01*
G01X895550Y726000D02*
X895243Y726052D01*
X894975Y726258D01*
X894745Y726568D01*
X894592Y726930D01*
X894515Y727343D01*
Y727757D01*
X894592Y728170D01*
X894745Y728532D01*
X894975Y728842D01*
X895243Y729048D01*
X895550Y729100D01*
X895857Y729048D01*
X896125Y728842D01*
X896355Y728532D01*
X896508Y728170D01*
X896585Y727757D01*
Y727343D01*
X896508Y726930D01*
X896355Y726568D01*
X896125Y726258D01*
X895857Y726052D01*
X895550Y726000D01*
G01X895857Y726827D02*
X896317Y726000D01*
G01X897807Y726465D02*
X898037Y726207D01*
X898305Y726052D01*
X898650Y726000D01*
X898995Y726103D01*
X899263Y726310D01*
X899455Y726672D01*
X899493Y727085D01*
X899417Y727498D01*
X899225Y727757D01*
X898957Y727963D01*
X898688Y728015D01*
X898420Y727963D01*
X898075Y727757D01*
X898190Y729100D01*
X899225D01*
G01X901673Y726000D02*
X901750Y726672D01*
X901865Y727240D01*
X902018Y727757D01*
X902210Y728325D01*
X902517Y729100D01*
X900983D01*
G01X891024Y725010D02*
X903498D01*
G01X885645Y745635D02*
X882445D01*
G01X885645Y751835D02*
Y745635D01*
G01X882445D02*
Y751835D01*
G01X882390Y767615D02*
Y764515D01*
G01X882445Y751835D02*
X885645D01*
G01X882390Y772715D02*
Y769615D01*
G01X881197Y768615D02*
X882390Y769615D01*
G01Y767715D02*
X881197Y768615D01*
G01X891128Y794376D02*
X894328D01*
G01X891128Y788176D02*
Y794376D01*
G01X894328Y788176D02*
X891128D01*
G01X894328Y794376D02*
Y788176D01*
G01X881516Y818140D02*
Y811940D01*
G01X889516Y801790D02*
X886316D01*
G01X889516Y807990D02*
Y801790D01*
G01X886316Y807990D02*
X889516D01*
G01X886316Y801790D02*
Y807990D01*
G01X885516Y801790D02*
X882316D01*
G01X885516Y807990D02*
Y801790D01*
G01X882316Y807990D02*
X885516D01*
G01X882316Y801790D02*
Y807990D01*
G01X894316Y811940D02*
Y818140D01*
G01X897516Y811940D02*
X894316D01*
G01X885516D02*
X882316D01*
G01X885516Y818140D02*
Y811940D01*
G01X882316D02*
Y818140D01*
G01X889516Y811940D02*
X886316D01*
G01X889516Y818140D02*
Y811940D01*
G01X886316D02*
Y818140D01*
G01X893516Y801790D02*
X890316D01*
G01X893516Y807990D02*
Y801790D01*
G01X890316Y807990D02*
X893516D01*
G01X890316Y801790D02*
Y807990D01*
G01X894316Y818140D02*
X897516D01*
G01X882316D02*
X885516D01*
G01X886316D02*
X889516D01*
G01X886228Y907989D02*
X883028D01*
G01X886228Y914189D02*
Y907989D01*
G01X883028D02*
Y914189D01*
G01X887028Y907989D02*
Y914189D01*
G01X890228Y907989D02*
X887028D01*
G01X890228Y914189D02*
Y907989D01*
G01X891028D02*
Y914189D01*
G01X894228Y907989D02*
X891028D01*
G01X894228Y914189D02*
Y907989D01*
G01X895028D02*
Y914189D01*
G01X898228Y907989D02*
X895028D01*
G01X882228Y914189D02*
Y907989D01*
G01X883028Y914189D02*
X886228D01*
G01X887028D02*
X890228D01*
G01X891028D02*
X894228D01*
G01X895028D02*
X898228D01*
G01X883151Y938135D02*
Y951135D01*
G01X899351Y938135D02*
X883151D01*
G01X881340Y945801D02*
Y939601D01*
G01X883558Y955702D02*
Y953480D01*
X883711Y953015D01*
X884018Y952705D01*
X884401Y952602D01*
X884784Y952705D01*
X885091Y953015D01*
X885244Y953480D01*
Y955702D01*
G01X887961Y952602D02*
Y955702D01*
X886543Y953480D01*
X888459D01*
G01X890601Y952602D02*
Y955702D01*
X890141Y955082D01*
G01Y952602D02*
X891061D01*
G01X893701D02*
X893969Y952654D01*
X894276Y952809D01*
X894468Y953067D01*
X894544Y953429D01*
X894468Y953790D01*
X894238Y954100D01*
X893893Y954255D01*
X893509D01*
X893279Y954359D01*
X893088Y954617D01*
X893011Y954979D01*
X893126Y955340D01*
X893394Y955599D01*
X893701Y955702D01*
X894008Y955599D01*
X894276Y955340D01*
X894391Y954979D01*
X894314Y954617D01*
X894123Y954359D01*
X893893Y954255D01*
X893509D01*
X893164Y954100D01*
X892934Y953790D01*
X892858Y953429D01*
X892934Y953067D01*
X893126Y952809D01*
X893433Y952654D01*
X893701Y952602D01*
G01X892751Y951135D02*
X899351D01*
G01X891251Y948635D02*
X892751Y951135D01*
G01X889751D02*
X891251Y948635D01*
G01X883151Y951135D02*
X889751D01*
G01X888520Y1005830D02*
Y995630D01*
X883920D01*
Y1005830D01*
X888520D01*
G01X893368D02*
Y995630D01*
X888768D01*
Y1005830D01*
X893368D01*
G01X898289D02*
Y995630D01*
X893689D01*
Y1005830D01*
X898289D01*
G01X886810Y1018753D02*
Y1012553D01*
X883610D01*
Y1018753D01*
X886810D01*
G01X890689D02*
Y1012553D01*
X887489D01*
Y1018753D01*
X890689D01*
G01X895213Y1018896D02*
Y1012696D01*
X892013D01*
Y1018896D01*
X895213D01*
G01X899646Y1018840D02*
Y1012640D01*
X896446D01*
Y1018840D01*
X899646D01*
G01X881689Y1030724D02*
X899391D01*
G01X881689Y1043994D02*
Y1030724D01*
G01Y1070024D02*
Y1057308D01*
G01X880397Y1046232D02*
Y1055132D01*
G01X900683Y1046232D02*
X880397D01*
G01Y1055132D02*
X900683D01*
G01X899391Y1070024D02*
X881689D01*
G01X893491Y1087763D02*
Y1089716D01*
G01X895444Y1087763D02*
X893491D01*
G01X894413Y1083987D02*
X892151Y1081725D01*
G01X890029Y1088371D02*
X894413Y1083987D01*
G01X887767Y1086109D02*
X890029Y1088371D01*
G01X892151Y1081725D02*
X887767Y1086109D01*
G01X895314Y1083364D02*
X901514D01*
G01X895314Y1080164D02*
Y1083364D01*
G01X901514Y1080164D02*
X895314D01*
G01X880320Y1085775D02*
Y1088975D01*
G01X886520Y1085775D02*
X880320D01*
G01X886520Y1088975D02*
Y1085775D01*
G01X880320Y1088975D02*
X886520D01*
G01X893491Y1099575D02*
X895444D01*
G01X893491Y1097622D02*
Y1099575D01*
G01X891981Y1104360D02*
Y1101160D01*
G01X885781Y1104360D02*
X891981D01*
G01X885781Y1101160D02*
Y1104360D01*
G01X891981Y1101160D02*
X885781D01*
G01X888990Y1094049D02*
X885790D01*
G01X888990Y1100249D02*
Y1094049D01*
G01X885790Y1100249D02*
X888990D01*
G01X885790Y1094049D02*
Y1100249D01*
G01X909668Y1122803D02*
Y1129930D01*
X891014D01*
X888014Y1126930D01*
Y1122803D01*
G01Y1115403D02*
Y1111276D01*
X891014Y1108276D01*
G01D02*
X909668D01*
Y1115403D01*
G01X910539Y1141395D02*
X892945D01*
G01X883975Y1200666D02*
Y1203866D01*
G01X890175Y1200666D02*
X883975D01*
G01X890175Y1203866D02*
Y1200666D01*
G01X883975Y1203866D02*
X890175D01*
G01X891014Y1199653D02*
Y1202853D01*
G01X897214Y1199653D02*
X891014D01*
G01Y1202853D02*
X897214D01*
G01X895827Y1204308D02*
Y1210508D01*
G01X899027Y1204308D02*
X895827D01*
G01X892945Y1195331D02*
X910539D01*
G01X882733Y1205137D02*
Y1202137D01*
G01X895827Y1210508D02*
X899027D01*
G01X898346Y1214267D02*
X895146D01*
G01Y1220467D02*
X898346D01*
G01X895146Y1214267D02*
Y1220467D01*
G01X893501Y1221112D02*
Y1224312D01*
G01X899701Y1221112D02*
X893501D01*
G01X886233Y1206766D02*
X890035D01*
Y1207037D01*
G01X891733Y1214837D02*
X893233D01*
G01X888940Y1233991D02*
X900940D01*
G01X888940Y1227991D02*
Y1233991D01*
G01X900940Y1227991D02*
X888940D01*
G01Y1234891D02*
Y1240891D01*
G01X900940Y1234891D02*
X888940D01*
G01X885940Y1239491D02*
Y1233491D01*
G01Y1232591D02*
Y1226591D01*
G01X893501Y1224312D02*
X899701D01*
G01X891908Y1223947D02*
X892117Y1224133D01*
X892200Y1224347D01*
X892117Y1224560D01*
X891867Y1224747D01*
X891492Y1224880D01*
X891117Y1224933D01*
X890658D01*
X890283Y1224880D01*
X889950Y1224747D01*
X889783Y1224587D01*
X889700Y1224400D01*
X889783Y1224187D01*
X889950Y1224027D01*
X890200Y1223920D01*
X890533Y1223867D01*
X890825Y1223920D01*
X891117Y1224053D01*
X891283Y1224213D01*
X891325Y1224400D01*
X891242Y1224613D01*
X891033Y1224773D01*
X890658Y1224933D01*
G01X890035Y1222637D02*
Y1222908D01*
G01D02*
X886233D01*
G01X885133Y1224537D02*
Y1227537D01*
G01X888815Y1249522D02*
Y1259522D01*
G01X893415D02*
Y1249522D01*
G01X888815D02*
X893415D01*
G01X888940Y1240891D02*
X900940D01*
G01X888940Y1247791D02*
X900940D01*
G01X888940Y1241791D02*
Y1247791D01*
G01X900940Y1241791D02*
X888940D01*
G01X885940Y1246391D02*
Y1240391D01*
G01Y1253291D02*
Y1247291D01*
G01X893315Y1259522D02*
X893415D01*
G01X888815D02*
X893415D01*
G01X887817Y1259051D02*
Y1255851D01*
G01X881617Y1259051D02*
X887817D01*
G01X881617Y1255851D02*
Y1259051D01*
G01X887817Y1255851D02*
X881617D01*
G01X882144Y1439259D02*
Y1442459D01*
G01X888344Y1439259D02*
X882144D01*
G01Y1442459D02*
X888344D01*
G01D02*
Y1439259D01*
G01X882144Y1443259D02*
Y1446459D01*
G01X888344Y1443259D02*
X882144D01*
G01Y1446459D02*
X888344D01*
G01D02*
Y1443259D01*
G01Y1447259D02*
X882144D01*
Y1450459D01*
X888344D01*
Y1447259D01*
G01X882144Y1462459D02*
X888344D01*
G01X893444Y1450559D02*
X890244D01*
G01D02*
Y1456759D01*
G01D02*
X893444D01*
G01D02*
Y1450559D01*
G01X882144Y1463259D02*
Y1466459D01*
G01X888344Y1463259D02*
X882144D01*
G01X888344Y1466459D02*
Y1463259D01*
G01X882144Y1459259D02*
Y1462459D01*
G01X888344Y1459259D02*
X882144D01*
G01X888344Y1462459D02*
Y1459259D01*
G01X888319Y1451063D02*
X882119D01*
Y1454263D01*
X888319D01*
Y1451063D01*
G01X882144Y1466459D02*
X888344D01*
G01X882144Y1475259D02*
Y1478459D01*
G01X888344Y1475259D02*
X882144D01*
G01Y1478459D02*
X888344D01*
G01D02*
Y1475259D01*
G01X882144Y1474459D02*
X888344D01*
G01X882144Y1471259D02*
Y1474459D01*
G01X888344Y1471259D02*
X882144D01*
G01X888344Y1474459D02*
Y1471259D01*
G01X882144Y1467259D02*
Y1470459D01*
G01X888344Y1467259D02*
X882144D01*
G01Y1470459D02*
X888344D01*
G01D02*
Y1467259D01*
G01X909762Y1590307D02*
X891252D01*
G01X884772D02*
X881252D01*
G01X882183Y1725786D02*
Y1723286D01*
X892183D01*
Y1723836D01*
G01Y1732736D02*
Y1733836D01*
G01X882183Y1735786D02*
Y1730786D01*
G01Y1743286D02*
Y1740786D01*
G01X881828Y1744486D02*
X883438Y1747586D01*
G01X881828D02*
X883438Y1744486D01*
G01X885005Y1745778D02*
X885273Y1746139D01*
X885503Y1746346D01*
X885810Y1746449D01*
X886078Y1746346D01*
X886270Y1746139D01*
X886423Y1745829D01*
X886461Y1745468D01*
X886423Y1745158D01*
X886270Y1744848D01*
X886040Y1744589D01*
X885771Y1744486D01*
X885465Y1744589D01*
X885196Y1744899D01*
X885043Y1745364D01*
X885005Y1745881D01*
X885081Y1746553D01*
X885196Y1746914D01*
X885388Y1747276D01*
X885656Y1747534D01*
X885925Y1747586D01*
X886193Y1747483D01*
X886385Y1747224D01*
G01X888756Y1744486D02*
X888833Y1745158D01*
X888948Y1745726D01*
X889101Y1746243D01*
X889293Y1746811D01*
X889600Y1747586D01*
X888066D01*
G01X892183Y1742736D02*
Y1743286D01*
X882183D01*
G01X881761Y1772938D02*
Y1770438D01*
X891761D01*
Y1770988D01*
G01Y1779888D02*
Y1780988D01*
G01X881761Y1782938D02*
Y1777938D01*
G01Y1790438D02*
Y1787938D01*
G01X881406Y1791638D02*
X883016Y1794738D01*
G01X881406D02*
X883016Y1791638D01*
G01X885234D02*
X885311Y1792310D01*
X885426Y1792878D01*
X885579Y1793395D01*
X885771Y1793963D01*
X886078Y1794738D01*
X884544D01*
G01X888411D02*
X888104Y1794635D01*
X887874Y1794376D01*
X887721Y1794066D01*
X887606Y1793653D01*
X887568Y1793188D01*
X887606Y1792723D01*
X887721Y1792310D01*
X887874Y1792000D01*
X888104Y1791741D01*
X888411Y1791638D01*
X888718Y1791741D01*
X888948Y1792000D01*
X889101Y1792310D01*
X889216Y1792723D01*
X889254Y1793188D01*
X889216Y1793653D01*
X889101Y1794066D01*
X888948Y1794376D01*
X888718Y1794635D01*
X888411Y1794738D01*
G01X891761Y1789888D02*
Y1790438D01*
X881761D01*
G01X914257Y116451D02*
X911157D01*
Y117371D01*
X911312Y117678D01*
X911674Y117908D01*
X912087Y117985D01*
X912500Y117908D01*
X912810Y117716D01*
X912965Y117371D01*
Y116451D01*
G01X911157Y119475D02*
X913379D01*
X913844Y119628D01*
X914154Y119935D01*
X914257Y120318D01*
X914154Y120701D01*
X913844Y121008D01*
X913379Y121161D01*
X911157D01*
G01X914257Y123418D02*
X911157D01*
X911777Y122958D01*
G01X914257D02*
Y123878D01*
G01X911674Y125790D02*
X911364Y126020D01*
X911209Y126288D01*
X911157Y126595D01*
X911260Y126978D01*
X911519Y127246D01*
X911829Y127323D01*
X912139Y127285D01*
X912397Y127131D01*
X912914Y126365D01*
X913275Y126020D01*
X913792Y125790D01*
X914257Y125713D01*
Y127323D01*
G01Y129541D02*
X913585Y129618D01*
X913017Y129733D01*
X912500Y129886D01*
X911932Y130078D01*
X911157Y130385D01*
Y128851D01*
G01X903690Y154138D02*
Y144690D01*
G01X901635Y142847D02*
Y139647D01*
G01X911297Y151368D02*
Y148168D01*
G01X905097D02*
Y151368D01*
G01X911297Y148168D02*
X905097D01*
G01Y144168D02*
Y147368D01*
G01X911297Y144168D02*
X905097D01*
G01X911297Y147368D02*
Y144168D01*
G01X905097Y147368D02*
X911297D01*
G01X912100Y134707D02*
X914322D01*
X914787Y134860D01*
X915097Y135167D01*
X915200Y135550D01*
X915097Y135933D01*
X914787Y136240D01*
X914322Y136393D01*
X912100D01*
G01X914580Y137807D02*
X914942Y138037D01*
X915148Y138343D01*
X915200Y138688D01*
X915148Y138995D01*
X914890Y139302D01*
X914580Y139493D01*
X914270Y139532D01*
X913908Y139455D01*
X913650Y139187D01*
X913547Y138918D01*
Y138573D01*
G01Y138918D02*
X913392Y139148D01*
X913133Y139340D01*
X912823Y139417D01*
X912513Y139340D01*
X912255Y139148D01*
X912100Y138803D01*
X912152Y138458D01*
X912358Y138113D01*
G01X914838Y141098D02*
X915097Y141367D01*
X915200Y141673D01*
X915097Y141980D01*
X914787Y142248D01*
X914322Y142440D01*
X913857Y142517D01*
X913288D01*
X912823Y142440D01*
X912410Y142248D01*
X912203Y142018D01*
X912100Y141750D01*
X912203Y141443D01*
X912410Y141213D01*
X912720Y141060D01*
X913133Y140983D01*
X913495Y141060D01*
X913857Y141252D01*
X914063Y141482D01*
X914115Y141750D01*
X914012Y142057D01*
X913753Y142287D01*
X913288Y142517D01*
G01X915200Y144850D02*
X912100D01*
X912720Y144390D01*
G01X915200D02*
Y145310D01*
G01X900272Y154138D02*
X903690D01*
G01X898272Y152414D02*
X900272Y154138D01*
G01X905097Y151368D02*
X911297D01*
G01X901741Y301501D02*
Y299279D01*
X901894Y298814D01*
X902201Y298504D01*
X902584Y298401D01*
X902967Y298504D01*
X903274Y298814D01*
X903427Y299279D01*
Y301501D01*
G01X905684Y298401D02*
Y301501D01*
X905224Y300881D01*
G01Y298401D02*
X906144D01*
G01X908784D02*
Y301501D01*
X908324Y300881D01*
G01Y298401D02*
X909244D01*
G01X911884Y301501D02*
X911577Y301398D01*
X911347Y301139D01*
X911194Y300829D01*
X911079Y300416D01*
X911041Y299951D01*
X911079Y299486D01*
X911194Y299073D01*
X911347Y298763D01*
X911577Y298504D01*
X911884Y298401D01*
X912191Y298504D01*
X912421Y298763D01*
X912574Y299073D01*
X912689Y299486D01*
X912727Y299951D01*
X912689Y300416D01*
X912574Y300829D01*
X912421Y301139D01*
X912191Y301398D01*
X911884Y301501D01*
G01X902639Y304638D02*
X902799Y304430D01*
X902986Y304305D01*
X903226Y304263D01*
X903466Y304346D01*
X903653Y304513D01*
X903786Y304805D01*
X903813Y305138D01*
X903759Y305471D01*
X903626Y305680D01*
X903439Y305846D01*
X903253Y305888D01*
X903066Y305846D01*
X902826Y305680D01*
X902906Y306763D01*
X903626D01*
G01X911931Y304800D02*
X912118Y304842D01*
X912331Y304967D01*
X912464Y305175D01*
X912518Y305467D01*
X912464Y305758D01*
X912304Y306008D01*
X912064Y306133D01*
X911798D01*
X911638Y306217D01*
X911504Y306425D01*
X911451Y306717D01*
X911531Y307008D01*
X911718Y307217D01*
X911931Y307300D01*
X912144Y307217D01*
X912331Y307008D01*
X912411Y306717D01*
X912358Y306425D01*
X912224Y306217D01*
X912064Y306133D01*
X911798D01*
X911558Y306008D01*
X911398Y305758D01*
X911344Y305467D01*
X911398Y305175D01*
X911531Y304967D01*
X911744Y304842D01*
X911931Y304800D01*
G01X904350Y308389D02*
Y308621D01*
G01X906011Y308389D02*
X904350D01*
G01X910846D02*
X909185D01*
G01X910846Y308621D02*
Y308389D01*
G01X902639Y314866D02*
X902799Y314574D01*
X903013Y314408D01*
X903253Y314366D01*
X903466Y314408D01*
X903679Y314616D01*
X903813Y314866D01*
X903839Y315116D01*
X903786Y315408D01*
X903599Y315616D01*
X903413Y315699D01*
X903173D01*
G01X903413D02*
X903573Y315824D01*
X903706Y316033D01*
X903759Y316283D01*
X903706Y316533D01*
X903573Y316741D01*
X903333Y316866D01*
X903093Y316824D01*
X902853Y316658D01*
G01X910007Y314832D02*
Y317332D01*
X909687Y316832D01*
G01Y314832D02*
X910327D01*
G01X912207Y317332D02*
X911994Y317249D01*
X911834Y317040D01*
X911727Y316790D01*
X911647Y316457D01*
X911620Y316082D01*
X911647Y315707D01*
X911727Y315374D01*
X911834Y315124D01*
X911994Y314915D01*
X912207Y314832D01*
X912420Y314915D01*
X912580Y315124D01*
X912687Y315374D01*
X912767Y315707D01*
X912794Y316082D01*
X912767Y316457D01*
X912687Y316790D01*
X912580Y317040D01*
X912420Y317249D01*
X912207Y317332D01*
G01X909185Y313703D02*
X910846D01*
G01X904350D02*
X906011D01*
G01X904350Y313471D02*
Y313703D01*
G01X910846D02*
Y313471D01*
G01X913698Y321702D02*
X910560D01*
Y324902D01*
X916760D01*
Y321702D01*
G01Y328002D02*
X910560D01*
Y331202D01*
X913664D01*
G01X903014Y338764D02*
X905214D01*
G01X909714D02*
X907546D01*
G01X906514Y344059D02*
Y339674D01*
G01X906214Y344059D02*
Y339674D01*
G01X903014Y338764D02*
Y344964D01*
G01X909714D02*
Y338764D01*
G01X903014Y344964D02*
X905124D01*
G01X909714D02*
X907535D01*
G01X907671Y352821D02*
X907421Y352981D01*
X907296Y353168D01*
X907254Y353381D01*
X907337Y353648D01*
X907546Y353835D01*
X907796Y353888D01*
X908046Y353861D01*
X908254Y353755D01*
X908671Y353221D01*
X908962Y352981D01*
X909379Y352821D01*
X909754Y352768D01*
Y353888D01*
G01Y355528D02*
X909712Y355715D01*
X909587Y355928D01*
X909379Y356061D01*
X909087Y356115D01*
X908796Y356061D01*
X908546Y355901D01*
X908421Y355661D01*
Y355395D01*
X908337Y355235D01*
X908129Y355101D01*
X907837Y355048D01*
X907546Y355128D01*
X907337Y355315D01*
X907254Y355528D01*
X907337Y355741D01*
X907546Y355928D01*
X907837Y356008D01*
X908129Y355955D01*
X908337Y355821D01*
X908421Y355661D01*
Y355395D01*
X908546Y355155D01*
X908796Y354995D01*
X909087Y354941D01*
X909379Y354995D01*
X909587Y355128D01*
X909712Y355341D01*
X909754Y355528D01*
G01X911500Y353411D02*
Y356254D01*
G01X914343Y353411D02*
X911500D01*
G01X897660Y356769D02*
Y359969D01*
G01X903860Y356769D02*
X897660D01*
G01X903860Y359969D02*
Y356769D01*
G01X897660Y359969D02*
X903860D01*
G01X897660Y352769D02*
Y355969D01*
G01X903860Y352769D02*
X897660D01*
G01X903860Y355969D02*
Y352769D01*
G01X897660Y355969D02*
X903860D01*
G01X907893Y370447D02*
X907643Y370607D01*
X907518Y370794D01*
X907476Y371007D01*
X907559Y371274D01*
X907768Y371461D01*
X908018Y371514D01*
X908268Y371487D01*
X908476Y371381D01*
X908893Y370847D01*
X909184Y370607D01*
X909601Y370447D01*
X909976Y370394D01*
Y371514D01*
G01X907893Y372647D02*
X907643Y372807D01*
X907518Y372994D01*
X907476Y373207D01*
X907559Y373474D01*
X907768Y373661D01*
X908018Y373714D01*
X908268Y373687D01*
X908476Y373581D01*
X908893Y373047D01*
X909184Y372807D01*
X909601Y372647D01*
X909976Y372594D01*
Y373714D01*
G01X914050Y375004D02*
X913890Y374754D01*
X913703Y374629D01*
X913490Y374587D01*
X913223Y374670D01*
X913036Y374879D01*
X912983Y375129D01*
X913010Y375379D01*
X913116Y375587D01*
X913650Y376004D01*
X913890Y376295D01*
X914050Y376712D01*
X914103Y377087D01*
X912983D01*
G01X911343D02*
Y374587D01*
X911663Y375087D01*
G01Y377087D02*
X911023D01*
G01X911500Y373097D02*
X914343D01*
G01X911500Y370254D02*
Y373097D01*
G01X909843Y363254D02*
X908343D01*
G01X903860Y363969D02*
Y360769D01*
G01X897660Y363969D02*
X903860D01*
G01X897660Y360769D02*
Y363969D01*
G01X903860Y360769D02*
X897660D01*
G01X903860Y371969D02*
Y368769D01*
G01X897660Y371969D02*
X903860D01*
G01X897660Y368769D02*
Y371969D01*
G01X903860Y368769D02*
X897660D01*
G01Y372769D02*
Y375969D01*
G01X903860Y372769D02*
X897660D01*
G01X903860Y375969D02*
Y372769D01*
G01X897660Y375969D02*
X903860D01*
G01X897660Y364769D02*
Y367969D01*
G01X903860Y364769D02*
X897660D01*
G01X903860Y367969D02*
Y364769D01*
G01X897660Y367969D02*
X903860D01*
G01X900371Y390108D02*
X915883D01*
G01X900371Y421200D02*
Y390108D01*
G01X909472Y386007D02*
X912672D01*
G01X909472Y379807D02*
Y386007D01*
G01X912672Y379807D02*
X909472D01*
G01X912672Y386007D02*
Y379807D01*
G01X899336Y390380D02*
Y384180D01*
G01X898179Y417643D02*
Y405643D01*
G01X915883Y421200D02*
X900371D01*
G01X900305Y438481D02*
Y422969D01*
G01D02*
X931397D01*
G01X898569Y438041D02*
Y426545D01*
G01X931397Y438481D02*
X900305D01*
G01X909359Y440154D02*
Y443354D01*
G01X915559Y440154D02*
X909359D01*
G01Y443354D02*
X915559D01*
G01X905573Y450278D02*
X908773D01*
G01X905573Y444078D02*
Y450278D01*
G01X908773Y444078D02*
X905573D01*
G01X908773Y450278D02*
Y444078D01*
G01X906000Y451183D02*
X902900D01*
Y452103D01*
X903055Y452410D01*
X903417Y452640D01*
X903830Y452717D01*
X904243Y452640D01*
X904553Y452448D01*
X904708Y452103D01*
Y451183D01*
G01X902900Y454207D02*
X905122D01*
X905587Y454360D01*
X905897Y454667D01*
X906000Y455050D01*
X905897Y455433D01*
X905587Y455740D01*
X905122Y455893D01*
X902900D01*
G01X906000Y458073D02*
X905328Y458150D01*
X904760Y458265D01*
X904243Y458418D01*
X903675Y458610D01*
X902900Y458917D01*
Y457383D01*
G01X906000Y461710D02*
X902900D01*
X905122Y460292D01*
Y462208D01*
G01X909949Y443935D02*
X909699Y444095D01*
X909574Y444282D01*
X909532Y444495D01*
X909615Y444762D01*
X909824Y444949D01*
X910074Y445002D01*
X910324Y444975D01*
X910532Y444869D01*
X910949Y444335D01*
X911240Y444095D01*
X911657Y443935D01*
X912032Y443882D01*
Y445002D01*
G01X909532Y446642D02*
X909615Y446429D01*
X909824Y446269D01*
X910074Y446162D01*
X910407Y446082D01*
X910782Y446055D01*
X911157Y446082D01*
X911490Y446162D01*
X911740Y446269D01*
X911949Y446429D01*
X912032Y446642D01*
X911949Y446855D01*
X911740Y447015D01*
X911490Y447122D01*
X911157Y447202D01*
X910782Y447229D01*
X910407Y447202D01*
X910074Y447122D01*
X909824Y447015D01*
X909615Y446855D01*
X909532Y446642D01*
G01X903799Y463342D02*
X899199D01*
G01X903799Y473542D02*
Y463342D01*
G01X899199Y473542D02*
X903799D01*
G01X899199Y463342D02*
Y473542D01*
G01X904699D02*
X909299D01*
G01X904699Y463342D02*
Y473542D01*
G01X909299Y463342D02*
X904699D01*
G01X909299Y473542D02*
Y463342D01*
G01X911899Y473242D02*
X918099D01*
G01X911899Y470042D02*
Y473242D01*
G01X918099Y470042D02*
X911899D01*
G01X898091Y466478D02*
Y460278D01*
G01X911899Y473842D02*
Y477042D01*
G01X918099Y473842D02*
X911899D01*
G01X909444Y459558D02*
X906944D01*
X907444Y459238D01*
G01X909444D02*
Y459878D01*
G01X907361Y461251D02*
X907111Y461411D01*
X906986Y461598D01*
X906944Y461811D01*
X907027Y462078D01*
X907236Y462265D01*
X907486Y462318D01*
X907736Y462291D01*
X907944Y462185D01*
X908361Y461651D01*
X908652Y461411D01*
X909069Y461251D01*
X909444Y461198D01*
Y462318D01*
G01X912978Y469465D02*
Y466965D01*
X913298Y467465D01*
G01Y469465D02*
X912658D01*
G01X910778D02*
Y466965D01*
X911098Y467465D01*
G01Y469465D02*
X910458D01*
G01X911899Y481042D02*
X918099D01*
G01X911899Y477842D02*
Y481042D01*
G01X918099Y477842D02*
X911899D01*
G01Y477042D02*
X918099D01*
G01X905031Y534968D02*
X901831D01*
G01X905031Y541168D02*
Y534968D01*
G01X901831D02*
Y541168D01*
G01X898331Y534968D02*
Y541168D01*
G01X901531Y534968D02*
X898331D01*
G01X901531Y541168D02*
Y534968D01*
G01X898031Y541168D02*
Y534968D01*
G01X897100Y531233D02*
Y528033D01*
G01X913350Y526600D02*
Y527995D01*
X912583Y529700D01*
G01X914117D02*
X913350Y527995D01*
G01X916373Y526600D02*
X916450Y527272D01*
X916565Y527840D01*
X916718Y528357D01*
X916910Y528925D01*
X917217Y529700D01*
X915683D01*
G01X908177Y530798D02*
Y542914D01*
G01X923429Y530798D02*
X908177D01*
G01X909053Y548948D02*
X915253D01*
G01X909053Y545748D02*
Y548948D01*
G01X915253Y545748D02*
X909053D01*
G01X901831Y541168D02*
X905031D01*
G01X898331D02*
X901531D01*
G01X908177Y542914D02*
X923429D01*
G01X914808Y617119D02*
X912630D01*
G01X907608D02*
X909772D01*
G01X910808Y611800D02*
Y616275D01*
G01X911608Y611800D02*
Y616275D01*
G01X914808Y610919D02*
X912551D01*
G01X907608D02*
X909931D01*
G01X905976Y617039D02*
X903690D01*
G01X898776D02*
X900962D01*
G01X901976Y611730D02*
Y616166D01*
G01X902776Y611730D02*
Y616166D01*
G01X905976Y610839D02*
X903840D01*
G01X898776D02*
X901002D01*
G01X897533Y617268D02*
Y611068D01*
G01X907608Y610919D02*
Y617119D01*
G01X905976Y617039D02*
Y610839D01*
G01X898776D02*
Y617039D01*
G01X911561Y685370D02*
Y682170D01*
G01X905361D02*
Y685370D01*
G01X911561Y682170D02*
X905361D01*
G01X902218Y684503D02*
X899978D01*
G01X901191Y682878D02*
Y686128D01*
G01X899491Y687203D02*
Y681603D01*
G01X911561Y697370D02*
Y694170D01*
G01X905361Y697370D02*
X911561D01*
G01X905361Y694170D02*
Y697370D01*
G01X911561Y694170D02*
X905361D01*
G01X911561Y701370D02*
Y698170D01*
G01X905361Y701370D02*
X911561D01*
G01X905361Y698170D02*
Y701370D01*
G01X911561Y698170D02*
X905361D01*
G01Y685370D02*
X911561D01*
G01X905361Y686170D02*
Y689370D01*
G01X911561Y686170D02*
X905361D01*
G01X911561Y689370D02*
Y686170D01*
G01X905361Y689370D02*
X911561D01*
G01X905361Y690170D02*
Y693370D01*
G01X911561Y690170D02*
X905361D01*
G01X911561Y693370D02*
Y690170D01*
G01X905361Y693370D02*
X911561D01*
G01X898984Y689788D02*
Y698450D01*
G01X906161Y717370D02*
Y720570D01*
G01X912361Y717370D02*
X906161D01*
G01X912361Y720570D02*
Y717370D01*
G01X905024Y703730D02*
Y715810D01*
G01X917498Y703730D02*
X905024D01*
G01Y715810D02*
X917498D01*
G01X903498Y725010D02*
Y712930D01*
G01X906161Y720570D02*
X912361D01*
G01X913907Y724107D02*
X911481D01*
G01X903736Y783444D02*
Y786544D01*
G01X905346D02*
Y783444D01*
G01Y784994D02*
X903736D01*
G01X906913Y784736D02*
X907181Y785097D01*
X907411Y785304D01*
X907718Y785407D01*
X907986Y785304D01*
X908178Y785097D01*
X908331Y784787D01*
X908369Y784426D01*
X908331Y784116D01*
X908178Y783806D01*
X907948Y783547D01*
X907679Y783444D01*
X907373Y783547D01*
X907104Y783857D01*
X906951Y784322D01*
X906913Y784839D01*
X906989Y785511D01*
X907104Y785872D01*
X907296Y786234D01*
X907564Y786492D01*
X907833Y786544D01*
X908101Y786441D01*
X908293Y786182D01*
G01X910089Y783806D02*
X910358Y783547D01*
X910664Y783444D01*
X910971Y783547D01*
X911239Y783857D01*
X911431Y784322D01*
X911508Y784787D01*
Y785356D01*
X911431Y785821D01*
X911239Y786234D01*
X911009Y786441D01*
X910741Y786544D01*
X910434Y786441D01*
X910204Y786234D01*
X910051Y785924D01*
X909974Y785511D01*
X910051Y785149D01*
X910243Y784787D01*
X910473Y784581D01*
X910741Y784529D01*
X911048Y784632D01*
X911278Y784891D01*
X911508Y785356D01*
G01X902316Y807990D02*
X905516D01*
G01X902316Y801790D02*
Y807990D01*
G01X905516Y801790D02*
X902316D01*
G01X905516Y807990D02*
Y801790D01*
G01X898316Y811940D02*
Y818140D01*
G01X901516Y811940D02*
X898316D01*
G01X901516Y818140D02*
Y811940D01*
G01X898316Y807990D02*
X901516D01*
G01X898316Y801790D02*
Y807990D01*
G01X901516Y801790D02*
X898316D01*
G01X901516Y807990D02*
Y801790D01*
G01X902316Y811940D02*
Y818140D01*
G01X905516Y811940D02*
X902316D01*
G01X905516Y818140D02*
Y811940D01*
G01X907816D02*
Y818140D01*
G01X911016Y811940D02*
X907816D01*
G01X911016Y818140D02*
Y811940D01*
G01X913016Y801790D02*
X909816D01*
G01Y807990D02*
X913016D01*
G01X909816Y801790D02*
Y807990D01*
G01X897516Y818140D02*
Y811940D01*
G01X898316Y818140D02*
X901516D01*
G01X902316D02*
X905516D01*
G01X907816D02*
X911016D01*
G01X898600Y908000D02*
Y914200D01*
G01X901800Y908000D02*
X898600D01*
G01X901800Y914200D02*
Y908000D01*
G01X905700D02*
Y914200D01*
G01X908900Y908000D02*
X905700D01*
G01X908900Y914200D02*
Y908000D01*
G01X902100D02*
Y914200D01*
G01X905300Y908000D02*
X902100D01*
G01X905300Y914200D02*
Y908000D01*
G01X912500Y907900D02*
X909300D01*
G01D02*
Y914100D01*
G01X912500D02*
Y907900D01*
G01X898228Y914189D02*
Y907989D01*
G01X898600Y914200D02*
X901800D01*
G01X905700D02*
X908900D01*
G01X902100D02*
X905300D01*
G01X909300Y914100D02*
X912500D01*
G01X911028Y927226D02*
X914228D01*
G01X911028Y921026D02*
Y927226D01*
G01X914228Y921026D02*
X911028D01*
G01X899351Y951135D02*
Y938135D01*
G01X902457Y942213D02*
X905657D01*
G01X902457Y936013D02*
Y942213D01*
G01X905657Y936013D02*
X902457D01*
G01X905657Y942213D02*
Y936013D01*
G01X902234Y947007D02*
Y950207D01*
G01X908434Y947007D02*
X902234D01*
G01X908434Y950207D02*
Y947007D01*
G01X902234Y950207D02*
X908434D01*
G01X907728Y954490D02*
X904528D01*
G01X907728Y960690D02*
Y954490D01*
G01X904528Y960690D02*
X907728D01*
G01X904528Y954490D02*
Y960690D01*
G01X903021Y1005830D02*
Y995630D01*
X898421D01*
Y1005830D01*
X903021D01*
G01X916051Y1006830D02*
Y996630D01*
X911451D01*
Y1006830D01*
X916051D01*
G01X910953Y995791D02*
X904953D01*
Y1007791D01*
X910953D01*
Y995791D01*
G01X907855Y1020381D02*
Y1014181D01*
X904655D01*
Y1020381D01*
X907855D01*
G01X903825Y1020328D02*
Y1014128D01*
X900625D01*
Y1020328D01*
X903825D01*
G01X899391Y1030724D02*
Y1044557D01*
G01Y1057395D02*
Y1070024D01*
G01X900683Y1055132D02*
Y1046232D01*
G01X905631Y1071526D02*
Y1069304D01*
X905784Y1068839D01*
X906091Y1068529D01*
X906474Y1068426D01*
X906857Y1068529D01*
X907164Y1068839D01*
X907317Y1069304D01*
Y1071526D01*
G01X908922Y1068788D02*
X909191Y1068529D01*
X909497Y1068426D01*
X909804Y1068529D01*
X910072Y1068839D01*
X910264Y1069304D01*
X910341Y1069769D01*
Y1070338D01*
X910264Y1070803D01*
X910072Y1071216D01*
X909842Y1071423D01*
X909574Y1071526D01*
X909267Y1071423D01*
X909037Y1071216D01*
X908884Y1070906D01*
X908807Y1070493D01*
X908884Y1070131D01*
X909076Y1069769D01*
X909306Y1069563D01*
X909574Y1069511D01*
X909881Y1069614D01*
X910111Y1069873D01*
X910341Y1070338D01*
G01X912674Y1071526D02*
X912367Y1071423D01*
X912137Y1071164D01*
X911984Y1070854D01*
X911869Y1070441D01*
X911831Y1069976D01*
X911869Y1069511D01*
X911984Y1069098D01*
X912137Y1068788D01*
X912367Y1068529D01*
X912674Y1068426D01*
X912981Y1068529D01*
X913211Y1068788D01*
X913364Y1069098D01*
X913479Y1069511D01*
X913517Y1069976D01*
X913479Y1070441D01*
X913364Y1070854D01*
X913211Y1071164D01*
X912981Y1071423D01*
X912674Y1071526D01*
G01X909674Y1075059D02*
Y1078259D01*
G01X915874Y1075059D02*
X909674D01*
G01X905303Y1087763D02*
X903350D01*
G01X905303Y1089716D02*
Y1087763D01*
G01X909674Y1078259D02*
X915874D01*
G01X909674Y1079059D02*
Y1082259D01*
G01X915874Y1079059D02*
X909674D01*
G01Y1082259D02*
X915874D01*
G01X909674Y1083059D02*
Y1086259D01*
G01X915874Y1083059D02*
X909674D01*
G01Y1086259D02*
X915874D01*
G01X909674Y1087059D02*
Y1090259D01*
G01X915874Y1087059D02*
X909674D01*
G01Y1090259D02*
X915874D01*
G01X909674Y1091059D02*
Y1094259D01*
G01X915874Y1091059D02*
X909674D01*
G01X901514Y1083364D02*
Y1080164D01*
G01X905303Y1099575D02*
Y1097622D01*
G01X903350Y1099575D02*
X905303D01*
G01X909674Y1094259D02*
X915874D01*
G01X909674Y1106259D02*
X915874D01*
G01X909674Y1103059D02*
Y1106259D01*
G01X915874Y1103059D02*
X909674D01*
G01Y1102259D02*
X915874D01*
G01X909674Y1099059D02*
Y1102259D01*
G01X915874Y1099059D02*
X909674D01*
G01Y1095059D02*
Y1098259D01*
G01X915874Y1095059D02*
X909674D01*
G01Y1098259D02*
X915874D01*
G01X896753Y1132326D02*
Y1135526D01*
G01X902953Y1132326D02*
X896753D01*
G01X902953Y1135526D02*
Y1132326D01*
G01X896753Y1135526D02*
X902953D01*
G01X910539Y1195331D02*
Y1141395D01*
G01X915696Y1182906D02*
X912596D01*
Y1183826D01*
X912751Y1184133D01*
X913113Y1184363D01*
X913526Y1184440D01*
X913939Y1184363D01*
X914249Y1184171D01*
X914404Y1183826D01*
Y1182906D01*
G01X912596Y1186006D02*
X915696D01*
Y1187540D01*
G01X913113Y1189145D02*
X912803Y1189375D01*
X912648Y1189643D01*
X912596Y1189950D01*
X912699Y1190333D01*
X912958Y1190601D01*
X913268Y1190678D01*
X913578Y1190640D01*
X913836Y1190486D01*
X914353Y1189720D01*
X914714Y1189375D01*
X915231Y1189145D01*
X915696Y1189068D01*
Y1190678D01*
G01X912596Y1192973D02*
X912699Y1192666D01*
X912958Y1192436D01*
X913268Y1192283D01*
X913681Y1192168D01*
X914146Y1192130D01*
X914611Y1192168D01*
X915024Y1192283D01*
X915334Y1192436D01*
X915593Y1192666D01*
X915696Y1192973D01*
X915593Y1193280D01*
X915334Y1193510D01*
X915024Y1193663D01*
X914611Y1193778D01*
X914146Y1193816D01*
X913681Y1193778D01*
X913268Y1193663D01*
X912958Y1193510D01*
X912699Y1193280D01*
X912596Y1192973D01*
G01X899792Y1203148D02*
Y1209348D01*
G01X902992Y1203148D02*
X899792D01*
G01X902992Y1209348D02*
Y1203148D01*
G01X897214Y1202853D02*
Y1199653D01*
G01X899027Y1210508D02*
Y1204308D01*
G01X899792Y1209348D02*
X902992D01*
G01X900375Y1217123D02*
Y1220323D01*
G01X906575Y1217123D02*
X900375D01*
G01X906575Y1220323D02*
Y1217123D01*
G01X900375Y1220323D02*
X906575D01*
G01X902843Y1210138D02*
X899643D01*
G01X902843Y1216338D02*
Y1210138D01*
G01X899643Y1216338D02*
X902843D01*
G01X899643Y1210138D02*
Y1216338D01*
G01X903470Y1216074D02*
X906670D01*
G01X903470Y1209874D02*
Y1216074D01*
G01X906670Y1209874D02*
X903470D01*
G01X906670Y1216074D02*
Y1209874D01*
G01X906575Y1224323D02*
Y1221123D01*
G01X900375D02*
Y1224323D01*
G01X906575Y1221123D02*
X900375D01*
G01X898346Y1220467D02*
Y1214267D01*
G01X899701Y1224312D02*
Y1221112D01*
G01X900940Y1233991D02*
Y1227991D01*
G01Y1240891D02*
Y1234891D01*
G01X900375Y1224323D02*
X906575D01*
G01X910452Y1223408D02*
X907252D01*
G01X910452Y1229608D02*
Y1223408D01*
G01X907252Y1229608D02*
X910452D01*
G01X907252Y1223408D02*
Y1229608D01*
G01X914326Y1223408D02*
X911126D01*
G01Y1229608D02*
X914326D01*
G01X911126Y1223408D02*
Y1229608D01*
G01X900940Y1247791D02*
Y1241791D01*
G01X896562Y1462698D02*
Y1442480D01*
G01D02*
X916780D01*
G01Y1462698D02*
X896562D01*
G01X906495Y1579537D02*
Y1587037D01*
X908735D01*
X909482Y1586662D01*
X910042Y1585787D01*
X910229Y1584787D01*
X910042Y1583787D01*
X909575Y1583037D01*
X908735Y1582662D01*
X906495D01*
G01X913995Y1579537D02*
Y1587037D01*
X916329D01*
X917075Y1586662D01*
X917542Y1586162D01*
X917729Y1585162D01*
X917542Y1584162D01*
X916982Y1583537D01*
X916329Y1583162D01*
X913995D01*
G01X916329D02*
X917729Y1579537D01*
G01X925229D02*
X921495D01*
Y1587037D01*
X925229D01*
G01X923735Y1583412D02*
X921495D01*
G01X928902Y1580537D02*
X929649Y1579912D01*
X930489Y1579537D01*
X931235D01*
X931982Y1579912D01*
X932542Y1580537D01*
X932822Y1581412D01*
X932635Y1582287D01*
X932169Y1583037D01*
X931329Y1583537D01*
X930209Y1583787D01*
X929555Y1584287D01*
X929275Y1585162D01*
X929462Y1586037D01*
X929929Y1586662D01*
X930582Y1587037D01*
X931235D01*
X931889Y1586787D01*
X932449Y1586162D01*
G01X936402Y1580537D02*
X937149Y1579912D01*
X937989Y1579537D01*
X938735D01*
X939482Y1579912D01*
X940042Y1580537D01*
X940322Y1581412D01*
X940135Y1582287D01*
X939669Y1583037D01*
X938829Y1583537D01*
X937709Y1583787D01*
X937055Y1584287D01*
X936775Y1585162D01*
X936962Y1586037D01*
X937429Y1586662D01*
X938082Y1587037D01*
X938735D01*
X939389Y1586787D01*
X939949Y1586162D01*
G01X944649Y1582037D02*
X947075D01*
G01X951589Y1579537D02*
Y1587037D01*
X955135D01*
G01X953829Y1583412D02*
X951589D01*
G01X959742Y1587037D02*
X961982D01*
G01X960862D02*
Y1579537D01*
G01X959742D02*
X961982D01*
G01X968362Y1587037D02*
Y1579537D01*
G01X966215Y1587037D02*
X970509D01*
G01X917634Y1722790D02*
X916024Y1719690D01*
G01X917634D02*
X916024Y1722790D01*
G01X913806D02*
X913729Y1722118D01*
X913614Y1721550D01*
X913461Y1721033D01*
X913269Y1720465D01*
X912962Y1719690D01*
X914496D01*
G01X911472Y1722170D02*
X911242Y1722532D01*
X910936Y1722738D01*
X910591Y1722790D01*
X910284Y1722738D01*
X909977Y1722480D01*
X909786Y1722170D01*
X909747Y1721860D01*
X909824Y1721498D01*
X910092Y1721240D01*
X910361Y1721137D01*
X910706D01*
G01X910361D02*
X910131Y1720982D01*
X909939Y1720723D01*
X909862Y1720413D01*
X909939Y1720103D01*
X910131Y1719845D01*
X910476Y1719690D01*
X910821Y1719742D01*
X911166Y1719948D01*
G01X907279Y1724540D02*
Y1723990D01*
X917279D01*
G01X907279Y1734540D02*
Y1733440D01*
G01X917279Y1741490D02*
Y1743990D01*
X907279D01*
Y1743440D01*
G01X917428Y1769814D02*
X915818Y1766714D01*
G01X917428D02*
X915818Y1769814D01*
G01X914251Y1768522D02*
X913983Y1768161D01*
X913753Y1767954D01*
X913446Y1767851D01*
X913178Y1767954D01*
X912986Y1768161D01*
X912833Y1768471D01*
X912795Y1768832D01*
X912833Y1769142D01*
X912986Y1769452D01*
X913216Y1769711D01*
X913485Y1769814D01*
X913791Y1769711D01*
X914060Y1769401D01*
X914213Y1768936D01*
X914251Y1768419D01*
X914175Y1767747D01*
X914060Y1767386D01*
X913868Y1767024D01*
X913600Y1766766D01*
X913331Y1766714D01*
X913063Y1766817D01*
X912871Y1767076D01*
G01X910423Y1769814D02*
X910155Y1769762D01*
X909848Y1769607D01*
X909656Y1769349D01*
X909580Y1768987D01*
X909656Y1768626D01*
X909886Y1768316D01*
X910231Y1768161D01*
X910615D01*
X910845Y1768057D01*
X911036Y1767799D01*
X911113Y1767437D01*
X910998Y1767076D01*
X910730Y1766817D01*
X910423Y1766714D01*
X910116Y1766817D01*
X909848Y1767076D01*
X909733Y1767437D01*
X909810Y1767799D01*
X910001Y1768057D01*
X910231Y1768161D01*
X910615D01*
X910960Y1768316D01*
X911190Y1768626D01*
X911266Y1768987D01*
X911190Y1769349D01*
X910998Y1769607D01*
X910691Y1769762D01*
X910423Y1769814D01*
G01X907073Y1771564D02*
Y1771014D01*
X917073D01*
G01X907073Y1781564D02*
Y1780464D01*
G01X917073Y1788514D02*
Y1791014D01*
X907073D01*
Y1790464D01*
G01X914873Y111951D02*
Y118151D01*
G01X918073Y111951D02*
X914873D01*
G01X918073Y118151D02*
Y111951D01*
G01X925793Y109424D02*
X928993D01*
G01X925793Y103224D02*
Y109424D01*
G01X928993Y103224D02*
X925793D01*
G01X928993Y109424D02*
Y103224D01*
G01X921793Y109424D02*
X924993D01*
G01X921793Y103224D02*
Y109424D01*
G01X924993Y103224D02*
X921793D01*
G01X924993Y109424D02*
Y103224D01*
G01X920247Y111734D02*
Y123508D01*
G01X930009Y111734D02*
X920247D01*
G01X914873Y118151D02*
X918073D01*
G01X931018Y126223D02*
X927818D01*
G01Y132423D02*
X931018D01*
G01X927818Y126223D02*
Y132423D01*
G01X923018Y126223D02*
X919818D01*
G01X923018Y132423D02*
Y126223D01*
G01X919818Y132423D02*
X923018D01*
G01X919818Y126223D02*
Y132423D01*
G01X923818D02*
X927018D01*
G01X923818Y126223D02*
Y132423D01*
G01X927018Y126223D02*
X923818D01*
G01X927018Y132423D02*
Y126223D01*
G01X920247Y123508D02*
X930009D01*
G01X920207Y146229D02*
X917007D01*
G01X920207Y152429D02*
Y146229D01*
G01X917007D02*
Y152429D01*
G01X918697Y144395D02*
Y135095D01*
G01X929297Y144395D02*
X918697D01*
G01Y134995D02*
X929297D01*
G01X917007Y152429D02*
X920207D01*
G01X917007Y159540D02*
X920207D01*
G01X917007Y153340D02*
Y159540D01*
G01X920207Y153340D02*
X917007D01*
G01X920207Y159540D02*
Y153340D01*
G01X926920Y149950D02*
Y165304D01*
G01X939598Y149950D02*
X926920D01*
G01X927117Y165304D02*
X939598D01*
G01X920467Y174606D02*
X922707D01*
G01X921494Y176231D02*
Y172981D01*
G01X924108Y180754D02*
X953667D01*
G01X924108Y169258D02*
Y180754D01*
G01X953667Y169258D02*
X924108D01*
G01X924261Y189677D02*
Y201677D01*
G01X930261Y189677D02*
X924261D01*
G01Y201677D02*
X930261D01*
G01X929383Y220669D02*
X929191Y220979D01*
X928961Y221186D01*
X928693Y221289D01*
X928386Y221186D01*
X928156Y220979D01*
X927926Y220669D01*
X927849Y220256D01*
Y218189D01*
G01X926244Y218706D02*
X926014Y218396D01*
X925746Y218241D01*
X925439Y218189D01*
X925056Y218292D01*
X924788Y218551D01*
X924711Y218861D01*
X924749Y219171D01*
X924903Y219429D01*
X925669Y219946D01*
X926014Y220307D01*
X926244Y220824D01*
X926321Y221289D01*
X924711D01*
G01X923829Y275856D02*
Y229656D01*
G01X926052Y306855D02*
X932252D01*
G01X926052Y303655D02*
Y306855D01*
G01X932252Y303655D02*
X926052D01*
G01X915467Y309385D02*
Y312585D01*
G01X921667Y309385D02*
X915467D01*
G01X921667Y312585D02*
Y309385D01*
G01X921445Y306185D02*
Y302985D01*
G01X915245Y306185D02*
X921445D01*
G01X915245Y302985D02*
Y306185D01*
G01X921445Y302985D02*
X915245D01*
G01X915467Y312585D02*
X921667D01*
G01X919227Y324902D02*
X925427D01*
Y321702D01*
X922345D01*
G01X919227D02*
Y324902D01*
G01X916760Y331202D02*
Y328002D01*
G01X913635Y321777D02*
Y327977D01*
X916835D01*
G01Y324905D02*
Y321777D01*
G01X913635Y324927D02*
Y331127D01*
G01X916835Y324927D02*
X913635D01*
G01X922352Y331127D02*
Y324927D01*
X919152D01*
G01Y327965D02*
Y331127D01*
G01Y321777D02*
Y324889D01*
G01Y327977D02*
X922352D01*
Y321777D01*
G01X922237Y331202D02*
X925427D01*
Y328002D01*
X919227D01*
Y331202D01*
G01X916835Y331127D02*
Y328065D01*
G01X928496Y351987D02*
X928443Y351445D01*
X928363Y350987D01*
X928256Y350570D01*
X928123Y350112D01*
X927910Y349487D01*
X928976D01*
G01X931186Y353411D02*
X928343D01*
G01X923343Y351754D02*
Y350254D01*
G01X931243Y377187D02*
Y374687D01*
X931563Y375187D01*
G01Y377187D02*
X930923D01*
G01X929630Y376812D02*
X929470Y377020D01*
X929283Y377145D01*
X929043Y377187D01*
X928803Y377104D01*
X928616Y376937D01*
X928483Y376645D01*
X928456Y376312D01*
X928510Y375979D01*
X928643Y375770D01*
X928830Y375604D01*
X929016Y375562D01*
X929203Y375604D01*
X929443Y375770D01*
X929363Y374687D01*
X928643D01*
G01X928343Y373097D02*
X931186D01*
G01X927343Y374754D02*
Y376254D01*
G01X917343Y374754D02*
Y377754D01*
G01X920200Y390583D02*
X917100D01*
Y391503D01*
X917255Y391810D01*
X917617Y392040D01*
X918030Y392117D01*
X918443Y392040D01*
X918753Y391848D01*
X918908Y391503D01*
Y390583D01*
G01X920200Y393607D02*
X917100D01*
Y394373D01*
X917255Y394680D01*
X917462Y394910D01*
X917772Y395102D01*
X918133Y395255D01*
X918650Y395293D01*
X919167Y395255D01*
X919528Y395102D01*
X919838Y394910D01*
X920045Y394680D01*
X920200Y394373D01*
Y393607D01*
G01Y397550D02*
X920148Y397818D01*
X919993Y398125D01*
X919735Y398317D01*
X919373Y398393D01*
X919012Y398317D01*
X918702Y398087D01*
X918547Y397742D01*
Y397358D01*
X918443Y397128D01*
X918185Y396937D01*
X917823Y396860D01*
X917462Y396975D01*
X917203Y397243D01*
X917100Y397550D01*
X917203Y397857D01*
X917462Y398125D01*
X917823Y398240D01*
X918185Y398163D01*
X918443Y397972D01*
X918547Y397742D01*
Y397358D01*
X918702Y397013D01*
X919012Y396783D01*
X919373Y396707D01*
X919735Y396783D01*
X919993Y396975D01*
X920148Y397282D01*
X920200Y397550D01*
G01X915883Y390108D02*
Y421200D01*
G01X928672Y379807D02*
X925472D01*
G01X928672Y386007D02*
Y379807D01*
G01X925472Y386007D02*
X928672D01*
G01X925472Y379807D02*
Y386007D01*
G01X913472D02*
X916672D01*
G01X913472Y379807D02*
Y386007D01*
G01X916672Y379807D02*
X913472D01*
G01X916672Y386007D02*
Y379807D01*
G01X924672D02*
X921472D01*
G01X924672Y386007D02*
Y379807D01*
G01X921472Y386007D02*
X924672D01*
G01X921472Y379807D02*
Y386007D01*
G01X920672Y379807D02*
X917472D01*
G01X920672Y386007D02*
Y379807D01*
G01X917472Y386007D02*
X920672D01*
G01X917472Y379807D02*
Y386007D01*
G01X920383Y418600D02*
Y421700D01*
X921303D01*
X921610Y421545D01*
X921840Y421183D01*
X921917Y420770D01*
X921840Y420357D01*
X921648Y420047D01*
X921303Y419892D01*
X920383D01*
G01X923407Y418600D02*
Y421700D01*
X924173D01*
X924480Y421545D01*
X924710Y421338D01*
X924902Y421028D01*
X925055Y420667D01*
X925093Y420150D01*
X925055Y419633D01*
X924902Y419272D01*
X924710Y418962D01*
X924480Y418755D01*
X924173Y418600D01*
X923407D01*
G01X927350D02*
X927618Y418652D01*
X927925Y418807D01*
X928117Y419065D01*
X928193Y419427D01*
X928117Y419788D01*
X927887Y420098D01*
X927542Y420253D01*
X927158D01*
X926928Y420357D01*
X926737Y420615D01*
X926660Y420977D01*
X926775Y421338D01*
X927043Y421597D01*
X927350Y421700D01*
X927657Y421597D01*
X927925Y421338D01*
X928040Y420977D01*
X927963Y420615D01*
X927772Y420357D01*
X927542Y420253D01*
X927158D01*
X926813Y420098D01*
X926583Y419788D01*
X926507Y419427D01*
X926583Y419065D01*
X926775Y418807D01*
X927082Y418652D01*
X927350Y418600D01*
G01X930450Y421700D02*
X930143Y421597D01*
X929913Y421338D01*
X929760Y421028D01*
X929645Y420615D01*
X929607Y420150D01*
X929645Y419685D01*
X929760Y419272D01*
X929913Y418962D01*
X930143Y418703D01*
X930450Y418600D01*
X930757Y418703D01*
X930987Y418962D01*
X931140Y419272D01*
X931255Y419685D01*
X931293Y420150D01*
X931255Y420615D01*
X931140Y421028D01*
X930987Y421338D01*
X930757Y421597D01*
X930450Y421700D01*
G01X915559Y443354D02*
Y440154D01*
G01X917028Y443566D02*
X917188Y443816D01*
X917375Y443941D01*
X917588Y443983D01*
X917855Y443900D01*
X918042Y443691D01*
X918095Y443441D01*
X918068Y443191D01*
X917962Y442983D01*
X917428Y442566D01*
X917188Y442275D01*
X917028Y441858D01*
X916975Y441483D01*
X918095D01*
G01X919735D02*
Y443983D01*
X919415Y443483D01*
G01Y441483D02*
X920055D01*
G01X921135Y440650D02*
X922735D01*
G01X923628Y443566D02*
X923788Y443816D01*
X923975Y443941D01*
X924188Y443983D01*
X924455Y443900D01*
X924642Y443691D01*
X924695Y443441D01*
X924668Y443191D01*
X924562Y442983D01*
X924028Y442566D01*
X923788Y442275D01*
X923628Y441858D01*
X923575Y441483D01*
X924695D01*
G01X925828Y443566D02*
X925988Y443816D01*
X926175Y443941D01*
X926388Y443983D01*
X926655Y443900D01*
X926842Y443691D01*
X926895Y443441D01*
X926868Y443191D01*
X926762Y442983D01*
X926228Y442566D01*
X925988Y442275D01*
X925828Y441858D01*
X925775Y441483D01*
X926895D01*
G01X918049Y446403D02*
X919949D01*
G01X912897Y447568D02*
Y446403D01*
G01X925101D02*
Y447576D01*
G01X921960Y446403D02*
X925101D01*
G01X912897D02*
X916038D01*
G01X918099Y473242D02*
Y470042D01*
G01Y477042D02*
Y473842D01*
G01X926599Y470842D02*
X923399D01*
G01X926599Y477042D02*
Y470842D01*
G01X923399D02*
Y477042D01*
G01X930599Y470842D02*
X927399D01*
G01D02*
Y477042D01*
G01X919399Y470842D02*
Y477042D01*
G01X922599Y470842D02*
X919399D01*
G01X922599Y477042D02*
Y470842D01*
G01X925699Y470375D02*
Y467875D01*
X926019Y468375D01*
G01Y470375D02*
X925379D01*
G01X923499Y467875D02*
X923712Y467958D01*
X923872Y468167D01*
X923979Y468417D01*
X924059Y468750D01*
X924086Y469125D01*
X924059Y469500D01*
X923979Y469833D01*
X923872Y470083D01*
X923712Y470292D01*
X923499Y470375D01*
X923286Y470292D01*
X923126Y470083D01*
X923019Y469833D01*
X922939Y469500D01*
X922912Y469125D01*
X922939Y468750D01*
X923019Y468417D01*
X923126Y468167D01*
X923286Y467958D01*
X923499Y467875D01*
G01X929040Y466189D02*
X929249Y466375D01*
X929332Y466589D01*
X929249Y466802D01*
X928999Y466989D01*
X928624Y467122D01*
X928249Y467175D01*
X927790D01*
X927415Y467122D01*
X927082Y466989D01*
X926915Y466829D01*
X926832Y466642D01*
X926915Y466429D01*
X927082Y466269D01*
X927332Y466162D01*
X927665Y466109D01*
X927957Y466162D01*
X928249Y466295D01*
X928415Y466455D01*
X928457Y466642D01*
X928374Y466855D01*
X928165Y467015D01*
X927790Y467175D01*
G01X912897Y466481D02*
Y465316D01*
G01X916031Y466481D02*
X912897D01*
G01X919967D02*
X918031D01*
G01X925101D02*
X921967D01*
G01X925101Y465316D02*
Y466481D01*
G01X917376Y487741D02*
X917568Y487431D01*
X917798Y487224D01*
X918066Y487121D01*
X918373Y487224D01*
X918603Y487431D01*
X918833Y487741D01*
X918910Y488154D01*
Y490221D01*
G01X921703Y487121D02*
Y490221D01*
X920285Y487999D01*
X922201D01*
G01X918099Y481042D02*
Y477842D01*
G01X923399Y477042D02*
X926599D01*
G01X927399D02*
X930599D01*
G01X919399D02*
X922599D01*
G01X926547Y491429D02*
X916547D01*
G01D02*
Y503379D01*
G01X926547Y493379D02*
Y491429D01*
G01Y513379D02*
Y499479D01*
G01X916547Y509479D02*
Y521429D01*
G01D02*
X926547D01*
G01D02*
Y519479D01*
G01X923429Y542914D02*
Y530798D01*
G01X916286Y545748D02*
Y548948D01*
G01X922486Y545748D02*
X916286D01*
G01X922486Y548948D02*
Y545748D01*
G01X916286Y548948D02*
X922486D01*
G01X915253D02*
Y545748D01*
G01X918850Y550020D02*
X915650D01*
G01X918850Y556220D02*
Y550020D01*
G01X915650D02*
Y556220D01*
G01X924552Y556041D02*
Y559241D01*
G01X930752Y556041D02*
X924552D01*
G01Y559241D02*
X930752D01*
G01X915650Y556220D02*
X918850D01*
G01X924552Y563178D02*
X930752D01*
G01X924552Y559978D02*
Y563178D01*
G01X930752Y559978D02*
X924552D01*
G01Y567178D02*
X930752D01*
G01X924552Y563978D02*
Y567178D01*
G01X930752Y563978D02*
X924552D01*
G01Y567978D02*
Y571178D01*
G01X930752Y567978D02*
X924552D01*
G01Y571178D02*
X930752D01*
G01X915736Y563545D02*
Y565593D01*
G01X913688Y563545D02*
X915736D01*
G01X925351Y587178D02*
X929896D01*
G01X924536Y583978D02*
Y586170D01*
G01X924552Y571978D02*
Y575178D01*
G01X930752Y571978D02*
X924552D01*
G01Y575178D02*
X930752D01*
G01X930736Y583978D02*
X924536D01*
G01X924552Y575978D02*
Y579178D01*
G01X930752Y575978D02*
X924552D01*
G01Y579178D02*
X930752D01*
G01X924552Y579978D02*
Y583178D01*
G01X930752Y579978D02*
X924552D01*
G01Y583178D02*
X930752D01*
G01X925351Y587978D02*
X929896D01*
G01X924536Y591178D02*
Y589037D01*
G01X925371Y596729D02*
X929836D01*
G01X925371Y595929D02*
X929836D01*
G01X924552Y592729D02*
Y594941D01*
G01Y599929D02*
Y597719D01*
G01X924536Y591178D02*
X930736D01*
G01X930752Y592729D02*
X924552D01*
G01Y599929D02*
X930752D01*
G01X915736Y595041D02*
X913688D01*
G01X915736Y592993D02*
Y595041D01*
G01X914808Y617119D02*
Y610919D01*
G01X922172Y683960D02*
Y700160D01*
G01X935172Y683960D02*
X922172D01*
G01X923818Y682470D02*
X927018D01*
G01X923818Y676270D02*
Y682470D01*
G01X927018Y676270D02*
X923818D01*
G01X927018Y682470D02*
Y676270D01*
G01X919818Y682470D02*
X923018D01*
G01X919818Y676270D02*
Y682470D01*
G01X923018Y676270D02*
X919818D01*
G01X923018Y682470D02*
Y676270D01*
G01X922172Y700160D02*
X935172D01*
G01X925550Y705711D02*
Y702511D01*
G01X919350Y705711D02*
X925550D01*
G01X919350Y702511D02*
Y705711D01*
G01X925550Y702511D02*
X919350D01*
G01X919461Y714445D02*
X922661D01*
G01X919461Y708245D02*
Y714445D01*
G01X922661Y708245D02*
X919461D01*
G01X922661Y714445D02*
Y708245D01*
G01X923461Y714445D02*
X926661D01*
G01X923461Y708245D02*
Y714445D01*
G01X926661Y708245D02*
X923461D01*
G01X926661Y714445D02*
Y708245D01*
G01X932149Y717343D02*
X929909D01*
G01X931122Y715718D02*
Y718968D01*
G01X914661Y717770D02*
Y723370D01*
G01X929161Y717770D02*
X914661D01*
G01X917498Y715810D02*
Y703730D01*
G01X917746Y725481D02*
Y728581D01*
X918512D01*
X918819Y728426D01*
X919049Y728219D01*
X919241Y727909D01*
X919394Y727548D01*
X919432Y727031D01*
X919394Y726514D01*
X919241Y726153D01*
X919049Y725843D01*
X918819Y725636D01*
X918512Y725481D01*
X917746D01*
G01X921689D02*
Y728581D01*
X921229Y727961D01*
G01Y725481D02*
X922149D01*
G01X924061Y728064D02*
X924291Y728374D01*
X924559Y728529D01*
X924866Y728581D01*
X925249Y728478D01*
X925517Y728219D01*
X925594Y727909D01*
X925556Y727599D01*
X925402Y727341D01*
X924636Y726824D01*
X924291Y726463D01*
X924061Y725946D01*
X923984Y725481D01*
X925594D01*
G01X921480Y718601D02*
Y722539D01*
G01X921874Y720570D02*
X923842Y718601D01*
G01Y722539D02*
X921874Y720570D01*
G01X923842Y718601D02*
Y722539D01*
G01X914661Y723370D02*
X929161D01*
G01X916161Y717870D02*
Y723270D01*
G01X915661D02*
Y717870D01*
G01X915161D02*
Y723270D01*
G01X926106Y796671D02*
Y799871D01*
G01X932306Y796671D02*
X926106D01*
G01Y799871D02*
X932306D01*
G01X929516Y801790D02*
X926316D01*
G01Y807990D02*
X929516D01*
G01X926316Y801790D02*
Y807990D01*
G01Y809940D02*
Y816140D01*
G01X929516Y809940D02*
X926316D01*
G01X920190Y811940D02*
Y818140D01*
G01X923390Y811940D02*
X920190D01*
G01X923390Y818140D02*
Y811940D01*
G01X925390Y801790D02*
X922190D01*
G01X925390Y807990D02*
Y801790D01*
G01X922190Y807990D02*
X925390D01*
G01X922190Y801790D02*
Y807990D01*
G01X921264Y801790D02*
X918064D01*
G01X921264Y807990D02*
Y801790D01*
G01X918064Y807990D02*
X921264D01*
G01X918064Y801790D02*
Y807990D01*
G01X917316Y801790D02*
X914116D01*
G01X917316Y807990D02*
Y801790D01*
G01X914116Y807990D02*
X917316D01*
G01X914116Y801790D02*
Y807990D01*
G01X913016D02*
Y801790D01*
G01X926316Y816140D02*
X929516D01*
G01X920190Y818140D02*
X923390D01*
G01X921507Y831100D02*
Y828878D01*
X921660Y828413D01*
X921967Y828103D01*
X922350Y828000D01*
X922733Y828103D01*
X923040Y828413D01*
X923193Y828878D01*
Y831100D01*
G01X924607Y828465D02*
X924837Y828207D01*
X925105Y828052D01*
X925450Y828000D01*
X925795Y828103D01*
X926063Y828310D01*
X926255Y828672D01*
X926293Y829085D01*
X926217Y829498D01*
X926025Y829757D01*
X925757Y829963D01*
X925488Y830015D01*
X925220Y829963D01*
X924875Y829757D01*
X924990Y831100D01*
X926025D01*
G01X916100Y907900D02*
X912900D01*
G01X916100Y914100D02*
Y907900D01*
G01X912900D02*
Y914100D01*
G01X919700Y907900D02*
X916500D01*
G01X919700Y914100D02*
Y907900D01*
G01X916500D02*
Y914100D01*
G01X926228Y907989D02*
X923028D01*
G01X926228Y914189D02*
Y907989D01*
G01X923028D02*
Y914189D01*
G01X930228Y907989D02*
X927028D01*
G01D02*
Y914189D01*
G01X912900Y914100D02*
X916100D01*
G01X916500D02*
X919700D01*
G01X923028Y914189D02*
X926228D01*
G01X927028D02*
X930228D01*
G01X919028Y927226D02*
X922228D01*
G01X919028Y921026D02*
Y927226D01*
G01X922228Y921026D02*
X919028D01*
G01X922228Y927226D02*
Y921026D01*
G01X923028Y927226D02*
X926228D01*
G01X923028Y921026D02*
Y927226D01*
G01X926228Y921026D02*
X923028D01*
G01X926228Y927226D02*
Y921026D01*
G01X927028Y927226D02*
X930228D01*
G01X927028Y921026D02*
Y927226D01*
G01X930228Y921026D02*
X927028D01*
G01X915028Y927226D02*
X918228D01*
G01X915028Y921026D02*
Y927226D01*
G01X918228Y921026D02*
X915028D01*
G01X918228Y927226D02*
Y921026D01*
G01X914228Y927226D02*
Y921026D01*
G01X928269Y1005830D02*
Y995630D01*
X923669D01*
Y1005830D01*
X928269D01*
G01X922776D02*
Y995630D01*
X918176D01*
Y1005830D01*
X922776D01*
G01X929584Y1018753D02*
Y1012553D01*
X926384D01*
Y1018753D01*
X929584D01*
G01X918065D02*
Y1012553D01*
X914865D01*
Y1018753D01*
X918065D01*
G01X923461D02*
Y1012553D01*
X920261D01*
Y1018753D01*
X923461D01*
G01X923933Y1031032D02*
X941635D01*
G01X923933Y1044038D02*
Y1031032D01*
G01Y1070332D02*
Y1057266D01*
G01X922641Y1055132D02*
X942927D01*
G01X922641Y1046232D02*
Y1055132D01*
G01X942927Y1046232D02*
X922641D01*
G01X941635Y1070332D02*
X923933D01*
G01X915874Y1078259D02*
Y1075059D01*
G01X927982Y1075359D02*
X942782D01*
G01X927982Y1106363D02*
Y1075359D01*
G01X915874Y1082259D02*
Y1079059D01*
G01Y1086259D02*
Y1083059D01*
G01Y1090259D02*
Y1087059D01*
G01Y1094259D02*
Y1091059D01*
G01X942782Y1106363D02*
X927982D01*
G01X915874Y1106259D02*
Y1103059D01*
G01Y1102259D02*
Y1099059D01*
G01Y1098259D02*
Y1095059D01*
G01X919814Y1121936D02*
Y1114809D01*
X938468D01*
X941468Y1117809D01*
Y1121936D01*
G01X938468Y1136463D02*
X919814D01*
Y1129336D01*
G01X923728Y1141395D02*
Y1195331D01*
G01X941322Y1141395D02*
X923728D01*
G01Y1195331D02*
X941322D01*
G01X914326Y1229608D02*
Y1223408D01*
G01X920740Y1447936D02*
Y1451136D01*
G01X926940Y1447936D02*
X920740D01*
G01X926940Y1451136D02*
Y1447936D01*
G01X923416Y1440261D02*
Y1443361D01*
X924336D01*
X924643Y1443206D01*
X924873Y1442844D01*
X924950Y1442431D01*
X924873Y1442018D01*
X924681Y1441708D01*
X924336Y1441553D01*
X923416D01*
G01X926440Y1443361D02*
Y1441139D01*
X926593Y1440674D01*
X926900Y1440364D01*
X927283Y1440261D01*
X927666Y1440364D01*
X927973Y1440674D01*
X928126Y1441139D01*
Y1443361D01*
G01X929540Y1440881D02*
X929770Y1440519D01*
X930076Y1440313D01*
X930421Y1440261D01*
X930728Y1440313D01*
X931035Y1440571D01*
X931226Y1440881D01*
X931265Y1441191D01*
X931188Y1441553D01*
X930920Y1441811D01*
X930651Y1441914D01*
X930306D01*
G01X930651D02*
X930881Y1442069D01*
X931073Y1442328D01*
X931150Y1442638D01*
X931073Y1442948D01*
X930881Y1443206D01*
X930536Y1443361D01*
X930191Y1443309D01*
X929846Y1443103D01*
G01X916780Y1442480D02*
Y1462698D01*
G01X927297Y1452726D02*
X924097D01*
G01X927297Y1458926D02*
Y1452726D01*
G01X924097D02*
Y1458926D01*
G01D02*
X927297D01*
G01X923468Y1452756D02*
X920268D01*
G01X923468Y1458956D02*
Y1452756D01*
G01X920268D02*
Y1458956D01*
G01D02*
X923468D01*
G01X920740Y1451136D02*
X926940D01*
G01X920128Y1473700D02*
X926328D01*
G01X920128Y1470500D02*
Y1473700D01*
G01X926328Y1470500D02*
X920128D01*
G01X926328Y1473700D02*
Y1470500D01*
G01X920104Y1466500D02*
Y1469700D01*
G01X926304Y1466500D02*
X920104D01*
G01Y1469700D02*
X926304D01*
G01D02*
Y1466500D01*
G01X927978Y1562295D02*
Y1547795D01*
X978590D01*
Y1562295D01*
X927978D01*
G01X928406Y1564045D02*
Y1567145D01*
X929862D01*
G01X929326Y1565647D02*
X928406D01*
G01X931429Y1564458D02*
X931736Y1564200D01*
X932081Y1564045D01*
X932387D01*
X932694Y1564200D01*
X932924Y1564458D01*
X933039Y1564820D01*
X932962Y1565182D01*
X932771Y1565492D01*
X932426Y1565698D01*
X931966Y1565802D01*
X931697Y1566008D01*
X931582Y1566370D01*
X931659Y1566732D01*
X931851Y1566990D01*
X932119Y1567145D01*
X932387D01*
X932656Y1567042D01*
X932886Y1566783D01*
G01X935334Y1564045D02*
Y1567145D01*
X934874Y1566525D01*
G01Y1564045D02*
X935794D01*
G01X944742Y1590307D02*
X926252D01*
G01X919732D02*
X916212D01*
G01X917279Y1723990D02*
Y1726490D01*
G01Y1731490D02*
Y1736490D01*
G01X917073Y1771014D02*
Y1773514D01*
G01Y1778514D02*
Y1783514D01*
G01X943207Y-20800D02*
Y-17700D01*
X943973D01*
X944280Y-17855D01*
X944510Y-18062D01*
X944702Y-18372D01*
X944855Y-18733D01*
X944893Y-19250D01*
X944855Y-19767D01*
X944702Y-20128D01*
X944510Y-20438D01*
X944280Y-20645D01*
X943973Y-20800D01*
X943207D01*
G01X947917D02*
X946383D01*
Y-17700D01*
X947917D01*
G01X947303Y-19198D02*
X946383D01*
G01X950250Y-20800D02*
Y-17700D01*
X949790Y-18320D01*
G01Y-20800D02*
X950710D01*
G01X953350D02*
Y-17700D01*
X952890Y-18320D01*
G01Y-20800D02*
X953810D01*
G01X956450Y-17700D02*
Y-20800D01*
G01X955568Y-17700D02*
X957332D01*
G01X958400Y-21833D02*
X960700D01*
G01X962650Y-20800D02*
Y-17700D01*
X962190Y-18320D01*
G01Y-20800D02*
X963110D01*
G01X941671Y96067D02*
Y99267D01*
G01X947871Y96067D02*
X941671D01*
G01Y99267D02*
X947871D01*
G01X938410Y122172D02*
Y110172D01*
G01X932410D02*
Y122172D01*
G01X938410Y110172D02*
X932410D01*
G01X929793Y109424D02*
X932993D01*
G01X929793Y103224D02*
Y109424D01*
G01X932993Y103224D02*
X929793D01*
G01X932993Y109424D02*
Y103224D01*
G01X943687Y108095D02*
Y104895D01*
G01X937487Y108095D02*
X943687D01*
G01X937487Y104895D02*
Y108095D01*
G01X943687Y104895D02*
X937487D01*
G01X944544Y108086D02*
X947744D01*
G01X944544Y101886D02*
Y108086D01*
G01X947744Y101886D02*
X944544D01*
G01X937487Y100895D02*
Y104095D01*
G01X943687Y100895D02*
X937487D01*
G01X943687Y104095D02*
Y100895D01*
G01X937487Y104095D02*
X943687D01*
G01X930009Y123508D02*
Y111734D01*
G01X932410Y122172D02*
X938410D01*
G01X931018Y132423D02*
Y126223D01*
G01X935072Y126228D02*
X931872D01*
G01X935072Y132428D02*
Y126228D01*
G01X931872Y132428D02*
X935072D01*
G01X931872Y126228D02*
Y132428D01*
G01X935251Y141337D02*
X932051D01*
G01X935251Y147537D02*
Y141337D01*
G01X932051Y147537D02*
X935251D01*
G01X932051Y141337D02*
Y147537D01*
G01X931916Y133238D02*
Y136438D01*
G01X938116Y133238D02*
X931916D01*
G01X938116Y136438D02*
Y133238D01*
G01X931916Y136438D02*
X938116D01*
G01X931916Y137238D02*
Y140438D01*
G01X938116Y137238D02*
X931916D01*
G01X938116Y140438D02*
Y137238D01*
G01X931916Y140438D02*
X938116D01*
G01X938462Y148437D02*
X941662D01*
G01X938462Y142237D02*
Y148437D01*
G01X941662Y142237D02*
X938462D01*
G01X941662Y148437D02*
Y142237D01*
G01X929297Y134995D02*
Y144395D01*
G01X943783Y165200D02*
Y168300D01*
X944703D01*
X945010Y168145D01*
X945240Y167783D01*
X945317Y167370D01*
X945240Y166957D01*
X945048Y166647D01*
X944703Y166492D01*
X943783D01*
G01X946807Y165200D02*
Y168300D01*
X947573D01*
X947880Y168145D01*
X948110Y167938D01*
X948302Y167628D01*
X948455Y167267D01*
X948493Y166750D01*
X948455Y166233D01*
X948302Y165872D01*
X948110Y165562D01*
X947880Y165355D01*
X947573Y165200D01*
X946807D01*
G01X950022Y166492D02*
X950290Y166853D01*
X950520Y167060D01*
X950827Y167163D01*
X951095Y167060D01*
X951287Y166853D01*
X951440Y166543D01*
X951478Y166182D01*
X951440Y165872D01*
X951287Y165562D01*
X951057Y165303D01*
X950788Y165200D01*
X950482Y165303D01*
X950213Y165613D01*
X950060Y166078D01*
X950022Y166595D01*
X950098Y167267D01*
X950213Y167628D01*
X950405Y167990D01*
X950673Y168248D01*
X950942Y168300D01*
X951210Y168197D01*
X951402Y167938D01*
G01X953850Y165200D02*
X954118Y165252D01*
X954425Y165407D01*
X954617Y165665D01*
X954693Y166027D01*
X954617Y166388D01*
X954387Y166698D01*
X954042Y166853D01*
X953658D01*
X953428Y166957D01*
X953237Y167215D01*
X953160Y167577D01*
X953275Y167938D01*
X953543Y168197D01*
X953850Y168300D01*
X954157Y168197D01*
X954425Y167938D01*
X954540Y167577D01*
X954463Y167215D01*
X954272Y166957D01*
X954042Y166853D01*
X953658D01*
X953313Y166698D01*
X953083Y166388D01*
X953007Y166027D01*
X953083Y165665D01*
X953275Y165407D01*
X953582Y165252D01*
X953850Y165200D01*
G01X940900Y153107D02*
X943122D01*
X943587Y153260D01*
X943897Y153567D01*
X944000Y153950D01*
X943897Y154333D01*
X943587Y154640D01*
X943122Y154793D01*
X940900D01*
G01X943380Y156207D02*
X943742Y156437D01*
X943948Y156743D01*
X944000Y157088D01*
X943948Y157395D01*
X943690Y157702D01*
X943380Y157893D01*
X943070Y157932D01*
X942708Y157855D01*
X942450Y157587D01*
X942347Y157318D01*
Y156973D01*
G01Y157318D02*
X942192Y157548D01*
X941933Y157740D01*
X941623Y157817D01*
X941313Y157740D01*
X941055Y157548D01*
X940900Y157203D01*
X940952Y156858D01*
X941158Y156513D01*
G01X944000Y160073D02*
X943328Y160150D01*
X942760Y160265D01*
X942243Y160418D01*
X941675Y160610D01*
X940900Y160917D01*
Y159383D01*
G01X944000Y163250D02*
X940900D01*
X941520Y162790D01*
G01X944000D02*
Y163710D01*
G01X939598Y165304D02*
Y149950D01*
G01X930261Y201677D02*
Y189677D01*
G01X943084Y182816D02*
X931084D01*
G01X943084Y188816D02*
Y182816D01*
G01X931084Y188816D02*
X943084D01*
G01X931084Y182816D02*
Y188816D01*
G01X941037Y193635D02*
Y190435D01*
G01X934837Y193635D02*
X941037D01*
G01X934837Y190435D02*
Y193635D01*
G01X941037Y190435D02*
X934837D01*
G01X931061Y193477D02*
Y199677D01*
G01X934261Y193477D02*
X931061D01*
G01X934261Y199677D02*
Y193477D01*
G01X935867Y211972D02*
X948071D01*
Y196668D01*
X935867D01*
Y211972D01*
G01X931061Y199677D02*
X934261D01*
G01X940530Y216617D02*
X937330D01*
G01X940530Y222817D02*
Y216617D01*
G01X937330Y222817D02*
X940530D01*
G01X937330Y216617D02*
Y222817D01*
G01X944066Y225252D02*
Y228452D01*
G01X950266Y225252D02*
X944066D01*
G01Y228452D02*
X950266D01*
G01X944405Y216605D02*
X941205D01*
G01X944405Y222805D02*
Y216605D01*
G01X941205Y222805D02*
X944405D01*
G01X941205Y216605D02*
Y222805D01*
G01X936400Y240750D02*
X936348Y240443D01*
X936142Y240175D01*
X935832Y239945D01*
X935470Y239792D01*
X935057Y239715D01*
X934643D01*
X934230Y239792D01*
X933868Y239945D01*
X933558Y240175D01*
X933352Y240443D01*
X933300Y240750D01*
X933352Y241057D01*
X933558Y241325D01*
X933868Y241555D01*
X934230Y241708D01*
X934643Y241785D01*
X935057D01*
X935470Y241708D01*
X935832Y241555D01*
X936142Y241325D01*
X936348Y241057D01*
X936400Y240750D01*
G01X935573Y241057D02*
X936400Y241517D01*
G01X933817Y243122D02*
X933507Y243352D01*
X933352Y243620D01*
X933300Y243927D01*
X933403Y244310D01*
X933662Y244578D01*
X933972Y244655D01*
X934282Y244617D01*
X934540Y244463D01*
X935057Y243697D01*
X935418Y243352D01*
X935935Y243122D01*
X936400Y243045D01*
Y244655D01*
G01X933300Y246950D02*
X933403Y246643D01*
X933662Y246413D01*
X933972Y246260D01*
X934385Y246145D01*
X934850Y246107D01*
X935315Y246145D01*
X935728Y246260D01*
X936038Y246413D01*
X936297Y246643D01*
X936400Y246950D01*
X936297Y247257D01*
X936038Y247487D01*
X935728Y247640D01*
X935315Y247755D01*
X934850Y247793D01*
X934385Y247755D01*
X933972Y247640D01*
X933662Y247487D01*
X933403Y247257D01*
X933300Y246950D01*
G01X936400Y250510D02*
X933300D01*
X935522Y249092D01*
Y251008D01*
G01X940111Y246264D02*
X938387Y248264D01*
G01Y244264D02*
X940111Y246264D01*
G01X938387Y240846D02*
Y244264D01*
G01X947835Y240846D02*
X938387D01*
G01X936525Y238344D02*
X939725D01*
G01X936525Y232144D02*
Y238344D01*
G01X939725Y232144D02*
X936525D01*
G01X939725Y238344D02*
Y232144D01*
G01X941043Y238466D02*
X947243D01*
G01X941043Y235266D02*
Y238466D01*
G01X947243Y235266D02*
X941043D01*
G01X938387Y248264D02*
Y251682D01*
G01D02*
X947835D01*
G01X941157Y259289D02*
X944357D01*
G01X941157Y253089D02*
Y259289D01*
G01X944357Y253089D02*
X941157D01*
G01X944357Y259289D02*
Y253089D01*
G01X932252Y306855D02*
Y303655D01*
G01X942989Y318339D02*
X949189D01*
G01X942989Y315139D02*
Y318339D01*
G01X949189Y315139D02*
X942989D01*
G01X945375Y338417D02*
X948462D01*
Y335217D01*
X942262D01*
G01X939812D02*
X933612D01*
Y338417D01*
X936695D01*
G01X936687Y328992D02*
Y335192D01*
X939887D01*
G01Y332020D02*
Y328992D01*
G01X942187D02*
Y332082D01*
G01Y335192D02*
X945387D01*
Y328992D01*
G01X936687Y332142D02*
Y335163D01*
G01X939887Y338342D02*
Y335248D01*
G01X942187Y335198D02*
Y338342D01*
G01X942262Y332117D02*
X948462D01*
Y328917D01*
X945391D01*
G01X942262D02*
Y332117D01*
G01X936777Y328917D02*
X933612D01*
Y332117D01*
X939812D01*
Y328917D01*
G01X935276Y355854D02*
X935234Y356041D01*
X935109Y356254D01*
X934901Y356387D01*
X934609Y356441D01*
X934318Y356387D01*
X934068Y356227D01*
X933943Y355987D01*
Y355721D01*
X933859Y355561D01*
X933651Y355427D01*
X933359Y355374D01*
X933068Y355454D01*
X932859Y355641D01*
X932776Y355854D01*
X932859Y356067D01*
X933068Y356254D01*
X933359Y356334D01*
X933651Y356281D01*
X933859Y356147D01*
X933943Y355987D01*
Y355721D01*
X934068Y355481D01*
X934318Y355321D01*
X934609Y355267D01*
X934901Y355321D01*
X935109Y355454D01*
X935234Y355667D01*
X935276Y355854D01*
G01X931186Y356254D02*
Y353411D01*
G01X940085Y356153D02*
Y362353D01*
G01X943285Y356153D02*
X940085D01*
G01X943285Y362353D02*
Y356153D01*
G01X943277Y352881D02*
Y349681D01*
G01X937077Y352881D02*
X943277D01*
G01X937077Y349681D02*
Y352881D01*
G01X943277Y349681D02*
X937077D01*
G01X935276Y370554D02*
X932776D01*
X933276Y370234D01*
G01X935276D02*
Y370874D01*
G01Y373074D02*
X932776D01*
X934568Y372087D01*
Y373421D01*
G01X931186Y373097D02*
Y370254D01*
G01X932843Y361254D02*
X935843D01*
G01X940085Y362353D02*
X943285D01*
G01X940837Y369305D02*
X944037D01*
G01X940837Y363105D02*
Y369305D01*
G01X944037Y363105D02*
X940837D01*
G01X944037Y369305D02*
Y363105D01*
G01X937057Y363111D02*
Y369311D01*
X940257D01*
Y363111D01*
X937057D01*
G01X929472Y386007D02*
X932672D01*
G01X929472Y379807D02*
Y386007D01*
G01X932672Y379807D02*
X929472D01*
G01X932672Y386007D02*
Y379807D01*
G01X931397Y422969D02*
Y438481D01*
G01X940599Y442542D02*
Y439342D01*
G01X934399D02*
Y442542D01*
G01X940599Y439342D02*
X934399D01*
G01X940599Y446042D02*
Y442842D01*
G01X934399Y446042D02*
X940599D01*
G01X934399Y442842D02*
Y446042D01*
G01X940599Y442842D02*
X934399D01*
G01Y449842D02*
Y453042D01*
G01X940599Y449842D02*
X934399D01*
G01X940599Y453042D02*
Y449842D01*
G01X934399Y453042D02*
X940599D01*
G01X934399Y457842D02*
Y461042D01*
G01X940599Y457842D02*
X934399D01*
G01X940599Y461042D02*
Y457842D01*
G01X934399Y442542D02*
X940599D01*
G01X934399Y453842D02*
Y457042D01*
G01X940599Y453842D02*
X934399D01*
G01X940599Y457042D02*
Y453842D01*
G01X934399Y457042D02*
X940599D01*
G01Y449542D02*
Y446342D01*
G01X934399Y449542D02*
X940599D01*
G01X934399Y446342D02*
Y449542D01*
G01X940599Y446342D02*
X934399D01*
G01X932500Y453780D02*
X929300D01*
G01X932500Y459980D02*
Y453780D01*
G01X929300D02*
Y459980D01*
G01X934399Y461042D02*
X940599D01*
G01X934399Y461842D02*
Y465042D01*
G01X940599Y461842D02*
X934399D01*
G01X940599Y465042D02*
Y461842D01*
G01X934399Y465042D02*
X940599D01*
G01X934399Y467342D02*
Y470542D01*
G01X940599Y467342D02*
X934399D01*
G01X940599Y470542D02*
Y467342D01*
G01X934399Y470542D02*
X940599D01*
G01X929300Y459980D02*
X932500D01*
G01X930599Y477042D02*
Y470842D01*
G01X937760Y495586D02*
X938122Y495816D01*
X938328Y496122D01*
X938380Y496467D01*
X938328Y496774D01*
X938070Y497081D01*
X937760Y497272D01*
X937450Y497311D01*
X937088Y497234D01*
X936830Y496966D01*
X936727Y496697D01*
Y496352D01*
G01Y496697D02*
X936572Y496927D01*
X936313Y497119D01*
X936003Y497196D01*
X935693Y497119D01*
X935435Y496927D01*
X935280Y496582D01*
X935332Y496237D01*
X935538Y495892D01*
G01X941047Y538326D02*
X947247D01*
G01X941047Y535126D02*
Y538326D01*
G01X947247Y535126D02*
X941047D01*
G01Y533326D02*
X947247D01*
G01X941047Y530126D02*
Y533326D01*
G01X947247Y530126D02*
X941047D01*
G01Y526126D02*
Y529326D01*
G01X947247Y526126D02*
X941047D01*
G01Y529326D02*
X947247D01*
G01Y539126D02*
X941047D01*
Y542326D01*
X947247D01*
Y539126D01*
G01X941047Y547126D02*
Y550326D01*
G01X947247Y547126D02*
X941047D01*
G01Y550326D02*
X947247D01*
G01X941047Y546326D02*
X947247D01*
G01X941047Y543126D02*
Y546326D01*
G01X947247Y543126D02*
X941047D01*
G01X947247Y551126D02*
X941047D01*
Y554326D01*
X947247D01*
Y551126D01*
G01X930752Y559241D02*
Y556041D01*
G01Y563178D02*
Y559978D01*
G01Y567178D02*
Y563978D01*
G01Y571178D02*
Y567978D01*
G01X930736Y583978D02*
Y586170D01*
G01X937106Y585713D02*
X939346D01*
G01X938133Y587338D02*
Y584088D01*
G01X940747Y580365D02*
Y591861D01*
G01X970306Y580365D02*
X940747D01*
G01X930752Y575178D02*
Y571978D01*
G01Y579178D02*
Y575978D01*
G01Y583178D02*
Y579978D01*
G01X930736Y591178D02*
Y588992D01*
G01X930752Y592729D02*
Y594970D01*
G01Y599929D02*
Y597650D01*
G01X940916Y593480D02*
Y596580D01*
X941836D01*
X942143Y596425D01*
X942373Y596063D01*
X942450Y595650D01*
X942373Y595237D01*
X942181Y594927D01*
X941836Y594772D01*
X940916D01*
G01X943940Y593480D02*
Y596580D01*
X944706D01*
X945013Y596425D01*
X945243Y596218D01*
X945435Y595908D01*
X945588Y595547D01*
X945626Y595030D01*
X945588Y594513D01*
X945435Y594152D01*
X945243Y593842D01*
X945013Y593635D01*
X944706Y593480D01*
X943940D01*
G01X947231Y593842D02*
X947500Y593583D01*
X947806Y593480D01*
X948113Y593583D01*
X948381Y593893D01*
X948573Y594358D01*
X948650Y594823D01*
Y595392D01*
X948573Y595857D01*
X948381Y596270D01*
X948151Y596477D01*
X947883Y596580D01*
X947576Y596477D01*
X947346Y596270D01*
X947193Y595960D01*
X947116Y595547D01*
X947193Y595185D01*
X947385Y594823D01*
X947615Y594617D01*
X947883Y594565D01*
X948190Y594668D01*
X948420Y594927D01*
X948650Y595392D01*
G01X951443Y593480D02*
Y596580D01*
X950025Y594358D01*
X951941D01*
G01X940747Y591861D02*
X970306D01*
G01X942765Y619711D02*
Y622911D01*
G01X948965Y619711D02*
X942765D01*
G01X938765Y618411D02*
X941965D01*
G01X938765Y612211D02*
Y618411D01*
G01X941965Y612211D02*
X938765D01*
G01X941965Y618411D02*
Y612211D01*
G01X942765Y618411D02*
X945965D01*
G01X942765Y612211D02*
Y618411D01*
G01X945965Y612211D02*
X942765D01*
G01Y622911D02*
X948965D01*
G01X942765Y630911D02*
X948965D01*
G01X942765Y627711D02*
Y630911D01*
G01X948965Y627711D02*
X942765D01*
G01Y626911D02*
X948965D01*
G01X942765Y623711D02*
Y626911D01*
G01X948965Y623711D02*
X942765D01*
G01X936300Y685507D02*
X938522D01*
X938987Y685660D01*
X939297Y685967D01*
X939400Y686350D01*
X939297Y686733D01*
X938987Y687040D01*
X938522Y687193D01*
X936300D01*
G01X938780Y688607D02*
X939142Y688837D01*
X939348Y689143D01*
X939400Y689488D01*
X939348Y689795D01*
X939090Y690102D01*
X938780Y690293D01*
X938470Y690332D01*
X938108Y690255D01*
X937850Y689987D01*
X937747Y689718D01*
Y689373D01*
G01Y689718D02*
X937592Y689948D01*
X937333Y690140D01*
X937023Y690217D01*
X936713Y690140D01*
X936455Y689948D01*
X936300Y689603D01*
X936352Y689258D01*
X936558Y688913D01*
G01X936817Y691822D02*
X936507Y692052D01*
X936352Y692320D01*
X936300Y692627D01*
X936403Y693010D01*
X936662Y693278D01*
X936972Y693355D01*
X937282Y693317D01*
X937540Y693163D01*
X938057Y692397D01*
X938418Y692052D01*
X938935Y691822D01*
X939400Y691745D01*
Y693355D01*
G01Y695573D02*
X938728Y695650D01*
X938160Y695765D01*
X937643Y695918D01*
X937075Y696110D01*
X936300Y696417D01*
Y694883D01*
G01X935172Y690560D02*
Y683960D01*
G01X930812Y682470D02*
X934012D01*
G01X930812Y676270D02*
Y682470D01*
G01X934012Y676270D02*
X930812D01*
G01X934012Y682470D02*
Y676270D01*
G01X932672Y692060D02*
X935172Y690560D01*
G01Y693560D02*
X932672Y692060D01*
G01X935172Y700160D02*
Y693560D01*
G01X929161Y723370D02*
Y717770D01*
G01X944406Y713269D02*
X941806D01*
G01X936322D02*
Y718781D01*
G01X936906Y713269D02*
X936322D01*
G01X936926Y732125D02*
X940126D01*
G01X936926Y725925D02*
Y732125D01*
G01X940126Y725925D02*
X936926D01*
G01X940126Y732125D02*
Y725925D01*
G01X943500Y724107D02*
X945722D01*
X946187Y724260D01*
X946497Y724567D01*
X946600Y724950D01*
X946497Y725333D01*
X946187Y725640D01*
X945722Y725793D01*
X943500D01*
G01X945980Y727207D02*
X946342Y727437D01*
X946548Y727743D01*
X946600Y728088D01*
X946548Y728395D01*
X946290Y728702D01*
X945980Y728893D01*
X945670Y728932D01*
X945308Y728855D01*
X945050Y728587D01*
X944947Y728318D01*
Y727973D01*
G01Y728318D02*
X944792Y728548D01*
X944533Y728740D01*
X944223Y728817D01*
X943913Y728740D01*
X943655Y728548D01*
X943500Y728203D01*
X943552Y727858D01*
X943758Y727513D01*
G01X946135Y730307D02*
X946393Y730537D01*
X946548Y730805D01*
X946600Y731150D01*
X946497Y731495D01*
X946290Y731763D01*
X945928Y731955D01*
X945515Y731993D01*
X945102Y731917D01*
X944843Y731725D01*
X944637Y731457D01*
X944585Y731188D01*
X944637Y730920D01*
X944843Y730575D01*
X943500Y730690D01*
Y731725D01*
G01X946600Y734250D02*
X946548Y734518D01*
X946393Y734825D01*
X946135Y735017D01*
X945773Y735093D01*
X945412Y735017D01*
X945102Y734787D01*
X944947Y734442D01*
Y734058D01*
X944843Y733828D01*
X944585Y733637D01*
X944223Y733560D01*
X943862Y733675D01*
X943603Y733943D01*
X943500Y734250D01*
X943603Y734557D01*
X943862Y734825D01*
X944223Y734940D01*
X944585Y734863D01*
X944843Y734672D01*
X944947Y734442D01*
Y734058D01*
X945102Y733713D01*
X945412Y733483D01*
X945773Y733407D01*
X946135Y733483D01*
X946393Y733675D01*
X946548Y733982D01*
X946600Y734250D01*
G01X936322Y718781D02*
X936906D01*
G01X940206D02*
X944406D01*
G01X935798Y795241D02*
Y807839D01*
G01X946034Y795241D02*
X935798D01*
G01X938986Y790730D02*
Y793930D01*
G01X945186Y790730D02*
X938986D01*
G01X945186Y793930D02*
Y790730D01*
G01X938986Y793930D02*
X945186D01*
G01X932306Y799871D02*
Y796671D01*
G01X935798Y807839D02*
X946034D01*
G01X934017Y808910D02*
Y801820D01*
G01X930217Y808910D02*
X934017D01*
G01X930217Y801820D02*
Y808910D01*
G01X934017Y808410D02*
Y801220D01*
G01X930217Y808410D02*
X934017D01*
G01X930217Y801220D02*
Y808410D01*
G01X934017Y800770D02*
X930267D01*
G01X934017Y807910D02*
Y800770D01*
G01X930217Y807910D02*
X934017D01*
G01X930217Y800820D02*
Y807910D01*
G01X934316Y809940D02*
Y816140D01*
G01X937516Y809940D02*
X934316D01*
G01X937516Y816140D02*
Y809940D01*
G01X933516D02*
X930316D01*
G01X933516Y816140D02*
Y809940D01*
G01X930316D02*
Y816140D01*
G01X938316Y809940D02*
Y816140D01*
G01X941516Y809940D02*
X938316D01*
G01X941516Y816140D02*
Y809940D01*
G01X945516D02*
X942316D01*
G01D02*
Y816140D01*
G01X929516Y807990D02*
Y801790D01*
G01Y816140D02*
Y809940D01*
G01X934316Y816140D02*
X937516D01*
G01X939935Y821957D02*
Y828157D01*
G01X943135Y821957D02*
X939935D01*
G01X943135Y828157D02*
Y821957D01*
G01X939935Y828157D02*
X943135D01*
G01X930316Y816140D02*
X933516D01*
G01X938316D02*
X941516D01*
G01X942316D02*
X945516D01*
G01X936035Y821957D02*
Y828157D01*
G01X939235Y821957D02*
X936035D01*
G01Y828157D02*
X939235D01*
G01D02*
Y821957D01*
G01X946635Y828657D02*
X943435D01*
G01D02*
Y834857D01*
G01X945335Y843057D02*
X942135D01*
G01D02*
Y849257D01*
G01X943435Y834857D02*
X946635D01*
G01X929203Y835253D02*
Y886827D01*
G01X942135Y849257D02*
X945335D01*
G01X943027Y863262D02*
Y866462D01*
G01X949227Y863262D02*
X943027D01*
G01X944866Y862165D02*
Y856715D01*
G01X942566Y862165D02*
X944866D01*
G01X942566Y856715D02*
Y862165D01*
G01X944866Y856715D02*
X942566D01*
G01X942656Y868789D02*
Y906142D01*
G01X943027Y866462D02*
X949227D01*
G01X943170Y879816D02*
X949370D01*
G01X943170Y876616D02*
Y879816D01*
G01X949370Y876616D02*
X943170D01*
G01X948995Y873118D02*
X943545D01*
G01Y875418D02*
X948995D01*
G01X943545Y873118D02*
Y875418D01*
G01X935016Y893504D02*
Y899704D01*
X938216D01*
Y893504D01*
X935016D01*
G01X940970Y882190D02*
X934770D01*
Y885390D01*
X940970D01*
Y882190D01*
G01X942964Y881546D02*
Y884746D01*
G01X949164Y881546D02*
X942964D01*
G01Y884746D02*
X949164D01*
G01X940972Y885908D02*
X934772D01*
Y889108D01*
X940972D01*
Y885908D01*
G01X931116Y893504D02*
Y899704D01*
X934316D01*
Y893504D01*
X931116D01*
G01X934728Y892816D02*
X940928D01*
Y889616D01*
X934728D01*
Y892816D01*
G01X942116Y899705D02*
Y893505D01*
X938916D01*
Y899705D01*
X942116D01*
G01X943314Y898290D02*
X948497D01*
G01X943314Y901490D02*
X948557D01*
G01X938228Y907989D02*
X935028D01*
G01X938228Y914189D02*
Y907989D01*
G01X935028D02*
Y914189D01*
G01X946228Y907989D02*
X943028D01*
G01D02*
Y914189D01*
G01X942228Y907989D02*
X939028D01*
G01X942228Y914189D02*
Y907989D01*
G01X939028D02*
Y914189D01*
G01X930228D02*
Y907989D01*
G01X934228D02*
X931028D01*
G01X934228Y914189D02*
Y907989D01*
G01X931028D02*
Y914189D01*
G01X943314Y898290D02*
Y901490D01*
G01X942656Y915111D02*
Y917913D01*
X1040806D01*
Y857677D01*
X991731D01*
G01X935028Y914189D02*
X938228D01*
G01X943028D02*
X946228D01*
G01X939028D02*
X942228D01*
G01X943028Y927226D02*
X946228D01*
G01X943028Y921026D02*
Y927226D01*
G01X946228Y921026D02*
X943028D01*
G01X935028Y927226D02*
X938228D01*
G01X935028Y921026D02*
Y927226D01*
G01X938228Y921026D02*
X935028D01*
G01X938228Y927226D02*
Y921026D01*
G01X939028Y927226D02*
X942228D01*
G01X939028Y921026D02*
Y927226D01*
G01X942228Y921026D02*
X939028D01*
G01X942228Y927226D02*
Y921026D01*
G01X931028Y927226D02*
X934228D01*
G01X931028Y921026D02*
Y927226D01*
G01X934228Y921026D02*
X931028D01*
G01X934228Y927226D02*
Y921026D01*
G01X930228Y927226D02*
Y921026D01*
G01X931028Y914189D02*
X934228D01*
G01X932727Y947681D02*
X963829D01*
G01X932727Y964197D02*
Y947681D01*
G01X963829Y964197D02*
X932727D01*
G01X944071Y990343D02*
X947271D01*
G01X944071Y984143D02*
Y990343D01*
G01X947271Y984143D02*
X944071D01*
G01X939166Y1005830D02*
Y995630D01*
X934566D01*
Y1005830D01*
X939166D01*
G01X944556D02*
Y995630D01*
X939956D01*
Y1005830D01*
X944556D01*
G01X933725D02*
Y995630D01*
X929125D01*
Y1005830D01*
X933725D01*
G01X941531Y1018753D02*
Y1012553D01*
X938331D01*
Y1018753D01*
X941531D01*
G01X947031D02*
Y1012553D01*
X943831D01*
Y1018753D01*
X947031D01*
G01X935978D02*
Y1012553D01*
X932778D01*
Y1018753D01*
X935978D01*
G01X941635Y1031032D02*
Y1044125D01*
G01Y1057612D02*
Y1070332D01*
G01X944374Y1046232D02*
Y1055132D01*
G01X964660Y1046232D02*
X944374D01*
G01Y1055132D02*
X964660D01*
G01X942927D02*
Y1046232D01*
G01X942782Y1075359D02*
Y1106363D01*
G01X944297Y1085775D02*
Y1088975D01*
G01X950497Y1085775D02*
X944297D01*
G01Y1088975D02*
X950497D01*
G01X941468Y1129336D02*
Y1133463D01*
X938468Y1136463D01*
G01X934374Y1198345D02*
Y1201445D01*
X935294D01*
X935601Y1201290D01*
X935831Y1200928D01*
X935908Y1200515D01*
X935831Y1200102D01*
X935639Y1199792D01*
X935294Y1199637D01*
X934374D01*
G01X937398Y1201445D02*
Y1199223D01*
X937551Y1198758D01*
X937858Y1198448D01*
X938241Y1198345D01*
X938624Y1198448D01*
X938931Y1198758D01*
X939084Y1199223D01*
Y1201445D01*
G01X941341Y1198345D02*
Y1201445D01*
X940881Y1200825D01*
G01Y1198345D02*
X941801D01*
G01X944441D02*
X944709Y1198397D01*
X945016Y1198552D01*
X945208Y1198810D01*
X945284Y1199172D01*
X945208Y1199533D01*
X944978Y1199843D01*
X944633Y1199998D01*
X944249D01*
X944019Y1200102D01*
X943828Y1200360D01*
X943751Y1200722D01*
X943866Y1201083D01*
X944134Y1201342D01*
X944441Y1201445D01*
X944748Y1201342D01*
X945016Y1201083D01*
X945131Y1200722D01*
X945054Y1200360D01*
X944863Y1200102D01*
X944633Y1199998D01*
X944249D01*
X943904Y1199843D01*
X943674Y1199533D01*
X943598Y1199172D01*
X943674Y1198810D01*
X943866Y1198552D01*
X944173Y1198397D01*
X944441Y1198345D01*
G01X941600Y1203500D02*
X939100D01*
X939600Y1203180D01*
G01X941600D02*
Y1203820D01*
G01X941308Y1205247D02*
X941517Y1205433D01*
X941600Y1205647D01*
X941517Y1205860D01*
X941267Y1206047D01*
X940892Y1206180D01*
X940517Y1206233D01*
X940058D01*
X939683Y1206180D01*
X939350Y1206047D01*
X939183Y1205887D01*
X939100Y1205700D01*
X939183Y1205487D01*
X939350Y1205327D01*
X939600Y1205220D01*
X939933Y1205167D01*
X940225Y1205220D01*
X940517Y1205353D01*
X940683Y1205513D01*
X940725Y1205700D01*
X940642Y1205913D01*
X940433Y1206073D01*
X940058Y1206233D01*
G01X938394Y1206102D02*
X935194D01*
G01X938394Y1212302D02*
Y1206102D01*
G01X935194Y1212302D02*
X938394D01*
G01X935194Y1206102D02*
Y1212302D01*
G01X939143Y1214337D02*
X936643D01*
X937143Y1214017D01*
G01X939143D02*
Y1214657D01*
G01Y1216537D02*
X936643D01*
X937143Y1216217D01*
G01X939143D02*
Y1216857D01*
G01X939976Y1217937D02*
Y1219537D01*
G01X939143Y1220937D02*
X936643D01*
X937143Y1220617D01*
G01X939143D02*
Y1221257D01*
G01Y1223137D02*
X939101Y1223324D01*
X938976Y1223537D01*
X938768Y1223670D01*
X938476Y1223724D01*
X938185Y1223670D01*
X937935Y1223510D01*
X937810Y1223270D01*
Y1223004D01*
X937726Y1222844D01*
X937518Y1222710D01*
X937226Y1222657D01*
X936935Y1222737D01*
X936726Y1222924D01*
X936643Y1223137D01*
X936726Y1223350D01*
X936935Y1223537D01*
X937226Y1223617D01*
X937518Y1223564D01*
X937726Y1223430D01*
X937810Y1223270D01*
Y1223004D01*
X937935Y1222764D01*
X938185Y1222604D01*
X938476Y1222550D01*
X938768Y1222604D01*
X938976Y1222737D01*
X939101Y1222950D01*
X939143Y1223137D01*
G01X941808Y1207037D02*
Y1206766D01*
X945610D01*
G01X949917Y1226591D02*
X937917D01*
G01Y1232591D02*
X949917D01*
G01X937917Y1226591D02*
Y1232591D01*
G01X949917Y1233491D02*
X937917D01*
G01D02*
Y1239491D01*
G01X947910Y1222908D02*
X941808D01*
Y1222437D01*
G01X937917Y1239491D02*
X949917D01*
G01Y1240391D02*
X937917D01*
G01Y1246391D02*
X949917D01*
G01X937917Y1240391D02*
Y1246391D01*
G01X949917Y1247291D02*
X937917D01*
G01Y1253291D02*
X949917D01*
G01X937917Y1247291D02*
Y1253291D01*
G01X934032Y1422376D02*
Y1425476D01*
X934952D01*
X935259Y1425321D01*
X935489Y1424959D01*
X935566Y1424546D01*
X935489Y1424133D01*
X935297Y1423823D01*
X934952Y1423668D01*
X934032D01*
G01X937899Y1422376D02*
X937592Y1422428D01*
X937324Y1422634D01*
X937094Y1422944D01*
X936941Y1423306D01*
X936864Y1423719D01*
Y1424133D01*
X936941Y1424546D01*
X937094Y1424908D01*
X937324Y1425218D01*
X937592Y1425424D01*
X937899Y1425476D01*
X938206Y1425424D01*
X938474Y1425218D01*
X938704Y1424908D01*
X938857Y1424546D01*
X938934Y1424133D01*
Y1423719D01*
X938857Y1423306D01*
X938704Y1422944D01*
X938474Y1422634D01*
X938206Y1422428D01*
X937899Y1422376D01*
G01X938206Y1423203D02*
X938666Y1422376D01*
G01X940271Y1423668D02*
X940539Y1424029D01*
X940769Y1424236D01*
X941076Y1424339D01*
X941344Y1424236D01*
X941536Y1424029D01*
X941689Y1423719D01*
X941727Y1423358D01*
X941689Y1423048D01*
X941536Y1422738D01*
X941306Y1422479D01*
X941037Y1422376D01*
X940731Y1422479D01*
X940462Y1422789D01*
X940309Y1423254D01*
X940271Y1423771D01*
X940347Y1424443D01*
X940462Y1424804D01*
X940654Y1425166D01*
X940922Y1425424D01*
X941191Y1425476D01*
X941459Y1425373D01*
X941651Y1425114D01*
G01X943371Y1423668D02*
X943639Y1424029D01*
X943869Y1424236D01*
X944176Y1424339D01*
X944444Y1424236D01*
X944636Y1424029D01*
X944789Y1423719D01*
X944827Y1423358D01*
X944789Y1423048D01*
X944636Y1422738D01*
X944406Y1422479D01*
X944137Y1422376D01*
X943831Y1422479D01*
X943562Y1422789D01*
X943409Y1423254D01*
X943371Y1423771D01*
X943447Y1424443D01*
X943562Y1424804D01*
X943754Y1425166D01*
X944022Y1425424D01*
X944291Y1425476D01*
X944559Y1425373D01*
X944751Y1425114D01*
G01X947199Y1425476D02*
X946892Y1425373D01*
X946662Y1425114D01*
X946509Y1424804D01*
X946394Y1424391D01*
X946356Y1423926D01*
X946394Y1423461D01*
X946509Y1423048D01*
X946662Y1422738D01*
X946892Y1422479D01*
X947199Y1422376D01*
X947506Y1422479D01*
X947736Y1422738D01*
X947889Y1423048D01*
X948004Y1423461D01*
X948042Y1423926D01*
X948004Y1424391D01*
X947889Y1424804D01*
X947736Y1425114D01*
X947506Y1425373D01*
X947199Y1425476D01*
G01X950299Y1422376D02*
Y1425476D01*
X949839Y1424856D01*
G01Y1422376D02*
X950759D01*
G01X932010Y1446698D02*
X931177D01*
Y1465202D01*
X931810D01*
G01X949486Y1503552D02*
Y1471752D01*
X935686D01*
Y1503552D01*
X949486D01*
G01X933974Y1486463D02*
X930874D01*
Y1487383D01*
X931029Y1487690D01*
X931391Y1487920D01*
X931804Y1487997D01*
X932217Y1487920D01*
X932527Y1487728D01*
X932682Y1487383D01*
Y1486463D01*
G01X933974Y1489563D02*
X930874D01*
Y1490522D01*
X931029Y1490828D01*
X931236Y1491020D01*
X931649Y1491097D01*
X932062Y1491020D01*
X932321Y1490790D01*
X932476Y1490522D01*
Y1489563D01*
G01Y1490522D02*
X933974Y1491097D01*
G01X932682Y1492702D02*
X932321Y1492970D01*
X932114Y1493200D01*
X932011Y1493507D01*
X932114Y1493775D01*
X932321Y1493967D01*
X932631Y1494120D01*
X932992Y1494158D01*
X933302Y1494120D01*
X933612Y1493967D01*
X933871Y1493737D01*
X933974Y1493468D01*
X933871Y1493162D01*
X933561Y1492893D01*
X933096Y1492740D01*
X932579Y1492702D01*
X931907Y1492778D01*
X931546Y1492893D01*
X931184Y1493085D01*
X930926Y1493353D01*
X930874Y1493622D01*
X930977Y1493890D01*
X931236Y1494082D01*
G01X930874Y1496530D02*
X930977Y1496223D01*
X931236Y1495993D01*
X931546Y1495840D01*
X931959Y1495725D01*
X932424Y1495687D01*
X932889Y1495725D01*
X933302Y1495840D01*
X933612Y1495993D01*
X933871Y1496223D01*
X933974Y1496530D01*
X933871Y1496837D01*
X933612Y1497067D01*
X933302Y1497220D01*
X932889Y1497335D01*
X932424Y1497373D01*
X931959Y1497335D01*
X931546Y1497220D01*
X931236Y1497067D01*
X930977Y1496837D01*
X930874Y1496530D01*
G01Y1499630D02*
X930977Y1499323D01*
X931236Y1499093D01*
X931546Y1498940D01*
X931959Y1498825D01*
X932424Y1498787D01*
X932889Y1498825D01*
X933302Y1498940D01*
X933612Y1499093D01*
X933871Y1499323D01*
X933974Y1499630D01*
X933871Y1499937D01*
X933612Y1500167D01*
X933302Y1500320D01*
X932889Y1500435D01*
X932424Y1500473D01*
X931959Y1500435D01*
X931546Y1500320D01*
X931236Y1500167D01*
X930977Y1499937D01*
X930874Y1499630D01*
G01X933974Y1502730D02*
X930874D01*
X931494Y1502270D01*
G01X933974D02*
Y1503190D01*
G01X948392Y-40098D02*
Y-23498D01*
X957992D01*
Y-40098D01*
X948392D01*
G01X953110Y58150D02*
Y111596D01*
G01X952814Y57756D02*
Y111596D01*
G01X948857Y57631D02*
X949167Y57823D01*
X949374Y58053D01*
X949477Y58321D01*
X949374Y58628D01*
X949167Y58858D01*
X948857Y59088D01*
X948444Y59165D01*
X946377D01*
G01X948857Y60655D02*
X949219Y60885D01*
X949425Y61191D01*
X949477Y61536D01*
X949425Y61843D01*
X949167Y62150D01*
X948857Y62341D01*
X948547Y62380D01*
X948185Y62303D01*
X947927Y62035D01*
X947824Y61766D01*
Y61421D01*
G01Y61766D02*
X947669Y61996D01*
X947410Y62188D01*
X947100Y62265D01*
X946790Y62188D01*
X946532Y61996D01*
X946377Y61651D01*
X946429Y61306D01*
X946635Y60961D01*
G01X949477Y64598D02*
X949425Y64866D01*
X949270Y65173D01*
X949012Y65365D01*
X948650Y65441D01*
X948289Y65365D01*
X947979Y65135D01*
X947824Y64790D01*
Y64406D01*
X947720Y64176D01*
X947462Y63985D01*
X947100Y63908D01*
X946739Y64023D01*
X946480Y64291D01*
X946377Y64598D01*
X946480Y64905D01*
X946739Y65173D01*
X947100Y65288D01*
X947462Y65211D01*
X947720Y65020D01*
X947824Y64790D01*
Y64406D01*
X947979Y64061D01*
X948289Y63831D01*
X948650Y63755D01*
X949012Y63831D01*
X949270Y64023D01*
X949425Y64330D01*
X949477Y64598D01*
G01X959195Y57756D02*
X952814D01*
G01X958790Y58150D02*
X953110D01*
G01X947871Y99267D02*
Y96067D01*
G01X953110Y118848D02*
Y114048D01*
G01X952814Y118848D02*
Y114048D01*
G01X947744Y108086D02*
Y101886D01*
G01X953110Y132607D02*
Y128340D01*
G01X952814Y132607D02*
Y128340D01*
G01Y125781D02*
Y121219D01*
G01X953110Y125781D02*
Y121219D01*
G01X952814Y153150D02*
Y135528D01*
G01X953110Y152756D02*
Y135528D01*
G01X952814Y153150D02*
X959195D01*
G01X953110Y152756D02*
X958790D01*
G01X957207Y174706D02*
X954781D01*
G01X953667Y180754D02*
Y169258D01*
G01X955252Y198762D02*
X952152D01*
Y199682D01*
X952307Y199989D01*
X952669Y200219D01*
X953082Y200296D01*
X953495Y200219D01*
X953805Y200027D01*
X953960Y199682D01*
Y198762D01*
G01X952152Y201786D02*
X954374D01*
X954839Y201939D01*
X955149Y202246D01*
X955252Y202629D01*
X955149Y203012D01*
X954839Y203319D01*
X954374Y203472D01*
X952152D01*
G01X953960Y205001D02*
X953599Y205269D01*
X953392Y205499D01*
X953289Y205806D01*
X953392Y206074D01*
X953599Y206266D01*
X953909Y206419D01*
X954270Y206457D01*
X954580Y206419D01*
X954890Y206266D01*
X955149Y206036D01*
X955252Y205767D01*
X955149Y205461D01*
X954839Y205192D01*
X954374Y205039D01*
X953857Y205001D01*
X953185Y205077D01*
X952824Y205192D01*
X952462Y205384D01*
X952204Y205652D01*
X952152Y205921D01*
X952255Y206189D01*
X952514Y206381D01*
G01X952669Y208101D02*
X952359Y208331D01*
X952204Y208599D01*
X952152Y208906D01*
X952255Y209289D01*
X952514Y209557D01*
X952824Y209634D01*
X953134Y209596D01*
X953392Y209442D01*
X953909Y208676D01*
X954270Y208331D01*
X954787Y208101D01*
X955252Y208024D01*
Y209634D01*
G01X952640Y216630D02*
X949440D01*
G01X952640Y222830D02*
Y216630D01*
G01X949440Y222830D02*
X952640D01*
G01X949440Y216630D02*
Y222830D01*
G01X950266Y228452D02*
Y225252D01*
G01X945440Y222830D02*
X948640D01*
G01X945440Y216630D02*
Y222830D01*
G01X948640Y216630D02*
X945440D01*
G01X948640Y222830D02*
Y216630D01*
G01X947835Y251682D02*
Y240846D01*
G01X949678Y242648D02*
X952878D01*
G01X949678Y236448D02*
Y242648D01*
G01X952878Y236448D02*
X949678D01*
G01X952878Y242648D02*
Y236448D01*
G01X949678Y243427D02*
Y249627D01*
G01X952878Y243427D02*
X949678D01*
G01X952878Y249627D02*
Y243427D01*
G01X947243Y238466D02*
Y235266D01*
G01X949678Y249627D02*
X952878D01*
G01X949189Y318339D02*
Y315139D01*
G01X945387Y335205D02*
Y332142D01*
G01X945898Y368066D02*
Y358266D01*
G01D02*
X957698D01*
G01D02*
Y368066D01*
G01X949950Y370200D02*
Y371595D01*
X949183Y373300D01*
G01X950717D02*
X949950Y371595D01*
G01X952207Y370665D02*
X952437Y370407D01*
X952705Y370252D01*
X953050Y370200D01*
X953395Y370303D01*
X953663Y370510D01*
X953855Y370872D01*
X953893Y371285D01*
X953817Y371698D01*
X953625Y371957D01*
X953357Y372163D01*
X953088Y372215D01*
X952820Y372163D01*
X952475Y371957D01*
X952590Y373300D01*
X953625D01*
G01X957698Y368066D02*
X945898D01*
G01X953600Y452750D02*
X953548Y452443D01*
X953342Y452175D01*
X953032Y451945D01*
X952670Y451792D01*
X952257Y451715D01*
X951843D01*
X951430Y451792D01*
X951068Y451945D01*
X950758Y452175D01*
X950552Y452443D01*
X950500Y452750D01*
X950552Y453057D01*
X950758Y453325D01*
X951068Y453555D01*
X951430Y453708D01*
X951843Y453785D01*
X952257D01*
X952670Y453708D01*
X953032Y453555D01*
X953342Y453325D01*
X953548Y453057D01*
X953600Y452750D01*
G01X952773Y453057D02*
X953600Y453517D01*
G01X951017Y455122D02*
X950707Y455352D01*
X950552Y455620D01*
X950500Y455927D01*
X950603Y456310D01*
X950862Y456578D01*
X951172Y456655D01*
X951482Y456617D01*
X951740Y456463D01*
X952257Y455697D01*
X952618Y455352D01*
X953135Y455122D01*
X953600Y455045D01*
Y456655D01*
G01Y458950D02*
X950500D01*
X951120Y458490D01*
G01X953600D02*
Y459410D01*
G01X952308Y461322D02*
X951947Y461590D01*
X951740Y461820D01*
X951637Y462127D01*
X951740Y462395D01*
X951947Y462587D01*
X952257Y462740D01*
X952618Y462778D01*
X952928Y462740D01*
X953238Y462587D01*
X953497Y462357D01*
X953600Y462088D01*
X953497Y461782D01*
X953187Y461513D01*
X952722Y461360D01*
X952205Y461322D01*
X951533Y461398D01*
X951172Y461513D01*
X950810Y461705D01*
X950552Y461973D01*
X950500Y462242D01*
X950603Y462510D01*
X950862Y462702D01*
G01X955092Y452501D02*
Y463337D01*
G01X964540Y452501D02*
X955092D01*
G01X964416Y443819D02*
X961216D01*
G01Y450019D02*
X964416D01*
G01X961216Y443819D02*
Y450019D01*
G01X955092Y463337D02*
X964540D01*
G01X957416Y465819D02*
X954216D01*
G01X957416Y472019D02*
Y465819D01*
G01X954216Y472019D02*
X957416D01*
G01X954216Y465819D02*
Y472019D01*
G01X958216D02*
X961416D01*
G01X958216Y465819D02*
Y472019D01*
G01X961416Y465819D02*
X958216D01*
G01X961416Y472019D02*
Y465819D01*
G01X957078Y480582D02*
Y477382D01*
G01X950878Y480582D02*
X957078D01*
G01X950878Y477382D02*
Y480582D01*
G01X957078Y477382D02*
X950878D01*
G01X957078Y485582D02*
Y482382D01*
G01X950878Y485582D02*
X957078D01*
G01X950878Y482382D02*
Y485582D01*
G01X957078Y482382D02*
X950878D01*
G01X957078Y493582D02*
Y490382D01*
G01X950878D02*
Y493582D01*
G01X957078Y490382D02*
X950878D01*
G01X957078Y486382D02*
X950878D01*
Y489582D01*
X957078D01*
Y486382D01*
G01X958708Y479707D02*
Y482807D01*
X959628D01*
X959935Y482652D01*
X960165Y482290D01*
X960242Y481877D01*
X960165Y481464D01*
X959973Y481154D01*
X959628Y480999D01*
X958708D01*
G01X961732Y482807D02*
Y480585D01*
X961885Y480120D01*
X962192Y479810D01*
X962575Y479707D01*
X962958Y479810D01*
X963265Y480120D01*
X963418Y480585D01*
Y482807D01*
G01X966135Y479707D02*
Y482807D01*
X964717Y480585D01*
X966633D01*
G01X968698Y479707D02*
X968775Y480379D01*
X968890Y480947D01*
X969043Y481464D01*
X969235Y482032D01*
X969542Y482807D01*
X968008D01*
G01X960581Y486594D02*
Y498798D01*
X975885D01*
Y486594D01*
X960581D01*
G01X949531Y503265D02*
X980623D01*
G01X949531Y518777D02*
Y503265D01*
G01X957078Y501582D02*
Y498382D01*
G01X950878Y501582D02*
X957078D01*
G01X950878Y498382D02*
Y501582D01*
G01X957078Y498382D02*
X950878D01*
G01Y493582D02*
X957078D01*
G01X950878Y494382D02*
Y497582D01*
G01X957078Y494382D02*
X950878D01*
G01X957078Y497582D02*
Y494382D01*
G01X950878Y497582D02*
X957078D01*
G01X973066Y520969D02*
X961066D01*
G01D02*
Y526969D01*
G01X946783Y519800D02*
Y522900D01*
X947703D01*
X948010Y522745D01*
X948240Y522383D01*
X948317Y521970D01*
X948240Y521557D01*
X948048Y521247D01*
X947703Y521092D01*
X946783D01*
G01X949807Y519800D02*
Y522900D01*
X950573D01*
X950880Y522745D01*
X951110Y522538D01*
X951302Y522228D01*
X951455Y521867D01*
X951493Y521350D01*
X951455Y520833D01*
X951302Y520472D01*
X951110Y520162D01*
X950880Y519955D01*
X950573Y519800D01*
X949807D01*
G01X953098Y520162D02*
X953367Y519903D01*
X953673Y519800D01*
X953980Y519903D01*
X954248Y520213D01*
X954440Y520678D01*
X954517Y521143D01*
Y521712D01*
X954440Y522177D01*
X954248Y522590D01*
X954018Y522797D01*
X953750Y522900D01*
X953443Y522797D01*
X953213Y522590D01*
X953060Y522280D01*
X952983Y521867D01*
X953060Y521505D01*
X953252Y521143D01*
X953482Y520937D01*
X953750Y520885D01*
X954057Y520988D01*
X954287Y521247D01*
X954517Y521712D01*
G01X956122Y522383D02*
X956352Y522693D01*
X956620Y522848D01*
X956927Y522900D01*
X957310Y522797D01*
X957578Y522538D01*
X957655Y522228D01*
X957617Y521918D01*
X957463Y521660D01*
X956697Y521143D01*
X956352Y520782D01*
X956122Y520265D01*
X956045Y519800D01*
X957655D01*
G01X980623Y518777D02*
X949531D01*
G01X961066Y526969D02*
X973066D01*
G01X947247Y538326D02*
Y535126D01*
G01Y533326D02*
Y530126D01*
G01Y529326D02*
Y526126D01*
G01X948504Y527036D02*
Y530136D01*
X949424D01*
X949731Y529981D01*
X949961Y529619D01*
X950038Y529206D01*
X949961Y528793D01*
X949769Y528483D01*
X949424Y528328D01*
X948504D01*
G01X951528Y530136D02*
Y527914D01*
X951681Y527449D01*
X951988Y527139D01*
X952371Y527036D01*
X952754Y527139D01*
X953061Y527449D01*
X953214Y527914D01*
Y530136D01*
G01X954743Y529619D02*
X954973Y529929D01*
X955241Y530084D01*
X955548Y530136D01*
X955931Y530033D01*
X956199Y529774D01*
X956276Y529464D01*
X956238Y529154D01*
X956084Y528896D01*
X955318Y528379D01*
X954973Y528018D01*
X954743Y527501D01*
X954666Y527036D01*
X956276D01*
G01X957728Y527656D02*
X957958Y527294D01*
X958264Y527088D01*
X958609Y527036D01*
X958916Y527088D01*
X959223Y527346D01*
X959414Y527656D01*
X959453Y527966D01*
X959376Y528328D01*
X959108Y528586D01*
X958839Y528689D01*
X958494D01*
G01X958839D02*
X959069Y528844D01*
X959261Y529103D01*
X959338Y529413D01*
X959261Y529723D01*
X959069Y529981D01*
X958724Y530136D01*
X958379Y530084D01*
X958034Y529878D01*
G01X950750Y533338D02*
Y545542D01*
X966054D01*
Y533338D01*
X950750D01*
G01X947247Y550326D02*
Y547126D01*
G01Y546326D02*
Y543126D01*
G01X961632Y556194D02*
X949632D01*
G01Y562194D02*
X961632D01*
G01X949632Y556194D02*
Y562194D01*
G01X961632Y564194D02*
X949632D01*
G01Y570194D02*
X961632D01*
G01X949632Y564194D02*
Y570194D01*
G01X961632Y572194D02*
X949632D01*
G01Y578194D02*
X961632D01*
G01X949632Y572194D02*
Y578194D01*
G01X956465Y604111D02*
Y599511D01*
G01X946265Y604111D02*
X956465D01*
G01X946265Y599511D02*
Y604111D01*
G01X956465Y599511D02*
X946265D01*
G01X959372Y598993D02*
Y595793D01*
G01X953172Y598993D02*
X959372D01*
G01X953172Y595793D02*
Y598993D01*
G01X959372Y595793D02*
X953172D01*
G01X946265Y605011D02*
Y609611D01*
G01X956465Y605011D02*
X946265D01*
G01X956465Y609611D02*
Y605011D01*
G01X946265Y609611D02*
X956465D01*
G01X948965Y622911D02*
Y619711D01*
G01X945965Y618411D02*
Y612211D01*
G01X946565Y618411D02*
X949765D01*
G01X946565Y612211D02*
Y618411D01*
G01X949765Y612211D02*
X946565D01*
G01X949765Y618411D02*
Y612211D01*
G01X950774Y615279D02*
X953274D01*
X952774Y615599D01*
G01X950774D02*
Y614959D01*
G01Y613079D02*
X953274D01*
X952774Y613399D01*
G01X950774D02*
Y612759D01*
G01X959989Y610750D02*
Y608250D01*
X960309Y608750D01*
G01Y610750D02*
X959669D01*
G01X958296Y608667D02*
X958136Y608417D01*
X957949Y608292D01*
X957736Y608250D01*
X957469Y608333D01*
X957282Y608542D01*
X957229Y608792D01*
X957256Y609042D01*
X957362Y609250D01*
X957896Y609667D01*
X958136Y609958D01*
X958296Y610375D01*
X958349Y610750D01*
X957229D01*
G01X953326Y620279D02*
Y618343D01*
G01Y613209D02*
X954491D01*
G01X953326Y616343D02*
Y613209D01*
G01X961965Y634711D02*
X958765D01*
G01D02*
Y640911D01*
G01X957965Y634711D02*
X954765D01*
G01X957965Y640911D02*
Y634711D01*
G01X954765D02*
Y640911D01*
G01X948965Y630911D02*
Y627711D01*
G01Y626911D02*
Y623711D01*
G01X952465Y634711D02*
X949265D01*
G01X952465Y640911D02*
Y634711D01*
G01X949265D02*
Y640911D01*
G01X959827Y632812D02*
X966027D01*
G01X959827Y629612D02*
Y632812D01*
G01X966027Y629612D02*
X959827D01*
G01X953618Y629352D02*
X953432Y629561D01*
X953218Y629644D01*
X953005Y629561D01*
X952818Y629311D01*
X952685Y628936D01*
X952632Y628561D01*
Y628102D01*
X952685Y627727D01*
X952818Y627394D01*
X952978Y627227D01*
X953165Y627144D01*
X953378Y627227D01*
X953538Y627394D01*
X953645Y627644D01*
X953698Y627977D01*
X953645Y628269D01*
X953512Y628561D01*
X953352Y628727D01*
X953165Y628769D01*
X952952Y628686D01*
X952792Y628477D01*
X952632Y628102D01*
G01X949432Y626011D02*
X951932D01*
X951432Y626331D01*
G01X949432D02*
Y625691D01*
G01X951932Y623811D02*
X951849Y624024D01*
X951640Y624184D01*
X951390Y624291D01*
X951057Y624371D01*
X950682Y624398D01*
X950307Y624371D01*
X949974Y624291D01*
X949724Y624184D01*
X949515Y624024D01*
X949432Y623811D01*
X949515Y623598D01*
X949724Y623438D01*
X949974Y623331D01*
X950307Y623251D01*
X950682Y623224D01*
X951057Y623251D01*
X951390Y623331D01*
X951640Y623438D01*
X951849Y623598D01*
X951932Y623811D01*
G01X953326Y625413D02*
Y622279D01*
G01X954491Y625413D02*
X953326D01*
G01X958765Y640911D02*
X961965D01*
G01X954765D02*
X957965D01*
G01X949265D02*
X952465D01*
G01X959903Y699732D02*
Y705932D01*
G01X963103Y699732D02*
X959903D01*
G01X951951D02*
Y705932D01*
G01X955151Y699732D02*
X951951D01*
G01X955151Y705932D02*
Y699732D01*
G01X955951D02*
Y705932D01*
G01X959151Y699732D02*
X955951D01*
G01X959151Y705932D02*
Y699732D01*
G01X949156Y700525D02*
X945956D01*
G01X949156Y706725D02*
Y700525D01*
G01X945956D02*
Y706725D01*
G01X951263Y707880D02*
Y724080D01*
G01X964263Y707880D02*
X951263D01*
G01X959903Y705932D02*
X963103D01*
G01X951951D02*
X955151D01*
G01X955951D02*
X959151D01*
G01X945956Y706725D02*
X949156D01*
G01X948290Y713269D02*
X947706D01*
G01X948290Y718781D02*
Y713269D01*
G01X951263Y724080D02*
X964263D01*
G01X957550Y726938D02*
X954350D01*
G01X957550Y733138D02*
Y726938D01*
G01X954350Y733138D02*
X957550D01*
G01X954350Y726938D02*
Y733138D01*
G01X958350D02*
X961550D01*
G01X958350Y726938D02*
Y733138D01*
G01X961550Y726938D02*
X958350D01*
G01X947706Y718781D02*
X948290D01*
G01X947928Y780867D02*
Y784067D01*
G01X954128Y780867D02*
X947928D01*
G01X954128Y784067D02*
Y780867D01*
G01X946034Y807839D02*
Y795241D01*
G01X947928Y784067D02*
X954128D01*
G01X948084Y797633D02*
Y800833D01*
G01X954284Y797633D02*
X948084D01*
G01X954284Y800833D02*
Y797633D01*
G01X947853Y784766D02*
Y787966D01*
G01X954053Y784766D02*
X947853D01*
G01X954053Y787966D02*
Y784766D01*
G01X947853Y787966D02*
X954053D01*
G01X954284Y794105D02*
Y790905D01*
G01X948084Y794105D02*
X954284D01*
G01X948084Y790905D02*
Y794105D01*
G01X954284Y790905D02*
X948084D01*
G01X947665Y804358D02*
X947358Y804410D01*
X947090Y804616D01*
X946860Y804926D01*
X946707Y805288D01*
X946630Y805701D01*
Y806115D01*
X946707Y806528D01*
X946860Y806890D01*
X947090Y807200D01*
X947358Y807406D01*
X947665Y807458D01*
X947972Y807406D01*
X948240Y807200D01*
X948470Y806890D01*
X948623Y806528D01*
X948700Y806115D01*
Y805701D01*
X948623Y805288D01*
X948470Y804926D01*
X948240Y804616D01*
X947972Y804410D01*
X947665Y804358D01*
G01X949960Y804771D02*
X950267Y804513D01*
X950612Y804358D01*
X950918D01*
X951225Y804513D01*
X951455Y804771D01*
X951570Y805133D01*
X951493Y805495D01*
X951302Y805805D01*
X950957Y806011D01*
X950497Y806115D01*
X950228Y806321D01*
X950113Y806683D01*
X950190Y807045D01*
X950382Y807303D01*
X950650Y807458D01*
X950918D01*
X951187Y807355D01*
X951417Y807096D01*
G01X954708Y807200D02*
X954478Y807355D01*
X954210Y807458D01*
X953903D01*
X953558Y807303D01*
X953290Y807045D01*
X953098Y806735D01*
X952945Y806218D01*
X952907Y805753D01*
X952983Y805288D01*
X953098Y804978D01*
X953328Y804668D01*
X953597Y804461D01*
X953865Y804358D01*
X954133D01*
X954402Y804461D01*
X954632Y804616D01*
X954823Y804823D01*
G01X956237Y806941D02*
X956467Y807251D01*
X956735Y807406D01*
X957042Y807458D01*
X957425Y807355D01*
X957693Y807096D01*
X957770Y806786D01*
X957732Y806476D01*
X957578Y806218D01*
X956812Y805701D01*
X956467Y805340D01*
X956237Y804823D01*
X956160Y804358D01*
X957770D01*
G01X948084Y800833D02*
X954284D01*
G01X945516Y816140D02*
Y809940D01*
G01X950535Y828657D02*
X947335D01*
G01X950535Y834857D02*
Y828657D01*
G01X947335D02*
Y834857D01*
G01X951935Y821757D02*
X948735D01*
G01X951935Y827957D02*
Y821757D01*
G01X948735D02*
Y827957D01*
G01D02*
X951935D01*
G01X960282Y829828D02*
X957082D01*
G01X960282Y836028D02*
Y829828D01*
G01X957082D02*
Y836028D01*
G01X951183Y828683D02*
Y834883D01*
G01X954383Y828683D02*
X951183D01*
G01X954383Y834883D02*
Y828683D01*
G01X946635Y834857D02*
Y828657D01*
G01X945335Y849257D02*
Y843057D01*
G01X947335Y834857D02*
X950535D01*
G01X952700Y843200D02*
Y837000D01*
X949500D01*
Y843200D01*
X952700D01*
G01X957082Y836028D02*
X960282D01*
G01X959157Y848265D02*
Y845065D01*
G01X952957D02*
Y848265D01*
G01X959157Y845065D02*
X952957D01*
G01X951183Y834883D02*
X954383D01*
G01X952243Y848235D02*
Y845035D01*
G01X946043D02*
Y848235D01*
G01X952243Y845035D02*
X946043D01*
G01X948800Y843200D02*
Y837000D01*
X945600D01*
Y843200D01*
X948800D01*
G01X956600Y837000D02*
Y843200D01*
X959800D01*
Y837000D01*
X956600D01*
G01X991731Y857677D02*
X951820D01*
G01X991731D02*
X952917D01*
G01X948500Y848900D02*
Y855100D01*
X951700D01*
Y848900D01*
X948500D01*
G01X952957Y848265D02*
X959157D01*
G01X946043Y848235D02*
X952243D01*
G01X949227Y866462D02*
Y863262D01*
G01X952400Y848900D02*
Y855100D01*
X955600D01*
Y848900D01*
X952400D01*
G01X959500Y855100D02*
Y848900D01*
X956300D01*
Y855100D01*
X959500D01*
G01X951841Y856290D02*
X946391D01*
G01X951841Y858590D02*
Y856290D01*
G01X946391Y858590D02*
X951841D01*
G01X946391Y856290D02*
Y858590D01*
G01X951841Y860290D02*
X946391D01*
G01X951841Y862590D02*
Y860290D01*
G01X946391Y862590D02*
X951841D01*
G01X946391Y860290D02*
Y862590D01*
G01X963631Y868345D02*
X960531D01*
X961151Y867885D01*
G01X963631D02*
Y868805D01*
G01X962339Y870717D02*
X961978Y870985D01*
X961771Y871215D01*
X961668Y871522D01*
X961771Y871790D01*
X961978Y871982D01*
X962288Y872135D01*
X962649Y872173D01*
X962959Y872135D01*
X963269Y871982D01*
X963528Y871752D01*
X963631Y871483D01*
X963528Y871177D01*
X963218Y870908D01*
X962753Y870755D01*
X962236Y870717D01*
X961564Y870793D01*
X961203Y870908D01*
X960841Y871100D01*
X960583Y871368D01*
X960531Y871637D01*
X960634Y871905D01*
X960893Y872097D01*
G01X949370Y879816D02*
Y876616D01*
G01X957798Y871878D02*
Y868678D01*
G01X951598Y871878D02*
X957798D01*
G01Y868678D02*
X951598D01*
G01D02*
Y871878D01*
G01X955724Y878470D02*
X952524D01*
G01X955724Y884670D02*
Y878470D01*
G01X952524D02*
Y884670D01*
G01X948995Y875418D02*
Y873118D01*
G01X949164Y884746D02*
Y881546D01*
G01X952524Y884670D02*
X955724D01*
G01X956664Y898290D02*
X951375D01*
G01X956664Y901490D02*
X951375D01*
G01X963169Y904693D02*
X963428Y904962D01*
X963531Y905268D01*
X963428Y905575D01*
X963118Y905843D01*
X962653Y906035D01*
X962188Y906112D01*
X961619D01*
X961154Y906035D01*
X960741Y905843D01*
X960534Y905613D01*
X960431Y905345D01*
X960534Y905038D01*
X960741Y904808D01*
X961051Y904655D01*
X961464Y904578D01*
X961826Y904655D01*
X962188Y904847D01*
X962394Y905077D01*
X962446Y905345D01*
X962343Y905652D01*
X962084Y905882D01*
X961619Y906112D01*
G01X946228Y914189D02*
Y907989D01*
G01X956664Y901490D02*
Y898290D01*
G01X946228Y927226D02*
Y921026D01*
G01X960967Y928719D02*
Y934919D01*
G01X964167Y928719D02*
X960967D01*
G01X956967D02*
Y934919D01*
G01X960167Y928719D02*
X956967D01*
G01X960167Y934919D02*
Y928719D01*
G01X956167D02*
X952967D01*
G01X956167Y934919D02*
Y928719D01*
G01X952967D02*
Y934919D01*
G01X948967Y928719D02*
Y934919D01*
G01X952167Y928719D02*
X948967D01*
G01X952167Y934919D02*
Y928719D01*
G01X960967Y934919D02*
X964167D01*
G01X956967D02*
X960167D01*
G01X952967D02*
X956167D01*
G01X948967D02*
X952167D01*
G01X963829Y950388D02*
X958278Y955939D01*
G01D02*
X963829Y961490D01*
G01X947271Y990343D02*
Y984143D01*
G01X952071Y990343D02*
X955271D01*
G01X952071Y984143D02*
Y990343D01*
G01X955271Y984143D02*
X952071D01*
G01X955271Y990343D02*
Y984143D01*
G01X959271D02*
X956071D01*
G01X959271Y990343D02*
Y984143D01*
G01X956071Y990343D02*
X959271D01*
G01X956071Y984143D02*
Y990343D01*
G01X960071D02*
X963271D01*
G01X960071Y984143D02*
Y990343D01*
G01X963271Y984143D02*
X960071D01*
G01X948071Y990343D02*
X951271D01*
G01X948071Y984143D02*
Y990343D01*
G01X951271Y984143D02*
X948071D01*
G01X951271Y990343D02*
Y984143D01*
G01X951285Y993937D02*
X945285D01*
Y1005937D01*
X951285D01*
Y993937D01*
G01X963410Y1005483D02*
Y995283D01*
X958810D01*
Y1005483D01*
X963410D01*
G01X958165Y993986D02*
X952165D01*
Y1005986D01*
X958165D01*
Y993986D01*
G01X952587Y1018753D02*
Y1012553D01*
X949387D01*
Y1018753D01*
X952587D01*
G01X956466D02*
Y1012553D01*
X953266D01*
Y1018753D01*
X956466D01*
G01X945666Y1030724D02*
X963368D01*
G01X945666Y1043865D02*
Y1030724D01*
G01Y1070024D02*
Y1057352D01*
G01X963368Y1070024D02*
X945666D01*
G01X957468Y1087763D02*
Y1089716D01*
G01X959421Y1087763D02*
X957468D01*
G01X958390Y1083987D02*
X956128Y1081725D01*
G01X954006Y1088371D02*
X958390Y1083987D01*
G01X951744Y1086109D02*
X954006Y1088371D01*
G01X956128Y1081725D02*
X951744Y1086109D01*
G01X950497Y1088975D02*
Y1085775D01*
G01X959291Y1083364D02*
X965491D01*
G01X959291Y1080164D02*
Y1083364D01*
G01X965491Y1080164D02*
X959291D01*
G01X957468Y1099575D02*
X959421D01*
G01X957468Y1097622D02*
Y1099575D01*
G01X955958Y1104360D02*
Y1101160D01*
G01X949758Y1104360D02*
X955958D01*
G01X949758Y1101160D02*
Y1104360D01*
G01X955958Y1101160D02*
X949758D01*
G01X952967Y1094049D02*
X949767D01*
G01X952967Y1100249D02*
Y1094049D01*
G01X949767Y1100249D02*
X952967D01*
G01X949767Y1094049D02*
Y1100249D01*
G01X973775Y1122803D02*
Y1129930D01*
X955121D01*
X952121Y1126930D01*
Y1122803D01*
G01Y1115403D02*
Y1111276D01*
X955121Y1108276D01*
G01D02*
X973775D01*
Y1115403D01*
G01X960730Y1132326D02*
Y1135526D01*
G01X966930Y1132326D02*
X960730D01*
G01Y1135526D02*
X966930D01*
G01X974516Y1141395D02*
X956922D01*
G01X947952Y1200522D02*
Y1203722D01*
G01X954152Y1200522D02*
X947952D01*
G01X954152Y1203722D02*
Y1200522D01*
G01X947952Y1203722D02*
X954152D01*
G01X954991Y1199653D02*
Y1202853D01*
G01X961191Y1199653D02*
X954991D01*
G01X961191Y1202853D02*
Y1199653D01*
G01X954991Y1202853D02*
X961191D01*
G01X959804Y1204308D02*
Y1210508D01*
G01X963004Y1204308D02*
X959804D01*
G01X956922Y1195331D02*
X974516D01*
G01X946710Y1205137D02*
Y1202137D01*
G01X962323Y1214267D02*
X959123D01*
G01Y1220467D02*
X962323D01*
G01X959123Y1214267D02*
Y1220467D01*
G01X957478Y1221112D02*
Y1224312D01*
G01X963678Y1221112D02*
X957478D01*
G01X959804Y1210508D02*
X963004D01*
G01X950210Y1206766D02*
X954012D01*
Y1207037D01*
G01X955710Y1214837D02*
X957210D01*
G01X952917Y1233991D02*
X964917D01*
G01X952917Y1227991D02*
Y1233991D01*
G01X964917Y1227991D02*
X952917D01*
G01Y1234891D02*
Y1240891D01*
G01X964917Y1234891D02*
X952917D01*
G01X949917Y1232591D02*
Y1226591D01*
G01Y1239491D02*
Y1233491D01*
G01X957478Y1224312D02*
X963678D01*
G01X955908Y1223747D02*
X956117Y1223933D01*
X956200Y1224147D01*
X956117Y1224360D01*
X955867Y1224547D01*
X955492Y1224680D01*
X955117Y1224733D01*
X954658D01*
X954283Y1224680D01*
X953950Y1224547D01*
X953783Y1224387D01*
X953700Y1224200D01*
X953783Y1223987D01*
X953950Y1223827D01*
X954200Y1223720D01*
X954533Y1223667D01*
X954825Y1223720D01*
X955117Y1223853D01*
X955283Y1224013D01*
X955325Y1224200D01*
X955242Y1224413D01*
X955033Y1224573D01*
X954658Y1224733D01*
G01X954012Y1222637D02*
Y1222908D01*
G01D02*
X950210D01*
G01X949110Y1224537D02*
Y1227537D01*
G01X952792Y1249522D02*
Y1259522D01*
G01X957392D02*
Y1249522D01*
G01X952792D02*
X957392D01*
G01X952917Y1240891D02*
X964917D01*
G01X952917Y1247791D02*
X964917D01*
G01X952917Y1241791D02*
Y1247791D01*
G01X964917Y1241791D02*
X952917D01*
G01X949917Y1246391D02*
Y1240391D01*
G01Y1253291D02*
Y1247291D01*
G01X957292Y1259522D02*
X957392D01*
G01X952792D02*
X957392D01*
G01X951794Y1259051D02*
Y1255851D01*
G01X945594Y1259051D02*
X951794D01*
G01X945594Y1255851D02*
Y1259051D01*
G01X951794Y1255851D02*
X945594D01*
G01X955897Y1364251D02*
Y1365967D01*
G01Y1357284D02*
Y1357639D01*
G01X975583Y1357284D02*
X955897D01*
G01Y1408837D02*
Y1410553D01*
G01X959960Y1422450D02*
Y1425550D01*
X960880D01*
X961187Y1425395D01*
X961417Y1425033D01*
X961494Y1424620D01*
X961417Y1424207D01*
X961225Y1423897D01*
X960880Y1423742D01*
X959960D01*
G01X963827Y1422450D02*
X963520Y1422502D01*
X963252Y1422708D01*
X963022Y1423018D01*
X962869Y1423380D01*
X962792Y1423793D01*
Y1424207D01*
X962869Y1424620D01*
X963022Y1424982D01*
X963252Y1425292D01*
X963520Y1425498D01*
X963827Y1425550D01*
X964134Y1425498D01*
X964402Y1425292D01*
X964632Y1424982D01*
X964785Y1424620D01*
X964862Y1424207D01*
Y1423793D01*
X964785Y1423380D01*
X964632Y1423018D01*
X964402Y1422708D01*
X964134Y1422502D01*
X963827Y1422450D01*
G01X964134Y1423277D02*
X964594Y1422450D01*
G01X966199Y1423742D02*
X966467Y1424103D01*
X966697Y1424310D01*
X967004Y1424413D01*
X967272Y1424310D01*
X967464Y1424103D01*
X967617Y1423793D01*
X967655Y1423432D01*
X967617Y1423122D01*
X967464Y1422812D01*
X967234Y1422553D01*
X966965Y1422450D01*
X966659Y1422553D01*
X966390Y1422863D01*
X966237Y1423328D01*
X966199Y1423845D01*
X966275Y1424517D01*
X966390Y1424878D01*
X966582Y1425240D01*
X966850Y1425498D01*
X967119Y1425550D01*
X967387Y1425447D01*
X967579Y1425188D01*
G01X969299Y1423742D02*
X969567Y1424103D01*
X969797Y1424310D01*
X970104Y1424413D01*
X970372Y1424310D01*
X970564Y1424103D01*
X970717Y1423793D01*
X970755Y1423432D01*
X970717Y1423122D01*
X970564Y1422812D01*
X970334Y1422553D01*
X970065Y1422450D01*
X969759Y1422553D01*
X969490Y1422863D01*
X969337Y1423328D01*
X969299Y1423845D01*
X969375Y1424517D01*
X969490Y1424878D01*
X969682Y1425240D01*
X969950Y1425498D01*
X970219Y1425550D01*
X970487Y1425447D01*
X970679Y1425188D01*
G01X973127Y1425550D02*
X972820Y1425447D01*
X972590Y1425188D01*
X972437Y1424878D01*
X972322Y1424465D01*
X972284Y1424000D01*
X972322Y1423535D01*
X972437Y1423122D01*
X972590Y1422812D01*
X972820Y1422553D01*
X973127Y1422450D01*
X973434Y1422553D01*
X973664Y1422812D01*
X973817Y1423122D01*
X973932Y1423535D01*
X973970Y1424000D01*
X973932Y1424465D01*
X973817Y1424878D01*
X973664Y1425188D01*
X973434Y1425447D01*
X973127Y1425550D01*
G01X975499Y1425033D02*
X975729Y1425343D01*
X975997Y1425498D01*
X976304Y1425550D01*
X976687Y1425447D01*
X976955Y1425188D01*
X977032Y1424878D01*
X976994Y1424568D01*
X976840Y1424310D01*
X976074Y1423793D01*
X975729Y1423432D01*
X975499Y1422915D01*
X975422Y1422450D01*
X977032D01*
G01X955897Y1417520D02*
X975583D01*
G01X955897Y1417165D02*
Y1417520D01*
G01X952043Y1465202D02*
Y1446698D01*
X951110D01*
G01X958168Y1446951D02*
X957335D01*
Y1465455D01*
X957968D01*
G01X951410Y1465202D02*
X952043D01*
G01X979732Y1590307D02*
X961232D01*
G01X954772D02*
X951242D01*
G01X973236Y-79278D02*
Y-62678D01*
X982836D01*
Y-79278D01*
X973236D01*
G01X968607Y-59100D02*
Y-56000D01*
X969373D01*
X969680Y-56155D01*
X969910Y-56362D01*
X970102Y-56672D01*
X970255Y-57033D01*
X970293Y-57550D01*
X970255Y-58067D01*
X970102Y-58428D01*
X969910Y-58738D01*
X969680Y-58945D01*
X969373Y-59100D01*
X968607D01*
G01X973317D02*
X971783D01*
Y-56000D01*
X973317D01*
G01X972703Y-57498D02*
X971783D01*
G01X975650Y-56000D02*
X975343Y-56103D01*
X975113Y-56362D01*
X974960Y-56672D01*
X974845Y-57085D01*
X974807Y-57550D01*
X974845Y-58015D01*
X974960Y-58428D01*
X975113Y-58738D01*
X975343Y-58997D01*
X975650Y-59100D01*
X975957Y-58997D01*
X976187Y-58738D01*
X976340Y-58428D01*
X976455Y-58015D01*
X976493Y-57550D01*
X976455Y-57085D01*
X976340Y-56672D01*
X976187Y-56362D01*
X975957Y-56103D01*
X975650Y-56000D01*
G01X978750Y-59100D02*
Y-56000D01*
X978290Y-56620D01*
G01Y-59100D02*
X979210D01*
G01X981122D02*
Y-56000D01*
X982578D01*
G01X982042Y-57498D02*
X981122D01*
G01X983800Y-60133D02*
X986100D01*
G01X988050Y-59100D02*
Y-56000D01*
X987590Y-56620D01*
G01Y-59100D02*
X988510D01*
G01X977322Y58150D02*
Y104600D01*
G01X977618Y57756D02*
Y104600D01*
G01Y57756D02*
X971237D01*
G01X977322Y58150D02*
X971642D01*
G01X977618Y111507D02*
Y107060D01*
G01X977322Y111507D02*
Y107060D01*
G01Y118680D02*
Y114087D01*
G01X977618Y118680D02*
Y114087D01*
G01X977322Y132859D02*
Y128325D01*
G01X977618Y132859D02*
Y128325D01*
G01Y125844D02*
Y121329D01*
G01X977322Y125844D02*
Y121329D01*
G01X977618Y153150D02*
Y135401D01*
G01X977322Y152756D02*
Y135401D01*
G01X965268Y156615D02*
X966015Y155990D01*
X966855Y155615D01*
X967601D01*
X968348Y155990D01*
X968908Y156615D01*
X969188Y157490D01*
X969001Y158365D01*
X968535Y159115D01*
X967695Y159615D01*
X966575Y159865D01*
X965921Y160365D01*
X965641Y161240D01*
X965828Y162115D01*
X966295Y162740D01*
X966948Y163115D01*
X967601D01*
X968255Y162865D01*
X968815Y162240D01*
G01X972768Y156615D02*
X973515Y155990D01*
X974355Y155615D01*
X975101D01*
X975848Y155990D01*
X976408Y156615D01*
X976688Y157490D01*
X976501Y158365D01*
X976035Y159115D01*
X975195Y159615D01*
X974075Y159865D01*
X973421Y160365D01*
X973141Y161240D01*
X973328Y162115D01*
X973795Y162740D01*
X974448Y163115D01*
X975101D01*
X975755Y162865D01*
X976315Y162240D01*
G01X980175Y155615D02*
Y163115D01*
X982041D01*
X982788Y162740D01*
X983348Y162240D01*
X983815Y161490D01*
X984188Y160615D01*
X984281Y159365D01*
X984188Y158115D01*
X983815Y157240D01*
X983348Y156490D01*
X982788Y155990D01*
X982041Y155615D01*
X980175D01*
G01X989728D02*
X990381Y155740D01*
X991128Y156115D01*
X991595Y156740D01*
X991781Y157615D01*
X991595Y158490D01*
X991035Y159240D01*
X990195Y159615D01*
X989261D01*
X988701Y159865D01*
X988235Y160490D01*
X988048Y161365D01*
X988328Y162240D01*
X988981Y162865D01*
X989728Y163115D01*
X990475Y162865D01*
X991128Y162240D01*
X991408Y161365D01*
X991221Y160490D01*
X990755Y159865D01*
X990195Y159615D01*
X989261D01*
X988421Y159240D01*
X987861Y158490D01*
X987675Y157615D01*
X987861Y156740D01*
X988328Y156115D01*
X989075Y155740D01*
X989728Y155615D01*
G01X969718Y164436D02*
X984518D01*
G01X969718Y195440D02*
Y164436D01*
G01X971237Y153150D02*
X977618D01*
G01X971642Y152756D02*
X977322D01*
G01X984518Y195440D02*
X969718D01*
G01X973721Y199912D02*
Y202338D01*
G01X966800Y203983D02*
X963700D01*
Y204903D01*
X963855Y205210D01*
X964217Y205440D01*
X964630Y205517D01*
X965043Y205440D01*
X965353Y205248D01*
X965508Y204903D01*
Y203983D01*
G01X966800Y207007D02*
X963700D01*
Y207773D01*
X963855Y208080D01*
X964062Y208310D01*
X964372Y208502D01*
X964733Y208655D01*
X965250Y208693D01*
X965767Y208655D01*
X966128Y208502D01*
X966438Y208310D01*
X966645Y208080D01*
X966800Y207773D01*
Y207007D01*
G01Y210950D02*
X963700D01*
X964320Y210490D01*
G01X966800D02*
Y211410D01*
G01Y214050D02*
X963700D01*
X964320Y213590D01*
G01X966800D02*
Y214510D01*
G01Y217150D02*
X963700D01*
X964320Y216690D01*
G01X966800D02*
Y217610D01*
G01X979769Y203452D02*
X968273D01*
G01D02*
Y233011D01*
G01X973621Y236652D02*
Y234412D01*
G01X975246Y235625D02*
X971996D01*
G01X968273Y233011D02*
X979769D01*
G01X973490Y259204D02*
Y261630D01*
G01X966400Y263383D02*
X963300D01*
Y264303D01*
X963455Y264610D01*
X963817Y264840D01*
X964230Y264917D01*
X964643Y264840D01*
X964953Y264648D01*
X965108Y264303D01*
Y263383D01*
G01X966400Y266407D02*
X963300D01*
Y267173D01*
X963455Y267480D01*
X963662Y267710D01*
X963972Y267902D01*
X964333Y268055D01*
X964850Y268093D01*
X965367Y268055D01*
X965728Y267902D01*
X966038Y267710D01*
X966245Y267480D01*
X966400Y267173D01*
Y266407D01*
G01X965780Y269507D02*
X966142Y269737D01*
X966348Y270043D01*
X966400Y270388D01*
X966348Y270695D01*
X966090Y271002D01*
X965780Y271193D01*
X965470Y271232D01*
X965108Y271155D01*
X964850Y270887D01*
X964747Y270618D01*
Y270273D01*
G01Y270618D02*
X964592Y270848D01*
X964333Y271040D01*
X964023Y271117D01*
X963713Y271040D01*
X963455Y270848D01*
X963300Y270503D01*
X963352Y270158D01*
X963558Y269813D01*
G01X966400Y273450D02*
X966348Y273718D01*
X966193Y274025D01*
X965935Y274217D01*
X965573Y274293D01*
X965212Y274217D01*
X964902Y273987D01*
X964747Y273642D01*
Y273258D01*
X964643Y273028D01*
X964385Y272837D01*
X964023Y272760D01*
X963662Y272875D01*
X963403Y273143D01*
X963300Y273450D01*
X963403Y273757D01*
X963662Y274025D01*
X964023Y274140D01*
X964385Y274063D01*
X964643Y273872D01*
X964747Y273642D01*
Y273258D01*
X964902Y272913D01*
X965212Y272683D01*
X965573Y272607D01*
X965935Y272683D01*
X966193Y272875D01*
X966348Y273182D01*
X966400Y273450D01*
G01X979538Y262744D02*
X968042D01*
G01D02*
Y292303D01*
G01X977563Y296195D02*
Y293955D01*
G01X979188Y295168D02*
X975938D01*
G01X968042Y292303D02*
X979538D01*
G01X973855Y308474D02*
Y323726D01*
G01X985971Y308474D02*
X973855D01*
G01Y323726D02*
X985971D01*
G01X976506Y341512D02*
Y344712D01*
G01X982706Y341512D02*
X976506D01*
G01Y348212D02*
X982706D01*
G01X976506Y345012D02*
Y348212D01*
G01X982706Y345012D02*
X976506D01*
G01Y344712D02*
X982706D01*
G01X974332Y438394D02*
Y444594D01*
G01X977532Y438394D02*
X974332D01*
G01X977532Y444594D02*
Y438394D01*
G01X970332D02*
Y444594D01*
G01X973532Y438394D02*
X970332D01*
G01X973532Y444594D02*
Y438394D01*
G01X964540Y455919D02*
Y452501D01*
G01X962816Y457919D02*
X964540Y455919D01*
G01Y459919D02*
X962816Y457919D01*
G01X967509Y456438D02*
X970709D01*
G01X967509Y450238D02*
Y456438D01*
G01X970709Y450238D02*
X967509D01*
G01X970709Y456438D02*
Y450238D01*
G01X964416Y450019D02*
Y443819D01*
G01X974332Y444594D02*
X977532D01*
G01X970332D02*
X973532D01*
G01X966233Y445400D02*
Y448500D01*
X967153D01*
X967460Y448345D01*
X967690Y447983D01*
X967767Y447570D01*
X967690Y447157D01*
X967498Y446847D01*
X967153Y446692D01*
X966233D01*
G01X969257Y448500D02*
Y446278D01*
X969410Y445813D01*
X969717Y445503D01*
X970100Y445400D01*
X970483Y445503D01*
X970790Y445813D01*
X970943Y446278D01*
Y448500D01*
G01X973200Y445400D02*
Y448500D01*
X972740Y447880D01*
G01Y445400D02*
X973660D01*
G01X976300D02*
Y448500D01*
X975840Y447880D01*
G01Y445400D02*
X976760D01*
G01X978748Y445762D02*
X979017Y445503D01*
X979323Y445400D01*
X979630Y445503D01*
X979898Y445813D01*
X980090Y446278D01*
X980167Y446743D01*
Y447312D01*
X980090Y447777D01*
X979898Y448190D01*
X979668Y448397D01*
X979400Y448500D01*
X979093Y448397D01*
X978863Y448190D01*
X978710Y447880D01*
X978633Y447467D01*
X978710Y447105D01*
X978902Y446743D01*
X979132Y446537D01*
X979400Y446485D01*
X979707Y446588D01*
X979937Y446847D01*
X980167Y447312D01*
G01X972446Y449607D02*
Y461381D01*
G01X982208Y449607D02*
X972446D01*
G01X964540Y463337D02*
Y459919D01*
G01X973997Y465879D02*
X970797D01*
G01X973997Y472079D02*
Y465879D01*
G01X970797Y472079D02*
X973997D01*
G01X970797Y465879D02*
Y472079D01*
G01X962216Y472019D02*
X965416D01*
G01X962216Y465819D02*
Y472019D01*
G01X965416Y465819D02*
X962216D01*
G01X965416Y472019D02*
Y465819D01*
G01X974797Y472159D02*
X977997D01*
G01X974797Y465959D02*
Y472159D01*
G01X977997Y465959D02*
X974797D01*
G01X969416Y465819D02*
X966216D01*
G01X969416Y472019D02*
Y465819D01*
G01X966216Y472019D02*
X969416D01*
G01X966216Y465819D02*
Y472019D01*
G01X972446Y461381D02*
X982208D01*
G01X982876Y474988D02*
X970876D01*
G01Y480988D02*
X982876D01*
G01X970876Y474988D02*
Y480988D01*
G01X972876Y481788D02*
Y484988D01*
G01X979076Y481788D02*
X972876D01*
G01Y484988D02*
X979076D01*
G01X973066Y526969D02*
Y520969D01*
G01X973906Y528555D02*
Y540555D01*
G01X979906Y528555D02*
X973906D01*
G01X969087Y538508D02*
X972287D01*
G01X969087Y532308D02*
Y538508D01*
G01X972287Y532308D02*
X969087D01*
G01X972287Y538508D02*
Y532308D01*
G01X963066Y527669D02*
Y530869D01*
G01X969266Y527669D02*
X963066D01*
G01X969266Y530869D02*
Y527669D01*
G01X963066Y530869D02*
X969266D01*
G01X973906Y540555D02*
X979906D01*
G01X975082Y568248D02*
Y553448D01*
G01D02*
X1006086D01*
G01X961632Y562194D02*
Y556194D01*
G01Y570194D02*
Y564194D01*
G01X1006086Y568248D02*
X975082D01*
G01X961632Y578194D02*
Y572194D01*
G01X973846Y585813D02*
X971420D01*
G01X970306Y591861D02*
Y580365D01*
G01X976981Y580432D02*
X980181D01*
G01X976981Y574232D02*
Y580432D01*
G01X980181Y574232D02*
X976981D01*
G01X976257Y598125D02*
Y604325D01*
G01X979457Y598125D02*
X976257D01*
G01X972257D02*
Y604325D01*
G01X975457Y598125D02*
X972257D01*
G01X975457Y604325D02*
Y598125D01*
G01X969765Y606711D02*
Y609911D01*
G01X975965Y606711D02*
X969765D01*
G01X975965Y609911D02*
Y606711D01*
G01X969765Y609911D02*
X975965D01*
G01X976257Y604325D02*
X979457D01*
G01X972257D02*
X975457D01*
G01X977975Y622529D02*
X978225Y622369D01*
X978350Y622182D01*
X978392Y621969D01*
X978309Y621702D01*
X978100Y621515D01*
X977850Y621462D01*
X977600Y621489D01*
X977392Y621595D01*
X976975Y622129D01*
X976684Y622369D01*
X976267Y622529D01*
X975892Y622582D01*
Y621462D01*
G01Y619822D02*
X978392D01*
X977892Y620142D01*
G01X975892D02*
Y619502D01*
G01X975059Y618422D02*
Y616822D01*
G01X977975Y615929D02*
X978225Y615769D01*
X978350Y615582D01*
X978392Y615369D01*
X978309Y615102D01*
X978100Y614915D01*
X977850Y614862D01*
X977600Y614889D01*
X977392Y614995D01*
X976975Y615529D01*
X976684Y615769D01*
X976267Y615929D01*
X975892Y615982D01*
Y614862D01*
G01X977975Y613729D02*
X978225Y613569D01*
X978350Y613382D01*
X978392Y613169D01*
X978309Y612902D01*
X978100Y612715D01*
X977850Y612662D01*
X977600Y612689D01*
X977392Y612795D01*
X976975Y613329D01*
X976684Y613569D01*
X976267Y613729D01*
X975892Y613782D01*
Y612662D01*
G01X979762Y609223D02*
X979602Y608973D01*
X979415Y608848D01*
X979202Y608806D01*
X978935Y608889D01*
X978748Y609098D01*
X978695Y609348D01*
X978722Y609598D01*
X978828Y609806D01*
X979362Y610223D01*
X979602Y610514D01*
X979762Y610931D01*
X979815Y611306D01*
X978695D01*
G01X977055Y608806D02*
X977268Y608889D01*
X977428Y609098D01*
X977535Y609348D01*
X977615Y609681D01*
X977642Y610056D01*
X977615Y610431D01*
X977535Y610764D01*
X977428Y611014D01*
X977268Y611223D01*
X977055Y611306D01*
X976842Y611223D01*
X976682Y611014D01*
X976575Y610764D01*
X976495Y610431D01*
X976468Y610056D01*
X976495Y609681D01*
X976575Y609348D01*
X976682Y609098D01*
X976842Y608889D01*
X977055Y608806D01*
G01X973404Y613209D02*
Y616350D01*
G01X972239Y613209D02*
X973404D01*
G01Y618361D02*
Y620261D01*
G01X969965Y634711D02*
X966765D01*
G01X969965Y640911D02*
Y634711D01*
G01X966765D02*
Y640911D01*
G01X973765Y634711D02*
Y640911D01*
G01X976965Y634711D02*
X973765D01*
G01X976965Y640911D02*
Y634711D01*
G01X979761Y623567D02*
X976561D01*
G01Y629767D02*
X979761D01*
G01X976561Y623567D02*
Y629767D01*
G01X961965Y640911D02*
Y634711D01*
G01X970265D02*
Y640911D01*
G01X973465Y634711D02*
X970265D01*
G01X973465Y640911D02*
Y634711D01*
G01X977265D02*
Y640911D01*
G01X980465Y634711D02*
X977265D01*
G01X965965D02*
X962765D01*
G01X965965Y640911D02*
Y634711D01*
G01X962765D02*
Y640911D01*
G01X966027Y632812D02*
Y629612D01*
G01X967183Y630400D02*
Y633500D01*
X968103D01*
X968410Y633345D01*
X968640Y632983D01*
X968717Y632570D01*
X968640Y632157D01*
X968448Y631847D01*
X968103Y631692D01*
X967183D01*
G01X970207Y633500D02*
Y631278D01*
X970360Y630813D01*
X970667Y630503D01*
X971050Y630400D01*
X971433Y630503D01*
X971740Y630813D01*
X971893Y631278D01*
Y633500D01*
G01X974150Y630400D02*
Y633500D01*
X973690Y632880D01*
G01Y630400D02*
X974610D01*
G01X977250Y633500D02*
X976943Y633397D01*
X976713Y633138D01*
X976560Y632828D01*
X976445Y632415D01*
X976407Y631950D01*
X976445Y631485D01*
X976560Y631072D01*
X976713Y630762D01*
X976943Y630503D01*
X977250Y630400D01*
X977557Y630503D01*
X977787Y630762D01*
X977940Y631072D01*
X978055Y631485D01*
X978093Y631950D01*
X978055Y632415D01*
X977940Y632828D01*
X977787Y633138D01*
X977557Y633397D01*
X977250Y633500D01*
G01X979507Y631020D02*
X979737Y630658D01*
X980043Y630452D01*
X980388Y630400D01*
X980695Y630452D01*
X981002Y630710D01*
X981193Y631020D01*
X981232Y631330D01*
X981155Y631692D01*
X980887Y631950D01*
X980618Y632053D01*
X980273D01*
G01X980618D02*
X980848Y632208D01*
X981040Y632467D01*
X981117Y632777D01*
X981040Y633087D01*
X980848Y633345D01*
X980503Y633500D01*
X980158Y633448D01*
X979813Y633242D01*
G01X973404Y625413D02*
X972231D01*
G01X973404Y622272D02*
Y625413D01*
G01X966765Y640911D02*
X969965D01*
G01X973765D02*
X976965D01*
G01X970265D02*
X973465D01*
G01X977265D02*
X980465D01*
G01X962765D02*
X965965D01*
G01X963103Y705932D02*
Y699732D01*
G01X965121Y711038D02*
X967343D01*
X967808Y711191D01*
X968118Y711498D01*
X968221Y711881D01*
X968118Y712264D01*
X967808Y712571D01*
X967343Y712724D01*
X965121D01*
G01X967601Y714138D02*
X967963Y714368D01*
X968169Y714674D01*
X968221Y715019D01*
X968169Y715326D01*
X967911Y715633D01*
X967601Y715824D01*
X967291Y715863D01*
X966929Y715786D01*
X966671Y715518D01*
X966568Y715249D01*
Y714904D01*
G01Y715249D02*
X966413Y715479D01*
X966154Y715671D01*
X965844Y715748D01*
X965534Y715671D01*
X965276Y715479D01*
X965121Y715134D01*
X965173Y714789D01*
X965379Y714444D01*
G01X965638Y717353D02*
X965328Y717583D01*
X965173Y717851D01*
X965121Y718158D01*
X965224Y718541D01*
X965483Y718809D01*
X965793Y718886D01*
X966103Y718848D01*
X966361Y718694D01*
X966878Y717928D01*
X967239Y717583D01*
X967756Y717353D01*
X968221Y717276D01*
Y718886D01*
G01X967756Y720338D02*
X968014Y720568D01*
X968169Y720836D01*
X968221Y721181D01*
X968118Y721526D01*
X967911Y721794D01*
X967549Y721986D01*
X967136Y722024D01*
X966723Y721948D01*
X966464Y721756D01*
X966258Y721488D01*
X966206Y721219D01*
X966258Y720951D01*
X966464Y720606D01*
X965121Y720721D01*
Y721756D01*
G01X964263Y714480D02*
Y707880D01*
G01X961763Y715980D02*
X964263Y714480D01*
G01Y717480D02*
X961763Y715980D01*
G01X964263Y724080D02*
Y717480D01*
G01X975312Y721189D02*
Y714989D01*
G01X972112D02*
Y721189D01*
G01X975312Y714989D02*
X972112D01*
G01Y721189D02*
X975312D01*
G01X961550Y733138D02*
Y726938D01*
G01X962350Y733138D02*
X965550D01*
G01X962350Y726938D02*
Y733138D01*
G01X965550Y726938D02*
X962350D01*
G01X965550Y733138D02*
Y726938D01*
G01X971985Y833399D02*
X978185D01*
Y830199D01*
X971985D01*
Y833399D01*
G01X971991Y829507D02*
X978191D01*
Y826307D01*
X971991D01*
Y829507D01*
G01X974203Y839659D02*
Y845659D01*
G01D02*
X986203D01*
G01Y839659D02*
X974203D01*
G01X964388Y857677D02*
X991731D01*
G01X964388D02*
Y917913D01*
G01X977105Y867145D02*
X984396D01*
G01X977105Y908445D02*
Y867145D01*
G01X1006987Y908445D02*
X977105D01*
G01X964388Y917913D02*
X1019074D01*
G01X965146Y928692D02*
Y934892D01*
G01X968346Y928692D02*
X965146D01*
G01X968346Y934892D02*
Y928692D01*
G01X964167Y934919D02*
Y928719D01*
G01X965146Y934892D02*
X968346D01*
G01X965500Y950707D02*
X967722D01*
X968187Y950860D01*
X968497Y951167D01*
X968600Y951550D01*
X968497Y951933D01*
X968187Y952240D01*
X967722Y952393D01*
X965500D01*
G01X968600Y955110D02*
X965500D01*
X967722Y953692D01*
Y955608D01*
G01X968600Y957750D02*
X965500D01*
X966120Y957290D01*
G01X968600D02*
Y958210D01*
G01X968238Y960198D02*
X968497Y960467D01*
X968600Y960773D01*
X968497Y961080D01*
X968187Y961348D01*
X967722Y961540D01*
X967257Y961617D01*
X966688D01*
X966223Y961540D01*
X965810Y961348D01*
X965603Y961118D01*
X965500Y960850D01*
X965603Y960543D01*
X965810Y960313D01*
X966120Y960160D01*
X966533Y960083D01*
X966895Y960160D01*
X967257Y960352D01*
X967463Y960582D01*
X967515Y960850D01*
X967412Y961157D01*
X967153Y961387D01*
X966688Y961617D01*
G01X963829Y947681D02*
Y950388D01*
G01Y961490D02*
Y964197D01*
G01X964071Y990343D02*
X967271D01*
G01X964071Y984143D02*
Y990343D01*
G01X967271Y984143D02*
X964071D01*
G01X967271Y990343D02*
Y984143D01*
G01X963271Y990343D02*
Y984143D01*
G01X975380Y1005656D02*
Y995456D01*
X970780D01*
Y1005656D01*
X975380D01*
G01X982129Y994759D02*
X976129D01*
Y1006759D01*
X982129D01*
Y994759D01*
G01X970028Y994035D02*
X964028D01*
Y1006035D01*
X970028D01*
Y994035D01*
G01X969225Y1018984D02*
Y1012784D01*
X966025D01*
Y1018984D01*
X969225D01*
G01X973360Y1019004D02*
Y1012804D01*
X970160D01*
Y1019004D01*
X973360D01*
G01X965423Y1018840D02*
Y1012640D01*
X962223D01*
Y1018840D01*
X965423D01*
G01X977259Y1019025D02*
Y1012825D01*
X974059D01*
Y1019025D01*
X977259D01*
G01X963368Y1030724D02*
Y1043778D01*
G01Y1057698D02*
Y1070024D01*
G01X964660Y1055132D02*
Y1046232D01*
G01X962578Y1078560D02*
Y1076338D01*
X962731Y1075873D01*
X963038Y1075563D01*
X963421Y1075460D01*
X963804Y1075563D01*
X964111Y1075873D01*
X964264Y1076338D01*
Y1078560D01*
G01X965869Y1075822D02*
X966138Y1075563D01*
X966444Y1075460D01*
X966751Y1075563D01*
X967019Y1075873D01*
X967211Y1076338D01*
X967288Y1076803D01*
Y1077372D01*
X967211Y1077837D01*
X967019Y1078250D01*
X966789Y1078457D01*
X966521Y1078560D01*
X966214Y1078457D01*
X965984Y1078250D01*
X965831Y1077940D01*
X965754Y1077527D01*
X965831Y1077165D01*
X966023Y1076803D01*
X966253Y1076597D01*
X966521Y1076545D01*
X966828Y1076648D01*
X967058Y1076907D01*
X967288Y1077372D01*
G01X970081Y1075460D02*
Y1078560D01*
X968663Y1076338D01*
X970579D01*
G01X973651Y1075059D02*
Y1078259D01*
G01X979851Y1075059D02*
X973651D01*
G01X969280Y1089716D02*
Y1087763D01*
G01D02*
X967327D01*
G01X973651Y1078259D02*
X979851D01*
G01X973651Y1091059D02*
Y1094259D01*
G01X979851Y1091059D02*
X973651D01*
G01Y1087059D02*
Y1090259D01*
G01X979851Y1087059D02*
X973651D01*
G01Y1090259D02*
X979851D01*
G01X973651Y1083059D02*
Y1086259D01*
G01X979851Y1083059D02*
X973651D01*
G01Y1086259D02*
X979851D01*
G01X973651Y1079059D02*
Y1082259D01*
G01X979851Y1079059D02*
X973651D01*
G01Y1082259D02*
X979851D01*
G01X965491Y1083364D02*
Y1080164D01*
G01X969280Y1099575D02*
Y1097622D01*
G01X967327Y1099575D02*
X969280D01*
G01X973651Y1094259D02*
X979851D01*
G01X973651Y1102259D02*
X979851D01*
G01X973651Y1099059D02*
Y1102259D01*
G01X979851Y1099059D02*
X973651D01*
G01Y1106259D02*
X979851D01*
G01X973651Y1103059D02*
Y1106259D01*
G01X979851Y1103059D02*
X973651D01*
G01Y1095059D02*
Y1098259D01*
G01X979851Y1095059D02*
X973651D01*
G01Y1098259D02*
X979851D01*
G01X966930Y1135526D02*
Y1132326D01*
G01X974516Y1195331D02*
Y1141395D01*
G01X980649Y1182609D02*
X977549D01*
Y1183529D01*
X977704Y1183836D01*
X978066Y1184066D01*
X978479Y1184143D01*
X978892Y1184066D01*
X979202Y1183874D01*
X979357Y1183529D01*
Y1182609D01*
G01X977549Y1185709D02*
X980649D01*
Y1187243D01*
G01X978066Y1188848D02*
X977756Y1189078D01*
X977601Y1189346D01*
X977549Y1189653D01*
X977652Y1190036D01*
X977911Y1190304D01*
X978221Y1190381D01*
X978531Y1190343D01*
X978789Y1190189D01*
X979306Y1189423D01*
X979667Y1189078D01*
X980184Y1188848D01*
X980649Y1188771D01*
Y1190381D01*
G01X978066Y1191948D02*
X977756Y1192178D01*
X977601Y1192446D01*
X977549Y1192753D01*
X977652Y1193136D01*
X977911Y1193404D01*
X978221Y1193481D01*
X978531Y1193443D01*
X978789Y1193289D01*
X979306Y1192523D01*
X979667Y1192178D01*
X980184Y1191948D01*
X980649Y1191871D01*
Y1193481D01*
G01X963769Y1203148D02*
Y1209348D01*
G01X966969Y1203148D02*
X963769D01*
G01X966969Y1209348D02*
Y1203148D01*
G01X963004Y1210508D02*
Y1204308D01*
G01X963769Y1209348D02*
X966969D01*
G01X964352Y1217123D02*
Y1220323D01*
G01X970552Y1217123D02*
X964352D01*
G01X970552Y1220323D02*
Y1217123D01*
G01X964352Y1220323D02*
X970552D01*
G01X966820Y1210138D02*
X963620D01*
G01X966820Y1216338D02*
Y1210138D01*
G01X963620Y1216338D02*
X966820D01*
G01X963620Y1210138D02*
Y1216338D01*
G01X967447Y1216074D02*
X970647D01*
G01X967447Y1209874D02*
Y1216074D01*
G01X970647Y1209874D02*
X967447D01*
G01X970647Y1216074D02*
Y1209874D01*
G01X962323Y1220467D02*
Y1214267D01*
G01X963678Y1224312D02*
Y1221112D01*
G01X970552Y1224323D02*
Y1221123D01*
G01X964352D02*
Y1224323D01*
G01X970552Y1221123D02*
X964352D01*
G01X964917Y1233991D02*
Y1227991D01*
G01Y1240891D02*
Y1234891D01*
G01X964352Y1224323D02*
X970552D01*
G01X964917Y1247791D02*
Y1241791D01*
G01X967848Y1352718D02*
X968040Y1352408D01*
X968270Y1352201D01*
X968538Y1352098D01*
X968845Y1352201D01*
X969075Y1352408D01*
X969305Y1352718D01*
X969382Y1353131D01*
Y1355198D01*
G01X970987Y1353390D02*
X971255Y1353751D01*
X971485Y1353958D01*
X971792Y1354061D01*
X972060Y1353958D01*
X972252Y1353751D01*
X972405Y1353441D01*
X972443Y1353080D01*
X972405Y1352770D01*
X972252Y1352460D01*
X972022Y1352201D01*
X971753Y1352098D01*
X971447Y1352201D01*
X971178Y1352511D01*
X971025Y1352976D01*
X970987Y1353493D01*
X971063Y1354165D01*
X971178Y1354526D01*
X971370Y1354888D01*
X971638Y1355146D01*
X971907Y1355198D01*
X972175Y1355095D01*
X972367Y1354836D01*
G01X974163Y1352460D02*
X974432Y1352201D01*
X974738Y1352098D01*
X975045Y1352201D01*
X975313Y1352511D01*
X975505Y1352976D01*
X975582Y1353441D01*
Y1354010D01*
X975505Y1354475D01*
X975313Y1354888D01*
X975083Y1355095D01*
X974815Y1355198D01*
X974508Y1355095D01*
X974278Y1354888D01*
X974125Y1354578D01*
X974048Y1354165D01*
X974125Y1353803D01*
X974317Y1353441D01*
X974547Y1353235D01*
X974815Y1353183D01*
X975122Y1353286D01*
X975352Y1353545D01*
X975582Y1354010D01*
G01X975583Y1357639D02*
Y1357284D01*
G01Y1367935D02*
Y1364251D01*
G01Y1410553D02*
Y1406869D01*
G01Y1417520D02*
Y1417165D01*
G01X978201Y1465455D02*
Y1446951D01*
X977268D01*
G01X965985Y1505439D02*
X994185D01*
Y1474039D01*
X965985D01*
Y1505439D01*
G01X977568Y1465455D02*
X978201D01*
G01X991363Y-21559D02*
Y-18459D01*
X992129D01*
X992436Y-18614D01*
X992666Y-18821D01*
X992858Y-19131D01*
X993011Y-19492D01*
X993049Y-20009D01*
X993011Y-20526D01*
X992858Y-20887D01*
X992666Y-21197D01*
X992436Y-21404D01*
X992129Y-21559D01*
X991363D01*
G01X996073D02*
X994539D01*
Y-18459D01*
X996073D01*
G01X995459Y-19957D02*
X994539D01*
G01X998406Y-21559D02*
Y-18459D01*
X997946Y-19079D01*
G01Y-21559D02*
X998866D01*
G01X1000663Y-20939D02*
X1000893Y-21301D01*
X1001199Y-21507D01*
X1001544Y-21559D01*
X1001851Y-21507D01*
X1002158Y-21249D01*
X1002349Y-20939D01*
X1002388Y-20629D01*
X1002311Y-20267D01*
X1002043Y-20009D01*
X1001774Y-19906D01*
X1001429D01*
G01X1001774D02*
X1002004Y-19751D01*
X1002196Y-19492D01*
X1002273Y-19182D01*
X1002196Y-18872D01*
X1002004Y-18614D01*
X1001659Y-18459D01*
X1001314Y-18511D01*
X1000969Y-18717D01*
G01X1004606Y-18459D02*
Y-21559D01*
G01X1003724Y-18459D02*
X1005488D01*
G01X1006556Y-22592D02*
X1008856D01*
G01X1010078Y-18976D02*
X1010308Y-18666D01*
X1010576Y-18511D01*
X1010883Y-18459D01*
X1011266Y-18562D01*
X1011534Y-18821D01*
X1011611Y-19131D01*
X1011573Y-19441D01*
X1011419Y-19699D01*
X1010653Y-20216D01*
X1010308Y-20577D01*
X1010078Y-21094D01*
X1010001Y-21559D01*
X1011611D01*
G01X993543Y82540D02*
Y85740D01*
G01X999743Y82540D02*
X993543D01*
G01Y74540D02*
Y77740D01*
G01X999743Y74540D02*
X993543D01*
G01Y77740D02*
X999743D01*
G01X993543Y78540D02*
Y81740D01*
G01X999743Y78540D02*
X993543D01*
G01Y81740D02*
X999743D01*
G01X993543Y85740D02*
X999743D01*
G01X983150Y97026D02*
Y103226D01*
G01X986350Y97026D02*
X983150D01*
G01X986350Y103226D02*
Y97026D01*
G01X985154Y86929D02*
X981954D01*
G01X985154Y93129D02*
Y86929D01*
G01X981954Y93129D02*
X985154D01*
G01X981954Y86929D02*
Y93129D01*
G01X989154Y86929D02*
X985954D01*
G01X989154Y93129D02*
Y86929D01*
G01X985954Y93129D02*
X989154D01*
G01X985954Y86929D02*
Y93129D01*
G01X993154Y86929D02*
X989954D01*
G01X993154Y93129D02*
Y86929D01*
G01X989954Y93129D02*
X993154D01*
G01X989954Y86929D02*
Y93129D01*
G01X997163Y86929D02*
X993963D01*
G01Y93129D02*
X997163D01*
G01X993963Y86929D02*
Y93129D01*
G01X989233Y96673D02*
Y102873D01*
G01X992433Y96673D02*
X989233D01*
G01X992433Y102873D02*
Y96673D01*
G01X993233D02*
Y102873D01*
G01X996433Y96673D02*
X993233D01*
G01X983150Y103226D02*
X986350D01*
G01X989233Y102873D02*
X992433D01*
G01X993233D02*
X996433D01*
G01X990818Y139647D02*
Y142847D01*
G01X997018Y139647D02*
X990818D01*
G01Y142847D02*
X997018D01*
G01X986848Y145940D02*
Y149140D01*
G01X993048Y145940D02*
X986848D01*
G01X993048Y149140D02*
Y145940D01*
G01X986848Y149140D02*
X993048D01*
G01X984518Y164436D02*
Y195440D01*
G01X993048Y153140D02*
Y149940D01*
G01X986848Y153140D02*
X993048D01*
G01X986848Y149940D02*
Y153140D01*
G01X993048Y149940D02*
X986848D01*
G01X993484Y171473D02*
X990284D01*
G01X993484Y177673D02*
Y171473D01*
G01X990284Y177673D02*
X993484D01*
G01X990284Y171473D02*
Y177673D01*
G01X990307Y170297D02*
X996507D01*
G01X990307Y167097D02*
Y170297D01*
G01X996507Y167097D02*
X990307D01*
G01X989484Y171473D02*
X986284D01*
G01X989484Y177673D02*
Y171473D01*
G01X986284Y177673D02*
X989484D01*
G01X986284Y171473D02*
Y177673D01*
G01X993711Y182730D02*
X990511D01*
G01X993711Y188930D02*
Y182730D01*
G01X990511Y188930D02*
X993711D01*
G01X990511Y182730D02*
Y188930D01*
G01X990502Y193541D02*
X996702D01*
G01X990502Y190341D02*
Y193541D01*
G01X996702Y190341D02*
X990502D01*
G01X981831Y213035D02*
Y225035D01*
G01X987831Y213035D02*
X981831D01*
G01X987831Y225035D02*
Y213035D01*
G01X979769Y233011D02*
Y203452D01*
G01X981831Y225035D02*
X987831D01*
G01X988671Y226621D02*
Y232621D01*
G01X1000671Y226621D02*
X988671D01*
G01X992650Y215082D02*
X989450D01*
G01X992650Y221282D02*
Y215082D01*
G01X989450Y221282D02*
X992650D01*
G01X989450Y215082D02*
Y221282D01*
G01X992471Y225921D02*
X998671D01*
G01X992471Y222721D02*
Y225921D01*
G01X998671Y222721D02*
X992471D01*
G01X988671Y232621D02*
X1000671D01*
G01X981114Y250325D02*
Y234813D01*
G01D02*
X1012206D01*
G01X979538Y292303D02*
Y262744D01*
G01X981293Y251936D02*
Y255036D01*
X982213D01*
X982520Y254881D01*
X982750Y254519D01*
X982827Y254106D01*
X982750Y253693D01*
X982558Y253383D01*
X982213Y253228D01*
X981293D01*
G01X984317Y251936D02*
Y255036D01*
X985083D01*
X985390Y254881D01*
X985620Y254674D01*
X985812Y254364D01*
X985965Y254003D01*
X986003Y253486D01*
X985965Y252969D01*
X985812Y252608D01*
X985620Y252298D01*
X985390Y252091D01*
X985083Y251936D01*
X984317D01*
G01X988260D02*
Y255036D01*
X987800Y254416D01*
G01Y251936D02*
X988720D01*
G01X991360D02*
Y255036D01*
X990900Y254416D01*
G01Y251936D02*
X991820D01*
G01X993617Y252556D02*
X993847Y252194D01*
X994153Y251988D01*
X994498Y251936D01*
X994805Y251988D01*
X995112Y252246D01*
X995303Y252556D01*
X995342Y252866D01*
X995265Y253228D01*
X994997Y253486D01*
X994728Y253589D01*
X994383D01*
G01X994728D02*
X994958Y253744D01*
X995150Y254003D01*
X995227Y254313D01*
X995150Y254623D01*
X994958Y254881D01*
X994613Y255036D01*
X994268Y254984D01*
X993923Y254778D01*
G01X1012206Y250325D02*
X981114D01*
G01X989339Y258010D02*
Y264210D01*
G01X992539Y258010D02*
X989339D01*
G01X992539Y264210D02*
Y258010D01*
G01X996539D02*
X993339D01*
G01D02*
Y264210D01*
G01X981409Y271655D02*
Y283655D01*
G01X987409Y271655D02*
X981409D01*
G01X987409Y283655D02*
Y271655D01*
G01X989339Y264210D02*
X992539D01*
G01X993339D02*
X996539D01*
G01X990298Y267653D02*
Y279427D01*
G01X1000060Y267653D02*
X990298D01*
G01X981409Y283655D02*
X987409D01*
G01X991592Y283383D02*
X988392D01*
G01X991592Y289583D02*
Y283383D01*
G01X988392Y289583D02*
X991592D01*
G01X988392Y283383D02*
Y289583D01*
G01X995592Y283383D02*
X992392D01*
G01Y289583D02*
X995592D01*
G01X992392Y283383D02*
Y289583D01*
G01X990298Y279427D02*
X1000060D01*
G01X988805Y309417D02*
Y315617D01*
G01X992005Y309417D02*
X988805D01*
G01X992005Y315617D02*
Y309417D01*
G01X979550Y304000D02*
Y305395D01*
X978783Y307100D01*
G01X980317D02*
X979550Y305395D01*
G01X981922Y305292D02*
X982190Y305653D01*
X982420Y305860D01*
X982727Y305963D01*
X982995Y305860D01*
X983187Y305653D01*
X983340Y305343D01*
X983378Y304982D01*
X983340Y304672D01*
X983187Y304362D01*
X982957Y304103D01*
X982688Y304000D01*
X982382Y304103D01*
X982113Y304413D01*
X981960Y304878D01*
X981922Y305395D01*
X981998Y306067D01*
X982113Y306428D01*
X982305Y306790D01*
X982573Y307048D01*
X982842Y307100D01*
X983110Y306997D01*
X983302Y306738D01*
G01X985971Y323726D02*
Y308474D01*
G01X988805Y315617D02*
X992005D01*
G01Y316650D02*
X988805D01*
G01X992005Y322850D02*
Y316650D01*
G01X988805Y322850D02*
X992005D01*
G01X988805Y316650D02*
Y322850D01*
G01X993077Y313053D02*
Y316253D01*
G01X999277Y313053D02*
X993077D01*
G01Y316253D02*
X999277D01*
G01X978025Y326872D02*
Y330072D01*
G01X984225Y326872D02*
X978025D01*
G01X984225Y330072D02*
Y326872D01*
G01X978025Y330072D02*
X984225D01*
G01X978025Y333872D02*
Y337072D01*
G01X984225Y333872D02*
X978025D01*
G01X984225Y337072D02*
Y333872D01*
G01X978025Y337072D02*
X984225D01*
G01Y340572D02*
Y337372D01*
G01X978025Y340572D02*
X984225D01*
G01X978025Y337372D02*
Y340572D01*
G01X984225Y337372D02*
X978025D01*
G01X982706Y344712D02*
Y341512D01*
G01X984225Y333572D02*
Y330372D01*
G01X978025Y333572D02*
X984225D01*
G01X978025Y330372D02*
Y333572D01*
G01X984225Y330372D02*
X978025D01*
G01X985645Y359484D02*
X982445D01*
G01X985645Y365684D02*
Y359484D01*
G01X982445D02*
Y365684D01*
G01X986445Y359484D02*
Y365684D01*
G01X989645Y359484D02*
X986445D01*
G01X989645Y365684D02*
Y359484D01*
G01X990445D02*
Y365684D01*
G01X993645Y359484D02*
X990445D01*
G01X993645Y365684D02*
Y359484D01*
G01X982706Y348212D02*
Y345012D01*
G01X981645Y359484D02*
X978445D01*
G01X981645Y365684D02*
Y359484D01*
G01X978445D02*
Y365684D01*
G01X982445D02*
X985645D01*
G01X986445D02*
X989645D01*
G01X990445D02*
X993645D01*
G01X978445D02*
X981645D01*
G01X1052362Y388583D02*
G02I-31496J0D01*
G01X994145Y414800D02*
Y417900D01*
G01X995755D02*
Y414800D01*
G01Y416350D02*
X994145D01*
G01X998050Y414800D02*
X998318Y414852D01*
X998625Y415007D01*
X998817Y415265D01*
X998893Y415627D01*
X998817Y415988D01*
X998587Y416298D01*
X998242Y416453D01*
X997858D01*
X997628Y416557D01*
X997437Y416815D01*
X997360Y417177D01*
X997475Y417538D01*
X997743Y417797D01*
X998050Y417900D01*
X998357Y417797D01*
X998625Y417538D01*
X998740Y417177D01*
X998663Y416815D01*
X998472Y416557D01*
X998242Y416453D01*
X997858D01*
X997513Y416298D01*
X997283Y415988D01*
X997207Y415627D01*
X997283Y415265D01*
X997475Y415007D01*
X997782Y414852D01*
X998050Y414800D01*
G01X1001150D02*
Y417900D01*
X1000690Y417280D01*
G01Y414800D02*
X1001610D01*
G01X978332Y438394D02*
Y444594D01*
G01X981532Y438394D02*
X978332D01*
G01X981532Y444594D02*
Y438394D01*
G01X989816Y458419D02*
Y446419D01*
G01X983816D02*
Y458419D01*
G01X989816Y446419D02*
X983816D01*
G01X978332Y444594D02*
X981532D01*
G01X982208Y461381D02*
Y449607D01*
G01X983816Y458419D02*
X989816D01*
G01X997947Y471194D02*
Y473434D01*
G01X996322Y472221D02*
X999572D01*
G01X981997Y465959D02*
X978797D01*
G01X981997Y472159D02*
Y465959D01*
G01X978797Y472159D02*
X981997D01*
G01X978797Y465959D02*
Y472159D01*
G01X977997D02*
Y465959D01*
G01X991799Y474835D02*
Y504394D01*
G01X1003295Y474835D02*
X991799D01*
G01X989737Y493811D02*
Y481811D01*
G01X983737D02*
Y493811D01*
G01X989737Y481811D02*
X983737D01*
G01X982876Y480988D02*
Y474988D01*
G01X978918Y485564D02*
Y491764D01*
G01X982118Y485564D02*
X978918D01*
G01X982118Y491764D02*
Y485564D01*
G01X979076Y484988D02*
Y481788D01*
G01X997847Y507934D02*
Y505508D01*
G01X991799Y504394D02*
X1003295D01*
G01X980623Y503265D02*
Y518777D01*
G01X983737Y493811D02*
X989737D01*
G01X978918Y491764D02*
X982118D01*
G01X988116Y516938D02*
Y519178D01*
G01X986491Y517965D02*
X989741D01*
G01X981968Y520579D02*
Y550138D01*
G01X993464Y520579D02*
X981968D01*
G01X993464Y550138D02*
Y520579D01*
G01X979906Y540555D02*
Y528555D01*
G01X995121Y550739D02*
Y548313D01*
G01X981968Y550138D02*
X993464D01*
G01X992849Y570014D02*
Y573214D01*
G01X999049Y570014D02*
X992849D01*
G01X993578Y581942D02*
X991625D01*
G01X993578Y583895D02*
Y581942D01*
G01X981766D02*
Y583895D01*
G01X983719Y581942D02*
X981766D01*
G01X992849Y577214D02*
X999049D01*
G01X992849Y574014D02*
Y577214D01*
G01X999049Y574014D02*
X992849D01*
G01X987792Y577441D02*
Y574241D01*
G01X981592Y577441D02*
X987792D01*
G01X981592Y574241D02*
Y577441D01*
G01X987792Y574241D02*
X981592D01*
G01X980181Y580432D02*
Y574232D01*
G01X992849Y573214D02*
X999049D01*
G01X993578Y593754D02*
Y591801D01*
G01X991625Y593754D02*
X993578D01*
G01X981766D02*
X983719D01*
G01X981766Y591801D02*
Y593754D01*
G01X983457Y598125D02*
X980257D01*
G01X983457Y604325D02*
Y598125D01*
G01X980257D02*
Y604325D01*
G01X991457Y598125D02*
X988257D01*
G01X991457Y604325D02*
Y598125D01*
G01X988257D02*
Y604325D01*
G01X995457Y598125D02*
X992257D01*
G01D02*
Y604325D01*
G01X987457Y598125D02*
X984257D01*
G01X987457Y604325D02*
Y598125D01*
G01X984257D02*
Y604325D01*
G01X979457D02*
Y598125D01*
G01X982109Y609615D02*
X997621D01*
G01X982109Y640707D02*
Y609615D01*
G01X980257Y604325D02*
X983457D01*
G01X988257D02*
X991457D01*
G01X992257D02*
X995457D01*
G01X984257D02*
X987457D01*
G01X979761Y629767D02*
Y623567D01*
G01X980465Y640911D02*
Y634711D01*
G01X997621Y640707D02*
X982109D01*
G01X1000443Y692333D02*
Y690383D01*
X990443D01*
G01D02*
Y702333D01*
G01Y708433D02*
Y720383D01*
X1000443D01*
Y718433D01*
G01X982112Y714989D02*
Y721189D01*
G01X985312D02*
Y714989D01*
G01D02*
X982112D01*
G01X990226Y722570D02*
X990418Y722260D01*
X990648Y722053D01*
X990916Y721950D01*
X991223Y722053D01*
X991453Y722260D01*
X991683Y722570D01*
X991760Y722983D01*
Y725050D01*
G01X994093Y721950D02*
Y725050D01*
X993633Y724430D01*
G01Y721950D02*
X994553D01*
G01X996541Y722312D02*
X996810Y722053D01*
X997116Y721950D01*
X997423Y722053D01*
X997691Y722363D01*
X997883Y722828D01*
X997960Y723293D01*
Y723862D01*
X997883Y724327D01*
X997691Y724740D01*
X997461Y724947D01*
X997193Y725050D01*
X996886Y724947D01*
X996656Y724740D01*
X996503Y724430D01*
X996426Y724017D01*
X996503Y723655D01*
X996695Y723293D01*
X996925Y723087D01*
X997193Y723035D01*
X997500Y723138D01*
X997730Y723397D01*
X997960Y723862D01*
G01X982112Y721189D02*
X985312D01*
G01X993590Y766874D02*
X990390D01*
G01X993590Y773074D02*
Y766874D01*
G01X990390Y773074D02*
X993590D01*
G01X990390Y766874D02*
Y773074D01*
G01X989590Y766874D02*
X986390D01*
G01X989590Y773074D02*
Y766874D01*
G01X986390Y773074D02*
X989590D01*
G01X986390Y766874D02*
Y773074D01*
G01X988326Y797045D02*
Y802695D01*
G01X990576Y794795D02*
X988326Y797045D01*
G01Y792545D02*
X990576Y794795D01*
G01X988326Y786895D02*
Y792545D01*
G01X1008426Y786895D02*
X988326D01*
G01X991651Y812243D02*
X988451D01*
G01X991651Y818443D02*
Y812243D01*
G01X988451D02*
Y818443D01*
G01X992451Y812243D02*
Y818443D01*
G01X995651Y812243D02*
X992451D01*
G01X988326Y802695D02*
X1008426D01*
G01X988451Y818443D02*
X991651D01*
G01X992451D02*
X995651D01*
G01X980103Y826759D02*
X986303D01*
G01D02*
Y823559D01*
G01D02*
X980103D01*
G01D02*
Y826759D01*
G01Y830759D02*
X986303D01*
G01D02*
Y827559D01*
G01D02*
X980103D01*
G01D02*
Y830759D01*
G01X986203Y845659D02*
Y839659D01*
G01X984221Y846997D02*
X978021D01*
G01D02*
Y850197D01*
G01X984221D02*
Y846997D01*
G01X980103Y834759D02*
X986303D01*
G01D02*
Y831559D01*
G01D02*
X980103D01*
G01D02*
Y834759D01*
G01X986303Y835559D02*
X980103D01*
G01D02*
Y838759D01*
G01D02*
X986303D01*
G01D02*
Y835559D01*
G01X1019074Y857677D02*
X991731D01*
G01X990507Y862300D02*
Y860078D01*
X990660Y859613D01*
X990967Y859303D01*
X991350Y859200D01*
X991733Y859303D01*
X992040Y859613D01*
X992193Y860078D01*
Y862300D01*
G01X993607Y859820D02*
X993837Y859458D01*
X994143Y859252D01*
X994488Y859200D01*
X994795Y859252D01*
X995102Y859510D01*
X995293Y859820D01*
X995332Y860130D01*
X995255Y860492D01*
X994987Y860750D01*
X994718Y860853D01*
X994373D01*
G01X994718D02*
X994948Y861008D01*
X995140Y861267D01*
X995217Y861577D01*
X995140Y861887D01*
X994948Y862145D01*
X994603Y862300D01*
X994258Y862248D01*
X993913Y862042D01*
G01X997550Y859200D02*
Y862300D01*
X997090Y861680D01*
G01Y859200D02*
X998010D01*
G01X999998Y859562D02*
X1000267Y859303D01*
X1000573Y859200D01*
X1000880Y859303D01*
X1001148Y859613D01*
X1001340Y860078D01*
X1001417Y860543D01*
Y861112D01*
X1001340Y861577D01*
X1001148Y861990D01*
X1000918Y862197D01*
X1000650Y862300D01*
X1000343Y862197D01*
X1000113Y861990D01*
X999960Y861680D01*
X999883Y861267D01*
X999960Y860905D01*
X1000152Y860543D01*
X1000382Y860337D01*
X1000650Y860285D01*
X1000957Y860388D01*
X1001187Y860647D01*
X1001417Y861112D01*
G01X978021Y850197D02*
X984221D01*
G01X984396Y867145D02*
X992046Y874795D01*
G01D02*
X999696Y867145D01*
G01X994260Y1005685D02*
X994208Y1005378D01*
X994002Y1005110D01*
X993692Y1004880D01*
X993330Y1004727D01*
X992917Y1004650D01*
X992503D01*
X992090Y1004727D01*
X991728Y1004880D01*
X991418Y1005110D01*
X991212Y1005378D01*
X991160Y1005685D01*
X991212Y1005992D01*
X991418Y1006260D01*
X991728Y1006490D01*
X992090Y1006643D01*
X992503Y1006720D01*
X992917D01*
X993330Y1006643D01*
X993692Y1006490D01*
X994002Y1006260D01*
X994208Y1005992D01*
X994260Y1005685D01*
G01X993433Y1005992D02*
X994260Y1006452D01*
G01Y1008785D02*
X991160D01*
X991780Y1008325D01*
G01X994260D02*
Y1009245D01*
G01X993795Y1011042D02*
X994053Y1011272D01*
X994208Y1011540D01*
X994260Y1011885D01*
X994157Y1012230D01*
X993950Y1012498D01*
X993588Y1012690D01*
X993175Y1012728D01*
X992762Y1012652D01*
X992503Y1012460D01*
X992297Y1012192D01*
X992245Y1011923D01*
X992297Y1011655D01*
X992503Y1011310D01*
X991160Y1011425D01*
Y1012460D01*
G01X979851Y1078259D02*
Y1075059D01*
G01Y1094259D02*
Y1091059D01*
G01Y1090259D02*
Y1087059D01*
G01Y1086259D02*
Y1083059D01*
G01Y1082259D02*
Y1079059D01*
G01Y1102259D02*
Y1099059D01*
G01Y1106259D02*
Y1103059D01*
G01Y1098259D02*
Y1095059D01*
G01X988535Y1103022D02*
X982335D01*
Y1106222D01*
X988535D01*
Y1103022D01*
G01X988572Y1098702D02*
X982372D01*
Y1101902D01*
X988572D01*
Y1098702D01*
G01X987674Y1185234D02*
Y1188334D01*
G01X989284D02*
Y1185234D01*
G01Y1186784D02*
X987674D01*
G01X991579Y1185234D02*
Y1188334D01*
X991119Y1187714D01*
G01Y1185234D02*
X992039D01*
G01X995139D02*
Y1188334D01*
X993721Y1186112D01*
X995637D01*
G01X997779Y1185234D02*
Y1188334D01*
X997319Y1187714D01*
G01Y1185234D02*
X998239D01*
G01X980691Y1422397D02*
Y1425497D01*
X981611D01*
X981918Y1425342D01*
X982148Y1424980D01*
X982225Y1424567D01*
X982148Y1424154D01*
X981956Y1423844D01*
X981611Y1423689D01*
X980691D01*
G01X984558Y1422397D02*
X984251Y1422449D01*
X983983Y1422655D01*
X983753Y1422965D01*
X983600Y1423327D01*
X983523Y1423740D01*
Y1424154D01*
X983600Y1424567D01*
X983753Y1424929D01*
X983983Y1425239D01*
X984251Y1425445D01*
X984558Y1425497D01*
X984865Y1425445D01*
X985133Y1425239D01*
X985363Y1424929D01*
X985516Y1424567D01*
X985593Y1424154D01*
Y1423740D01*
X985516Y1423327D01*
X985363Y1422965D01*
X985133Y1422655D01*
X984865Y1422449D01*
X984558Y1422397D01*
G01X984865Y1423224D02*
X985325Y1422397D01*
G01X986930Y1423689D02*
X987198Y1424050D01*
X987428Y1424257D01*
X987735Y1424360D01*
X988003Y1424257D01*
X988195Y1424050D01*
X988348Y1423740D01*
X988386Y1423379D01*
X988348Y1423069D01*
X988195Y1422759D01*
X987965Y1422500D01*
X987696Y1422397D01*
X987390Y1422500D01*
X987121Y1422810D01*
X986968Y1423275D01*
X986930Y1423792D01*
X987006Y1424464D01*
X987121Y1424825D01*
X987313Y1425187D01*
X987581Y1425445D01*
X987850Y1425497D01*
X988118Y1425394D01*
X988310Y1425135D01*
G01X990030Y1423689D02*
X990298Y1424050D01*
X990528Y1424257D01*
X990835Y1424360D01*
X991103Y1424257D01*
X991295Y1424050D01*
X991448Y1423740D01*
X991486Y1423379D01*
X991448Y1423069D01*
X991295Y1422759D01*
X991065Y1422500D01*
X990796Y1422397D01*
X990490Y1422500D01*
X990221Y1422810D01*
X990068Y1423275D01*
X990030Y1423792D01*
X990106Y1424464D01*
X990221Y1424825D01*
X990413Y1425187D01*
X990681Y1425445D01*
X990950Y1425497D01*
X991218Y1425394D01*
X991410Y1425135D01*
G01X993858Y1425497D02*
X993551Y1425394D01*
X993321Y1425135D01*
X993168Y1424825D01*
X993053Y1424412D01*
X993015Y1423947D01*
X993053Y1423482D01*
X993168Y1423069D01*
X993321Y1422759D01*
X993551Y1422500D01*
X993858Y1422397D01*
X994165Y1422500D01*
X994395Y1422759D01*
X994548Y1423069D01*
X994663Y1423482D01*
X994701Y1423947D01*
X994663Y1424412D01*
X994548Y1424825D01*
X994395Y1425135D01*
X994165Y1425394D01*
X993858Y1425497D01*
G01X996115Y1423017D02*
X996345Y1422655D01*
X996651Y1422449D01*
X996996Y1422397D01*
X997303Y1422449D01*
X997610Y1422707D01*
X997801Y1423017D01*
X997840Y1423327D01*
X997763Y1423689D01*
X997495Y1423947D01*
X997226Y1424050D01*
X996881D01*
G01X997226D02*
X997456Y1424205D01*
X997648Y1424464D01*
X997725Y1424774D01*
X997648Y1425084D01*
X997456Y1425342D01*
X997111Y1425497D01*
X996766Y1425445D01*
X996421Y1425239D01*
G01X981234Y1446951D02*
X980401D01*
Y1465455D01*
X981034D01*
G01X980276Y1542279D02*
X982702D01*
G01X981724Y1544030D02*
Y1568518D01*
G01X981924Y1544030D02*
Y1568518D01*
G01X982124Y1544030D02*
Y1568518D01*
G01X982524Y1544030D02*
Y1568518D01*
G01X982924Y1544030D02*
Y1568518D01*
G01X983224Y1544030D02*
Y1568518D01*
G01X981343Y1544030D02*
X983812D01*
G01X981343Y1568518D02*
Y1544030D01*
G01X984493D02*
X985780D01*
G01X984880D02*
X986080D01*
G01X984118D02*
Y1568518D01*
G01Y1544030D02*
Y1568518D01*
G01X986174Y1544030D02*
X983767D01*
G01X984157D02*
Y1568518D01*
G01X984118Y1544030D02*
Y1568518D01*
G01X983724Y1544030D02*
Y1568518D01*
G01X1021007Y1544030D02*
X983967D01*
G01X984132Y1571039D02*
Y1574139D01*
X985052D01*
X985359Y1573984D01*
X985589Y1573622D01*
X985666Y1573209D01*
X985589Y1572796D01*
X985397Y1572486D01*
X985052Y1572331D01*
X984132D01*
G01X987156Y1571039D02*
Y1574139D01*
X987922D01*
X988229Y1573984D01*
X988459Y1573777D01*
X988651Y1573467D01*
X988804Y1573106D01*
X988842Y1572589D01*
X988804Y1572072D01*
X988651Y1571711D01*
X988459Y1571401D01*
X988229Y1571194D01*
X987922Y1571039D01*
X987156D01*
G01X991099D02*
Y1574139D01*
X990639Y1573519D01*
G01Y1571039D02*
X991559D01*
G01X983967Y1568518D02*
X981343D01*
G01X983767D02*
X988647D01*
G01X983967D02*
X984493D01*
G01X986280D02*
X986174D01*
G01X984080Y1568225D02*
X984093Y1568025D01*
G01X983867Y1568518D02*
X1021007D01*
G01X989812Y1590307D02*
X986262D01*
G01X1010056Y-23526D02*
Y-40126D01*
X1000456D01*
Y-23526D01*
X1010056D01*
G01X1004209Y66981D02*
Y70181D01*
G01X1010409Y66981D02*
X1004209D01*
G01X999743Y85740D02*
Y82540D01*
G01Y77740D02*
Y74540D01*
G01Y81740D02*
Y78540D01*
G01X1004209Y70181D02*
X1010409D01*
G01X1004254Y70987D02*
Y74187D01*
G01X1010454Y70987D02*
X1004254D01*
G01Y74187D02*
X1010454D01*
G01X1004254Y74987D02*
Y78187D01*
G01X1010454Y74987D02*
X1004254D01*
G01Y78187D02*
X1010454D01*
G01X1004209Y82181D02*
X1010409D01*
G01X1004209Y78981D02*
Y82181D01*
G01X1010409Y78981D02*
X1004209D01*
G01X997163Y93129D02*
Y86929D01*
G01X998737Y95950D02*
Y102150D01*
G01X1001937Y95950D02*
X998737D01*
G01X1001937Y102150D02*
Y95950D01*
G01X996433Y102873D02*
Y96673D01*
G01X1003401Y95913D02*
Y111267D01*
G01X1015882Y95913D02*
X1003401D01*
G01X998737Y102150D02*
X1001937D01*
G01X1009752Y116088D02*
X1015952D01*
G01X1009752Y112888D02*
Y116088D01*
G01X1015952Y112888D02*
X1009752D01*
G01X998737Y109762D02*
X1001937D01*
G01X998737Y103562D02*
Y109762D01*
G01X1001937Y103562D02*
X998737D01*
G01X1001937Y109762D02*
Y103562D01*
G01X1003401Y111267D02*
X1016079D01*
G01X995216Y144690D02*
Y154138D01*
G01X1006052Y144690D02*
X995216D01*
G01X1006052Y154138D02*
Y144690D01*
G01X997797Y139647D02*
Y142847D01*
G01X1003997Y139647D02*
X997797D01*
G01X1003997Y142847D02*
Y139647D01*
G01X997797Y142847D02*
X1003997D01*
G01X1007459Y148168D02*
Y151368D01*
G01X1013659Y148168D02*
X1007459D01*
G01Y144168D02*
Y147368D01*
G01X1013659Y144168D02*
X1007459D01*
G01Y147368D02*
X1013659D01*
G01X997018Y142847D02*
Y139647D01*
G01X995750Y155600D02*
X995443Y155652D01*
X995175Y155858D01*
X994945Y156168D01*
X994792Y156530D01*
X994715Y156943D01*
Y157357D01*
X994792Y157770D01*
X994945Y158132D01*
X995175Y158442D01*
X995443Y158648D01*
X995750Y158700D01*
X996057Y158648D01*
X996325Y158442D01*
X996555Y158132D01*
X996708Y157770D01*
X996785Y157357D01*
Y156943D01*
X996708Y156530D01*
X996555Y156168D01*
X996325Y155858D01*
X996057Y155652D01*
X995750Y155600D01*
G01X996057Y156427D02*
X996517Y155600D01*
G01X998122Y158183D02*
X998352Y158493D01*
X998620Y158648D01*
X998927Y158700D01*
X999310Y158597D01*
X999578Y158338D01*
X999655Y158028D01*
X999617Y157718D01*
X999463Y157460D01*
X998697Y156943D01*
X998352Y156582D01*
X998122Y156065D01*
X998045Y155600D01*
X999655D01*
G01X1001222Y158183D02*
X1001452Y158493D01*
X1001720Y158648D01*
X1002027Y158700D01*
X1002410Y158597D01*
X1002678Y158338D01*
X1002755Y158028D01*
X1002717Y157718D01*
X1002563Y157460D01*
X1001797Y156943D01*
X1001452Y156582D01*
X1001222Y156065D01*
X1001145Y155600D01*
X1002755D01*
G01X1004207Y156065D02*
X1004437Y155807D01*
X1004705Y155652D01*
X1005050Y155600D01*
X1005395Y155703D01*
X1005663Y155910D01*
X1005855Y156272D01*
X1005893Y156685D01*
X1005817Y157098D01*
X1005625Y157357D01*
X1005357Y157563D01*
X1005088Y157615D01*
X1004820Y157563D01*
X1004475Y157357D01*
X1004590Y158700D01*
X1005625D01*
G01X1002634Y154138D02*
X1006052D01*
G01X1000634Y152414D02*
X1002634Y154138D01*
G01X998634D02*
X1000634Y152414D01*
G01X995216Y154138D02*
X998634D01*
G01X1007459Y151368D02*
X1013659D01*
G01X1000657Y174900D02*
Y172678D01*
X1000810Y172213D01*
X1001117Y171903D01*
X1001500Y171800D01*
X1001883Y171903D01*
X1002190Y172213D01*
X1002343Y172678D01*
Y174900D01*
G01X1004523Y171800D02*
X1004600Y172472D01*
X1004715Y173040D01*
X1004868Y173557D01*
X1005060Y174125D01*
X1005367Y174900D01*
X1003833D01*
G01X1007700Y171800D02*
Y174900D01*
X1007240Y174280D01*
G01Y171800D02*
X1008160D01*
G01X1010024Y178897D02*
Y176944D01*
G01X998212D02*
Y178897D01*
G01X1000165Y176944D02*
X998212D01*
G01X1010024D02*
X1008071D01*
G01X996507Y170297D02*
Y167097D01*
G01X998212Y188756D02*
X1000165D01*
G01X998212Y186803D02*
Y188756D01*
G01X1010024D02*
Y186803D01*
G01X1008071Y188756D02*
X1010024D01*
G01X996702Y193541D02*
Y190341D01*
G01X1007071Y195020D02*
Y198220D01*
G01X1013271Y195020D02*
X1007071D01*
G01Y198220D02*
X1013271D01*
G01X995551Y200174D02*
Y203274D01*
X996471D01*
X996778Y203119D01*
X997008Y202757D01*
X997085Y202344D01*
X997008Y201931D01*
X996816Y201621D01*
X996471Y201466D01*
X995551D01*
G01X998575Y203274D02*
Y201052D01*
X998728Y200587D01*
X999035Y200277D01*
X999418Y200174D01*
X999801Y200277D01*
X1000108Y200587D01*
X1000261Y201052D01*
Y203274D01*
G01X1001675Y200794D02*
X1001905Y200432D01*
X1002211Y200226D01*
X1002556Y200174D01*
X1002863Y200226D01*
X1003170Y200484D01*
X1003361Y200794D01*
X1003400Y201104D01*
X1003323Y201466D01*
X1003055Y201724D01*
X1002786Y201827D01*
X1002441D01*
G01X1002786D02*
X1003016Y201982D01*
X1003208Y202241D01*
X1003285Y202551D01*
X1003208Y202861D01*
X1003016Y203119D01*
X1002671Y203274D01*
X1002326Y203222D01*
X1001981Y203016D01*
G01X1005618Y200174D02*
X1005886Y200226D01*
X1006193Y200381D01*
X1006385Y200639D01*
X1006461Y201001D01*
X1006385Y201362D01*
X1006155Y201672D01*
X1005810Y201827D01*
X1005426D01*
X1005196Y201931D01*
X1005005Y202189D01*
X1004928Y202551D01*
X1005043Y202912D01*
X1005311Y203171D01*
X1005618Y203274D01*
X1005925Y203171D01*
X1006193Y202912D01*
X1006308Y202551D01*
X1006231Y202189D01*
X1006040Y201931D01*
X1005810Y201827D01*
X1005426D01*
X1005081Y201672D01*
X1004851Y201362D01*
X1004775Y201001D01*
X1004851Y200639D01*
X1005043Y200381D01*
X1005350Y200226D01*
X1005618Y200174D01*
G01X1010987Y220252D02*
Y208048D01*
X995683D01*
Y220252D01*
X1010987D01*
G01X1000671Y232621D02*
Y226621D01*
G01X998671Y225921D02*
Y222721D01*
G01X997339Y258010D02*
Y264210D01*
G01X1000539Y258010D02*
X997339D01*
G01X1000539Y264210D02*
Y258010D01*
G01X996539Y264210D02*
Y258010D01*
G01X1007250Y264635D02*
X1022762D01*
G01X1007250Y295727D02*
Y264635D01*
G01X997339Y264210D02*
X1000539D01*
G01X1005618Y273701D02*
X1002418D01*
G01X1005618Y279901D02*
Y273701D01*
G01X1002418D02*
Y279901D01*
G01X1000060Y279427D02*
Y267653D01*
G01X1002418Y279901D02*
X1005618D01*
G01X995592Y289583D02*
Y283383D01*
G01X996392D02*
Y289583D01*
X999592D01*
Y283383D01*
X996392D01*
G01X1003800Y282033D02*
X1000700D01*
Y282953D01*
X1000855Y283260D01*
X1001217Y283490D01*
X1001630Y283567D01*
X1002043Y283490D01*
X1002353Y283298D01*
X1002508Y282953D01*
Y282033D01*
G01X1000700Y285057D02*
X1002922D01*
X1003387Y285210D01*
X1003697Y285517D01*
X1003800Y285900D01*
X1003697Y286283D01*
X1003387Y286590D01*
X1002922Y286743D01*
X1000700D01*
G01X1003800Y289000D02*
X1000700D01*
X1001320Y288540D01*
G01X1003800D02*
Y289460D01*
G01Y292100D02*
X1000700D01*
X1001320Y291640D01*
G01X1003800D02*
Y292560D01*
G01Y295200D02*
X1000700D01*
X1001320Y294740D01*
G01X1003800D02*
Y295660D01*
G01X1022762Y295727D02*
X1007250D01*
G01X1006235Y301151D02*
X1003035D01*
G01X1006235Y307351D02*
Y301151D01*
G01X1003035Y307351D02*
X1006235D01*
G01X1003035Y301151D02*
Y307351D01*
G01X1010235Y301151D02*
X1007035D01*
G01Y307351D02*
X1010235D01*
G01X1007035Y301151D02*
Y307351D01*
G01X999098D02*
X1002298D01*
G01X999098Y301151D02*
Y307351D01*
G01X1002298Y301151D02*
X999098D01*
G01X1002298Y307351D02*
Y301151D01*
G01X999277Y316253D02*
Y313053D01*
G01X1006602Y316167D02*
X1008650D01*
G01X1006602Y318215D02*
Y316167D01*
G01X994445Y359484D02*
Y365684D01*
G01X997645Y359484D02*
X994445D01*
G01X997645Y365684D02*
Y359484D01*
G01X1006602Y347663D02*
Y345615D01*
G01X1008650Y347663D02*
X1006602D01*
G01X994445Y365684D02*
X997645D01*
G01X1008000Y475383D02*
X1004900D01*
Y476303D01*
X1005055Y476610D01*
X1005417Y476840D01*
X1005830Y476917D01*
X1006243Y476840D01*
X1006553Y476648D01*
X1006708Y476303D01*
Y475383D01*
G01X1008000Y478407D02*
X1004900D01*
Y479173D01*
X1005055Y479480D01*
X1005262Y479710D01*
X1005572Y479902D01*
X1005933Y480055D01*
X1006450Y480093D01*
X1006967Y480055D01*
X1007328Y479902D01*
X1007638Y479710D01*
X1007845Y479480D01*
X1008000Y479173D01*
Y478407D01*
G01X1007535Y481507D02*
X1007793Y481737D01*
X1007948Y482005D01*
X1008000Y482350D01*
X1007897Y482695D01*
X1007690Y482963D01*
X1007328Y483155D01*
X1006915Y483193D01*
X1006502Y483117D01*
X1006243Y482925D01*
X1006037Y482657D01*
X1005985Y482388D01*
X1006037Y482120D01*
X1006243Y481775D01*
X1004900Y481890D01*
Y482925D01*
G01X1007380Y484607D02*
X1007742Y484837D01*
X1007948Y485143D01*
X1008000Y485488D01*
X1007948Y485795D01*
X1007690Y486102D01*
X1007380Y486293D01*
X1007070Y486332D01*
X1006708Y486255D01*
X1006450Y485987D01*
X1006347Y485718D01*
Y485373D01*
G01Y485718D02*
X1006192Y485948D01*
X1005933Y486140D01*
X1005623Y486217D01*
X1005313Y486140D01*
X1005055Y485948D01*
X1004900Y485603D01*
X1004952Y485258D01*
X1005158Y484913D01*
G01X1003295Y504394D02*
Y474835D01*
G01X997800Y520583D02*
X994700D01*
Y521503D01*
X994855Y521810D01*
X995217Y522040D01*
X995630Y522117D01*
X996043Y522040D01*
X996353Y521848D01*
X996508Y521503D01*
Y520583D01*
G01X997800Y523607D02*
X994700D01*
Y524373D01*
X994855Y524680D01*
X995062Y524910D01*
X995372Y525102D01*
X995733Y525255D01*
X996250Y525293D01*
X996767Y525255D01*
X997128Y525102D01*
X997438Y524910D01*
X997645Y524680D01*
X997800Y524373D01*
Y523607D01*
G01Y527473D02*
X997128Y527550D01*
X996560Y527665D01*
X996043Y527818D01*
X995475Y528010D01*
X994700Y528317D01*
Y526783D01*
G01X1006086Y553448D02*
Y568248D01*
G01X999049Y573214D02*
Y570014D01*
G01X995700Y583857D02*
X997922D01*
X998387Y584010D01*
X998697Y584317D01*
X998800Y584700D01*
X998697Y585083D01*
X998387Y585390D01*
X997922Y585543D01*
X995700D01*
G01X998800Y587800D02*
X998748Y588068D01*
X998593Y588375D01*
X998335Y588567D01*
X997973Y588643D01*
X997612Y588567D01*
X997302Y588337D01*
X997147Y587992D01*
Y587608D01*
X997043Y587378D01*
X996785Y587187D01*
X996423Y587110D01*
X996062Y587225D01*
X995803Y587493D01*
X995700Y587800D01*
X995803Y588107D01*
X996062Y588375D01*
X996423Y588490D01*
X996785Y588413D01*
X997043Y588222D01*
X997147Y587992D01*
Y587608D01*
X997302Y587263D01*
X997612Y587033D01*
X997973Y586957D01*
X998335Y587033D01*
X998593Y587225D01*
X998748Y587532D01*
X998800Y587800D01*
G01X998180Y590057D02*
X998542Y590287D01*
X998748Y590593D01*
X998800Y590938D01*
X998748Y591245D01*
X998490Y591552D01*
X998180Y591743D01*
X997870Y591782D01*
X997508Y591705D01*
X997250Y591437D01*
X997147Y591168D01*
Y590823D01*
G01Y591168D02*
X996992Y591398D01*
X996733Y591590D01*
X996423Y591667D01*
X996113Y591590D01*
X995855Y591398D01*
X995700Y591053D01*
X995752Y590708D01*
X995958Y590363D01*
G01X999049Y577214D02*
Y574014D01*
G01X1000225Y580237D02*
X1003425D01*
G01X1000225Y574037D02*
Y580237D01*
G01X1003425Y574037D02*
X1000225D01*
G01X1003425Y580237D02*
Y574037D01*
G01X995457Y604325D02*
Y598125D01*
G01X999457D02*
X996257D01*
G01X999457Y604325D02*
Y598125D01*
G01X996257D02*
Y604325D01*
G01X1003457Y598125D02*
X1000257D01*
G01X1003457Y604325D02*
Y598125D01*
G01X1000257D02*
Y604325D01*
G01X1002000Y610383D02*
X998900D01*
Y611303D01*
X999055Y611610D01*
X999417Y611840D01*
X999830Y611917D01*
X1000243Y611840D01*
X1000553Y611648D01*
X1000708Y611303D01*
Y610383D01*
G01X1002000Y613407D02*
X998900D01*
Y614173D01*
X999055Y614480D01*
X999262Y614710D01*
X999572Y614902D01*
X999933Y615055D01*
X1000450Y615093D01*
X1000967Y615055D01*
X1001328Y614902D01*
X1001638Y614710D01*
X1001845Y614480D01*
X1002000Y614173D01*
Y613407D01*
G01X1001638Y616698D02*
X1001897Y616967D01*
X1002000Y617273D01*
X1001897Y617580D01*
X1001587Y617848D01*
X1001122Y618040D01*
X1000657Y618117D01*
X1000088D01*
X999623Y618040D01*
X999210Y617848D01*
X999003Y617618D01*
X998900Y617350D01*
X999003Y617043D01*
X999210Y616813D01*
X999520Y616660D01*
X999933Y616583D01*
X1000295Y616660D01*
X1000657Y616852D01*
X1000863Y617082D01*
X1000915Y617350D01*
X1000812Y617657D01*
X1000553Y617887D01*
X1000088Y618117D01*
G01X1001380Y619607D02*
X1001742Y619837D01*
X1001948Y620143D01*
X1002000Y620488D01*
X1001948Y620795D01*
X1001690Y621102D01*
X1001380Y621293D01*
X1001070Y621332D01*
X1000708Y621255D01*
X1000450Y620987D01*
X1000347Y620718D01*
Y620373D01*
G01Y620718D02*
X1000192Y620948D01*
X999933Y621140D01*
X999623Y621217D01*
X999313Y621140D01*
X999055Y620948D01*
X998900Y620603D01*
X998952Y620258D01*
X999158Y619913D01*
G01X997621Y609615D02*
Y640707D01*
G01X996257Y604325D02*
X999457D01*
G01X1000257D02*
X1003457D01*
G01X1011656Y694540D02*
X1012018Y694770D01*
X1012224Y695076D01*
X1012276Y695421D01*
X1012224Y695728D01*
X1011966Y696035D01*
X1011656Y696226D01*
X1011346Y696265D01*
X1010984Y696188D01*
X1010726Y695920D01*
X1010623Y695651D01*
Y695306D01*
G01Y695651D02*
X1010468Y695881D01*
X1010209Y696073D01*
X1009899Y696150D01*
X1009589Y696073D01*
X1009331Y695881D01*
X1009176Y695536D01*
X1009228Y695191D01*
X1009434Y694846D01*
G01X1000443Y712333D02*
Y698433D01*
G01X1005590Y766874D02*
X1002390D01*
G01X1005590Y773074D02*
Y766874D01*
G01X1002390Y773074D02*
X1005590D01*
G01X1002390Y766874D02*
Y773074D01*
G01X1001590Y766874D02*
X998390D01*
G01X1001590Y773074D02*
Y766874D01*
G01X998390Y773074D02*
X1001590D01*
G01X998390Y766874D02*
Y773074D01*
G01X1006390D02*
X1009590D01*
G01X1006390Y766874D02*
Y773074D01*
G01X1009590Y766874D02*
X1006390D01*
G01X1009590Y773074D02*
Y766874D01*
G01X994390Y773074D02*
X997590D01*
G01X994390Y766874D02*
Y773074D01*
G01X997590Y766874D02*
X994390D01*
G01X997590Y773074D02*
Y766874D01*
G01X1008426Y802695D02*
Y786895D01*
G01X1005099Y812300D02*
Y818500D01*
G01X1008299Y812300D02*
X1005099D01*
G01X1008299Y818500D02*
Y812300D01*
G01X1001099D02*
Y818500D01*
G01X1004299Y812300D02*
X1001099D01*
G01X1004299Y818500D02*
Y812300D01*
G01X1009099D02*
Y818500D01*
G01X1012299Y812300D02*
X1009099D01*
G01X995651Y818443D02*
Y812243D01*
G01X1005099Y818500D02*
X1008299D01*
G01X1001099D02*
X1004299D01*
G01X1009099D02*
X1012299D01*
G01X997107Y832900D02*
Y830678D01*
X997260Y830213D01*
X997567Y829903D01*
X997950Y829800D01*
X998333Y829903D01*
X998640Y830213D01*
X998793Y830678D01*
Y832900D01*
G01X1000207Y830420D02*
X1000437Y830058D01*
X1000743Y829852D01*
X1001088Y829800D01*
X1001395Y829852D01*
X1001702Y830110D01*
X1001893Y830420D01*
X1001932Y830730D01*
X1001855Y831092D01*
X1001587Y831350D01*
X1001318Y831453D01*
X1000973D01*
G01X1001318D02*
X1001548Y831608D01*
X1001740Y831867D01*
X1001817Y832177D01*
X1001740Y832487D01*
X1001548Y832745D01*
X1001203Y832900D01*
X1000858Y832848D01*
X1000513Y832642D01*
G01X1004610Y829800D02*
Y832900D01*
X1003192Y830678D01*
X1005108D01*
G01X1006522Y832383D02*
X1006752Y832693D01*
X1007020Y832848D01*
X1007327Y832900D01*
X1007710Y832797D01*
X1007978Y832538D01*
X1008055Y832228D01*
X1008017Y831918D01*
X1007863Y831660D01*
X1007097Y831143D01*
X1006752Y830782D01*
X1006522Y830265D01*
X1006445Y829800D01*
X1008055D01*
G01X995333Y848265D02*
Y847461D01*
G01X1007341D02*
Y848265D01*
G01X995333Y837061D02*
Y836257D01*
G01D02*
X997837D01*
G01X1005237D02*
X1007341D01*
G01D02*
Y837061D01*
G01Y836257D02*
X995333D01*
G01X1007341Y848265D02*
X1005037D01*
G01X997937D02*
X995333D01*
G01X1007341D02*
X995333D01*
G01X1006987Y867145D02*
Y908445D01*
G01X999696Y867145D02*
X1006987D01*
G01X1010619Y935322D02*
X1004619D01*
Y947322D01*
X1010619D01*
Y935322D01*
G01X1008409Y987631D02*
X1011609D01*
G01X1008409Y981431D02*
Y987631D01*
G01X1011609Y981431D02*
X1008409D01*
G01Y990431D02*
Y996631D01*
G01X1011609Y990431D02*
X1008409D01*
G01X996977Y1007489D02*
Y1016937D01*
G01X1007813Y1007489D02*
X996977D01*
G01X1007813Y1016937D02*
Y1007489D01*
G01X1002351Y996942D02*
Y1000042D01*
X1003117D01*
X1003424Y999887D01*
X1003654Y999680D01*
X1003846Y999370D01*
X1003999Y999009D01*
X1004037Y998492D01*
X1003999Y997975D01*
X1003846Y997614D01*
X1003654Y997304D01*
X1003424Y997097D01*
X1003117Y996942D01*
X1002351D01*
G01X1005451Y997562D02*
X1005681Y997200D01*
X1005987Y996994D01*
X1006332Y996942D01*
X1006639Y996994D01*
X1006946Y997252D01*
X1007137Y997562D01*
X1007176Y997872D01*
X1007099Y998234D01*
X1006831Y998492D01*
X1006562Y998595D01*
X1006217D01*
G01X1006562D02*
X1006792Y998750D01*
X1006984Y999009D01*
X1007061Y999319D01*
X1006984Y999629D01*
X1006792Y999887D01*
X1006447Y1000042D01*
X1006102Y999990D01*
X1005757Y999784D01*
G01X1003131Y1005249D02*
X1010271D01*
G01X1003131Y1001449D02*
Y1005249D01*
G01X1010221Y1001449D02*
X1003131D01*
G01X1002631Y1005249D02*
X1009821D01*
G01X1002631Y1001449D02*
Y1005249D01*
G01X1009821Y1001449D02*
X1002631D01*
G01X1002131Y1005249D02*
X1009221D01*
G01X1002131Y1001449D02*
Y1005249D01*
G01X1009221Y1001449D02*
X1002131D01*
G01X1008409Y996631D02*
X1011609D01*
G01X997272Y1006066D02*
X1000472D01*
G01X997272Y999866D02*
Y1006066D01*
G01X1000472Y999866D02*
X997272D01*
G01X1000472Y1006066D02*
Y999866D01*
G01X1010182Y1009297D02*
Y1015497D01*
G01X1013382Y1009297D02*
X1010182D01*
G01X1004395Y1016937D02*
X1007813D01*
G01X1002395Y1015213D02*
X1004395Y1016937D01*
G01X1000395D02*
X1002395Y1015213D01*
G01X996977Y1016937D02*
X1000395D01*
G01X1008844Y1025363D02*
Y1029963D01*
G01X1019044Y1025363D02*
X1008844D01*
G01X1010182Y1015497D02*
X1013382D01*
G01X1006830Y1023702D02*
X1003630D01*
G01X1006830Y1029902D02*
Y1023702D01*
G01X1003630D02*
Y1029902D01*
G01X998648Y1026011D02*
X1001848D01*
G01X998648Y1019811D02*
Y1026011D01*
G01X1001848Y1019811D02*
X998648D01*
G01X1001848Y1026011D02*
Y1019811D01*
G01X1004084Y1019577D02*
Y1022777D01*
G01X1010284Y1019577D02*
X1004084D01*
G01Y1022777D02*
X1010284D01*
G01X1008844Y1029963D02*
X1019044D01*
G01X1003630Y1029902D02*
X1006830D01*
G01X1053799Y1088165D02*
G03X1062401Y1066535I-22895J-21630D01*
G01X1007480Y1094955D02*
Y1098055D01*
G01X1009090D02*
Y1094955D01*
G01Y1096505D02*
X1007480D01*
G01X1011385Y1094955D02*
X1011653Y1095007D01*
X1011960Y1095162D01*
X1012152Y1095420D01*
X1012228Y1095782D01*
X1012152Y1096143D01*
X1011922Y1096453D01*
X1011577Y1096608D01*
X1011193D01*
X1010963Y1096712D01*
X1010772Y1096970D01*
X1010695Y1097332D01*
X1010810Y1097693D01*
X1011078Y1097952D01*
X1011385Y1098055D01*
X1011692Y1097952D01*
X1011960Y1097693D01*
X1012075Y1097332D01*
X1011998Y1096970D01*
X1011807Y1096712D01*
X1011577Y1096608D01*
X1011193D01*
X1010848Y1096453D01*
X1010618Y1096143D01*
X1010542Y1095782D01*
X1010618Y1095420D01*
X1010810Y1095162D01*
X1011117Y1095007D01*
X1011385Y1094955D01*
G01X1014408D02*
X1014485Y1095627D01*
X1014600Y1096195D01*
X1014753Y1096712D01*
X1014945Y1097280D01*
X1015252Y1098055D01*
X1013718D01*
G01X1062401Y1263386D02*
G03X1052791Y1240736I-31497J0D01*
G01X1005769Y1291763D02*
Y1294863D01*
G01X1007379D02*
Y1291763D01*
G01Y1293313D02*
X1005769D01*
G01X1009674Y1291763D02*
X1009942Y1291815D01*
X1010249Y1291970D01*
X1010441Y1292228D01*
X1010517Y1292590D01*
X1010441Y1292951D01*
X1010211Y1293261D01*
X1009866Y1293416D01*
X1009482D01*
X1009252Y1293520D01*
X1009061Y1293778D01*
X1008984Y1294140D01*
X1009099Y1294501D01*
X1009367Y1294760D01*
X1009674Y1294863D01*
X1009981Y1294760D01*
X1010249Y1294501D01*
X1010364Y1294140D01*
X1010287Y1293778D01*
X1010096Y1293520D01*
X1009866Y1293416D01*
X1009482D01*
X1009137Y1293261D01*
X1008907Y1292951D01*
X1008831Y1292590D01*
X1008907Y1292228D01*
X1009099Y1291970D01*
X1009406Y1291815D01*
X1009674Y1291763D01*
G01X1011931Y1292228D02*
X1012161Y1291970D01*
X1012429Y1291815D01*
X1012774Y1291763D01*
X1013119Y1291866D01*
X1013387Y1292073D01*
X1013579Y1292435D01*
X1013617Y1292848D01*
X1013541Y1293261D01*
X1013349Y1293520D01*
X1013081Y1293726D01*
X1012812Y1293778D01*
X1012544Y1293726D01*
X1012199Y1293520D01*
X1012314Y1294863D01*
X1013349D01*
G01X1015608Y1352114D02*
X1009408D01*
Y1355314D01*
X1015608D01*
Y1352114D01*
G01X1009392Y1370435D02*
X1015592D01*
Y1367235D01*
X1009392D01*
Y1370435D01*
G01X1015561Y1361933D02*
X1009361D01*
Y1365133D01*
X1015561D01*
Y1361933D01*
G01X1009404Y1359538D02*
X1015604D01*
Y1356338D01*
X1009404D01*
Y1359538D01*
G01X1009387Y1382397D02*
X1015587D01*
Y1379197D01*
X1009387D01*
Y1382397D01*
G01X1015583Y1371134D02*
X1009383D01*
Y1374334D01*
X1015583D01*
Y1371134D01*
G01X1015578Y1375152D02*
X1009378D01*
Y1378352D01*
X1015578D01*
Y1375152D01*
G01X1004352Y1405662D02*
Y1395462D01*
X999752D01*
Y1405662D01*
X1004352D01*
G01X1009768Y1393087D02*
Y1420967D01*
G01X1029768Y1393087D02*
X1009768D01*
G01Y1420967D02*
X1029768D01*
G01X1006139Y1422512D02*
Y1425612D01*
X1007059D01*
X1007366Y1425457D01*
X1007596Y1425095D01*
X1007673Y1424682D01*
X1007596Y1424269D01*
X1007404Y1423959D01*
X1007059Y1423804D01*
X1006139D01*
G01X1010006Y1422512D02*
X1009699Y1422564D01*
X1009431Y1422770D01*
X1009201Y1423080D01*
X1009048Y1423442D01*
X1008971Y1423855D01*
Y1424269D01*
X1009048Y1424682D01*
X1009201Y1425044D01*
X1009431Y1425354D01*
X1009699Y1425560D01*
X1010006Y1425612D01*
X1010313Y1425560D01*
X1010581Y1425354D01*
X1010811Y1425044D01*
X1010964Y1424682D01*
X1011041Y1424269D01*
Y1423855D01*
X1010964Y1423442D01*
X1010811Y1423080D01*
X1010581Y1422770D01*
X1010313Y1422564D01*
X1010006Y1422512D01*
G01X1010313Y1423339D02*
X1010773Y1422512D01*
G01X1012378Y1423804D02*
X1012646Y1424165D01*
X1012876Y1424372D01*
X1013183Y1424475D01*
X1013451Y1424372D01*
X1013643Y1424165D01*
X1013796Y1423855D01*
X1013834Y1423494D01*
X1013796Y1423184D01*
X1013643Y1422874D01*
X1013413Y1422615D01*
X1013144Y1422512D01*
X1012838Y1422615D01*
X1012569Y1422925D01*
X1012416Y1423390D01*
X1012378Y1423907D01*
X1012454Y1424579D01*
X1012569Y1424940D01*
X1012761Y1425302D01*
X1013029Y1425560D01*
X1013298Y1425612D01*
X1013566Y1425509D01*
X1013758Y1425250D01*
G01X1015478Y1423804D02*
X1015746Y1424165D01*
X1015976Y1424372D01*
X1016283Y1424475D01*
X1016551Y1424372D01*
X1016743Y1424165D01*
X1016896Y1423855D01*
X1016934Y1423494D01*
X1016896Y1423184D01*
X1016743Y1422874D01*
X1016513Y1422615D01*
X1016244Y1422512D01*
X1015938Y1422615D01*
X1015669Y1422925D01*
X1015516Y1423390D01*
X1015478Y1423907D01*
X1015554Y1424579D01*
X1015669Y1424940D01*
X1015861Y1425302D01*
X1016129Y1425560D01*
X1016398Y1425612D01*
X1016666Y1425509D01*
X1016858Y1425250D01*
G01X1019306Y1425612D02*
X1018999Y1425509D01*
X1018769Y1425250D01*
X1018616Y1424940D01*
X1018501Y1424527D01*
X1018463Y1424062D01*
X1018501Y1423597D01*
X1018616Y1423184D01*
X1018769Y1422874D01*
X1018999Y1422615D01*
X1019306Y1422512D01*
X1019613Y1422615D01*
X1019843Y1422874D01*
X1019996Y1423184D01*
X1020111Y1423597D01*
X1020149Y1424062D01*
X1020111Y1424527D01*
X1019996Y1424940D01*
X1019843Y1425250D01*
X1019613Y1425509D01*
X1019306Y1425612D01*
G01X1022866Y1422512D02*
Y1425612D01*
X1021448Y1423390D01*
X1023364D01*
G01X1001267Y1465455D02*
Y1446951D01*
X1000334D01*
G01X1004266Y1447051D02*
X1003433D01*
Y1465555D01*
X1004066D01*
G01X1003767Y1505439D02*
X1031967D01*
Y1474039D01*
X1003767D01*
Y1505439D01*
G01X1000634Y1465455D02*
X1001267D01*
G01X1011906Y1541160D02*
X1014146D01*
G01X1012933Y1542785D02*
Y1539535D01*
G01X999643Y1556274D02*
X1004643Y1560274D01*
G01Y1552274D02*
X999643Y1556274D01*
G01Y1561274D02*
Y1551274D01*
G01Y1556274D02*
X997843D01*
G01X1006843D02*
X1005043D01*
G01X1004643Y1560274D02*
Y1552274D01*
G01X1014762Y1590307D02*
X996262D01*
G01X1026100Y68107D02*
X1028322D01*
X1028787Y68260D01*
X1029097Y68567D01*
X1029200Y68950D01*
X1029097Y69333D01*
X1028787Y69640D01*
X1028322Y69793D01*
X1026100D01*
G01X1029200Y72050D02*
X1026100D01*
X1026720Y71590D01*
G01X1029200D02*
Y72510D01*
G01X1028580Y74307D02*
X1028942Y74537D01*
X1029148Y74843D01*
X1029200Y75188D01*
X1029148Y75495D01*
X1028890Y75802D01*
X1028580Y75993D01*
X1028270Y76032D01*
X1027908Y75955D01*
X1027650Y75687D01*
X1027547Y75418D01*
Y75073D01*
G01Y75418D02*
X1027392Y75648D01*
X1027133Y75840D01*
X1026823Y75917D01*
X1026513Y75840D01*
X1026255Y75648D01*
X1026100Y75303D01*
X1026152Y74958D01*
X1026358Y74613D01*
G01X1029200Y78710D02*
X1026100D01*
X1028322Y77292D01*
Y79208D01*
G01X1025041Y67523D02*
X1012837D01*
G01X1025041Y79047D02*
Y67523D01*
G01X1012837D02*
Y70183D01*
G01X1019734Y59613D02*
Y56413D01*
G01X1013534Y59613D02*
X1019734D01*
G01X1013534Y56413D02*
Y59613D01*
G01X1019734Y56413D02*
X1013534D01*
G01X1010409Y70181D02*
Y66981D01*
G01X1012837Y79047D02*
X1025041D01*
G01X1012837Y76285D02*
Y79047D01*
G01X1015939Y73285D02*
X1012837Y76285D01*
G01Y70183D02*
X1015939Y73285D01*
G01X1010454Y74187D02*
Y70987D01*
G01Y78187D02*
Y74987D01*
G01X1010409Y82181D02*
Y78981D01*
G01X1011244Y93476D02*
X1014444D01*
G01X1011244Y87276D02*
Y93476D01*
G01X1014444Y87276D02*
X1011244D01*
G01X1014444Y93476D02*
Y87276D01*
G01X1019944D02*
X1016744D01*
G01X1019944Y93476D02*
Y87276D01*
G01X1016744Y93476D02*
X1019944D01*
G01X1016744Y87276D02*
Y93476D01*
G01X1023893Y87204D02*
X1020693D01*
G01X1023893Y93404D02*
Y87204D01*
G01X1020693Y93404D02*
X1023893D01*
G01X1020693Y87204D02*
Y93404D01*
G01X1027800Y87299D02*
X1024600D01*
G01Y93499D02*
X1027800D01*
G01X1024600Y87299D02*
Y93499D01*
G01X1017300Y98107D02*
X1019522D01*
X1019987Y98260D01*
X1020297Y98567D01*
X1020400Y98950D01*
X1020297Y99333D01*
X1019987Y99640D01*
X1019522Y99793D01*
X1017300D01*
G01X1020400Y102510D02*
X1017300D01*
X1019522Y101092D01*
Y103008D01*
G01X1020400Y105150D02*
X1017300D01*
X1017920Y104690D01*
G01X1020400D02*
Y105610D01*
G01X1017817Y107522D02*
X1017507Y107752D01*
X1017352Y108020D01*
X1017300Y108327D01*
X1017403Y108710D01*
X1017662Y108978D01*
X1017972Y109055D01*
X1018282Y109017D01*
X1018540Y108863D01*
X1019057Y108097D01*
X1019418Y107752D01*
X1019935Y107522D01*
X1020400Y107445D01*
Y109055D01*
G01X1016079Y111267D02*
Y95913D01*
G01X1017235Y111951D02*
Y118151D01*
G01X1020435Y111951D02*
X1017235D01*
G01X1020435Y118151D02*
Y111951D01*
G01X1024155Y109424D02*
X1027355D01*
G01X1024155Y103224D02*
Y109424D01*
G01X1027355Y103224D02*
X1024155D01*
G01X1015952Y116088D02*
Y112888D01*
G01X1022609Y111734D02*
Y123508D01*
G01X1032371Y111734D02*
X1022609D01*
G01X1017235Y118151D02*
X1020435D01*
G01X1023380Y126223D02*
X1020180D01*
G01X1023380Y132423D02*
Y126223D01*
G01X1020180Y132423D02*
X1023380D01*
G01X1020180Y126223D02*
Y132423D01*
G01X1026180D02*
X1029380D01*
G01X1026180Y126223D02*
Y132423D01*
G01X1029380Y126223D02*
X1026180D01*
G01X1015844Y119384D02*
X1012744D01*
Y120304D01*
X1012899Y120611D01*
X1013261Y120841D01*
X1013674Y120918D01*
X1014087Y120841D01*
X1014397Y120649D01*
X1014552Y120304D01*
Y119384D01*
G01X1012744Y122408D02*
X1014966D01*
X1015431Y122561D01*
X1015741Y122868D01*
X1015844Y123251D01*
X1015741Y123634D01*
X1015431Y123941D01*
X1014966Y124094D01*
X1012744D01*
G01X1015844Y126351D02*
X1012744D01*
X1013364Y125891D01*
G01X1015844D02*
Y126811D01*
G01X1013261Y128723D02*
X1012951Y128953D01*
X1012796Y129221D01*
X1012744Y129528D01*
X1012847Y129911D01*
X1013106Y130179D01*
X1013416Y130256D01*
X1013726Y130218D01*
X1013984Y130064D01*
X1014501Y129298D01*
X1014862Y128953D01*
X1015379Y128723D01*
X1015844Y128646D01*
Y130256D01*
G01Y132551D02*
X1015792Y132819D01*
X1015637Y133126D01*
X1015379Y133318D01*
X1015017Y133394D01*
X1014656Y133318D01*
X1014346Y133088D01*
X1014191Y132743D01*
Y132359D01*
X1014087Y132129D01*
X1013829Y131938D01*
X1013467Y131861D01*
X1013106Y131976D01*
X1012847Y132244D01*
X1012744Y132551D01*
X1012847Y132858D01*
X1013106Y133126D01*
X1013467Y133241D01*
X1013829Y133164D01*
X1014087Y132973D01*
X1014191Y132743D01*
Y132359D01*
X1014346Y132014D01*
X1014656Y131784D01*
X1015017Y131708D01*
X1015379Y131784D01*
X1015637Y131976D01*
X1015792Y132283D01*
X1015844Y132551D01*
G01X1022609Y123508D02*
X1032371D01*
G01X1022569Y146229D02*
X1019369D01*
G01X1022569Y152429D02*
Y146229D01*
G01X1019369D02*
Y152429D01*
G01X1013659Y151368D02*
Y148168D01*
G01Y147368D02*
Y144168D01*
G01X1014700Y136907D02*
X1016922D01*
X1017387Y137060D01*
X1017697Y137367D01*
X1017800Y137750D01*
X1017697Y138133D01*
X1017387Y138440D01*
X1016922Y138593D01*
X1014700D01*
G01X1017180Y140007D02*
X1017542Y140237D01*
X1017748Y140543D01*
X1017800Y140888D01*
X1017748Y141195D01*
X1017490Y141502D01*
X1017180Y141693D01*
X1016870Y141732D01*
X1016508Y141655D01*
X1016250Y141387D01*
X1016147Y141118D01*
Y140773D01*
G01Y141118D02*
X1015992Y141348D01*
X1015733Y141540D01*
X1015423Y141617D01*
X1015113Y141540D01*
X1014855Y141348D01*
X1014700Y141003D01*
X1014752Y140658D01*
X1014958Y140313D01*
G01X1017438Y143298D02*
X1017697Y143567D01*
X1017800Y143873D01*
X1017697Y144180D01*
X1017387Y144448D01*
X1016922Y144640D01*
X1016457Y144717D01*
X1015888D01*
X1015423Y144640D01*
X1015010Y144448D01*
X1014803Y144218D01*
X1014700Y143950D01*
X1014803Y143643D01*
X1015010Y143413D01*
X1015320Y143260D01*
X1015733Y143183D01*
X1016095Y143260D01*
X1016457Y143452D01*
X1016663Y143682D01*
X1016715Y143950D01*
X1016612Y144257D01*
X1016353Y144487D01*
X1015888Y144717D01*
G01X1014700Y147050D02*
X1014803Y146743D01*
X1015062Y146513D01*
X1015372Y146360D01*
X1015785Y146245D01*
X1016250Y146207D01*
X1016715Y146245D01*
X1017128Y146360D01*
X1017438Y146513D01*
X1017697Y146743D01*
X1017800Y147050D01*
X1017697Y147357D01*
X1017438Y147587D01*
X1017128Y147740D01*
X1016715Y147855D01*
X1016250Y147893D01*
X1015785Y147855D01*
X1015372Y147740D01*
X1015062Y147587D01*
X1014803Y147357D01*
X1014700Y147050D01*
G01X1021059Y144395D02*
Y135095D01*
G01X1031659Y144395D02*
X1021059D01*
G01Y134995D02*
X1031659D01*
G01X1019369Y152429D02*
X1022569D01*
G01X1019369Y159540D02*
X1022569D01*
G01X1019369Y153340D02*
Y159540D01*
G01X1022569Y153340D02*
X1019369D01*
G01X1022569Y159540D02*
Y153340D01*
G01X1026383Y179600D02*
Y182700D01*
X1027303D01*
X1027610Y182545D01*
X1027840Y182183D01*
X1027917Y181770D01*
X1027840Y181357D01*
X1027648Y181047D01*
X1027303Y180892D01*
X1026383D01*
G01X1029407Y179600D02*
Y182700D01*
X1030173D01*
X1030480Y182545D01*
X1030710Y182338D01*
X1030902Y182028D01*
X1031055Y181667D01*
X1031093Y181150D01*
X1031055Y180633D01*
X1030902Y180272D01*
X1030710Y179962D01*
X1030480Y179755D01*
X1030173Y179600D01*
X1029407D01*
G01X1033273D02*
X1033350Y180272D01*
X1033465Y180840D01*
X1033618Y181357D01*
X1033810Y181925D01*
X1034117Y182700D01*
X1032583D01*
G01X1036450D02*
X1036143Y182597D01*
X1035913Y182338D01*
X1035760Y182028D01*
X1035645Y181615D01*
X1035607Y181150D01*
X1035645Y180685D01*
X1035760Y180272D01*
X1035913Y179962D01*
X1036143Y179703D01*
X1036450Y179600D01*
X1036757Y179703D01*
X1036987Y179962D01*
X1037140Y180272D01*
X1037255Y180685D01*
X1037293Y181150D01*
X1037255Y181615D01*
X1037140Y182028D01*
X1036987Y182338D01*
X1036757Y182597D01*
X1036450Y182700D01*
G01X1014395Y179065D02*
Y182265D01*
G01X1020595Y179065D02*
X1014395D01*
G01X1020595Y182265D02*
Y179065D01*
G01X1014395Y171065D02*
Y174265D01*
G01X1020595Y171065D02*
X1014395D01*
G01X1020595Y174265D02*
Y171065D01*
G01X1014395Y174265D02*
X1020595D01*
G01X1014395Y175065D02*
Y178265D01*
G01X1020595Y175065D02*
X1014395D01*
G01X1020595Y178265D02*
Y175065D01*
G01X1014395Y178265D02*
X1020595D01*
G01X1014395Y167065D02*
Y170265D01*
G01X1020595Y167065D02*
X1014395D01*
G01X1020595Y170265D02*
Y167065D01*
G01X1014395Y170265D02*
X1020595D01*
G01X1022163Y189435D02*
X1024403D01*
G01X1023190Y191060D02*
Y187810D01*
G01X1025804Y195583D02*
X1055363D01*
G01X1025804Y184087D02*
Y195583D01*
G01X1055363Y184087D02*
X1025804D01*
G01X1014395Y182265D02*
X1020595D01*
G01X1014395Y183065D02*
Y186265D01*
G01X1020595Y183065D02*
X1014395D01*
G01X1020595Y186265D02*
Y183065D01*
G01X1014395Y186265D02*
X1020595D01*
G01X1014395Y187065D02*
Y190265D01*
G01X1020595Y187065D02*
X1014395D01*
G01X1020595Y190265D02*
Y187065D01*
G01X1014395Y190265D02*
X1020595D01*
G01Y198265D02*
Y195065D01*
G01X1014395D02*
Y198265D01*
G01X1020595Y195065D02*
X1014395D01*
G01X1020595Y194265D02*
Y191065D01*
G01X1014395Y194265D02*
X1020595D01*
G01X1014395Y191065D02*
Y194265D01*
G01X1020595Y191065D02*
X1014395D01*
G01X1013271Y198220D02*
Y195020D01*
G01X1025957Y204506D02*
Y216506D01*
G01X1031957Y204506D02*
X1025957D01*
G01X1014490Y202464D02*
X1020690D01*
Y199264D01*
X1014490D01*
Y202464D01*
G01X1014395Y198265D02*
X1020595D01*
G01X1014490Y207264D02*
Y210464D01*
G01X1020690Y207264D02*
X1014490D01*
G01X1020690Y210464D02*
Y207264D01*
G01X1014490Y210464D02*
X1020690D01*
G01Y206464D02*
Y203264D01*
G01X1014490Y206464D02*
X1020690D01*
G01X1014490Y203264D02*
Y206464D01*
G01X1020690Y203264D02*
X1014490D01*
G01Y214464D02*
X1020690D01*
Y211264D01*
X1014490D01*
Y214464D01*
G01X1025957Y216506D02*
X1031957D01*
G01X1014490Y215264D02*
Y218464D01*
G01X1020690Y215264D02*
X1014490D01*
G01X1020690Y218464D02*
Y215264D01*
G01X1014490Y218464D02*
X1020690D01*
G01X1014490Y220264D02*
Y223464D01*
G01X1020690Y220264D02*
X1014490D01*
G01X1020690Y223464D02*
Y220264D01*
G01X1014490Y223464D02*
X1020690D01*
G01X1014487Y227319D02*
X1020687D01*
Y224119D01*
X1014487D01*
Y227319D01*
G01X1012206Y234813D02*
Y250325D01*
G01X1024755Y246771D02*
Y249971D01*
G01X1030955Y246771D02*
X1024755D01*
G01Y249971D02*
X1030955D01*
G01X1024755Y253971D02*
X1030955D01*
G01X1024755Y250771D02*
Y253971D01*
G01X1030955Y250771D02*
X1024755D01*
G01X1027200Y264783D02*
X1024100D01*
Y265703D01*
X1024255Y266010D01*
X1024617Y266240D01*
X1025030Y266317D01*
X1025443Y266240D01*
X1025753Y266048D01*
X1025908Y265703D01*
Y264783D01*
G01X1027200Y267807D02*
X1024100D01*
Y268573D01*
X1024255Y268880D01*
X1024462Y269110D01*
X1024772Y269302D01*
X1025133Y269455D01*
X1025650Y269493D01*
X1026167Y269455D01*
X1026528Y269302D01*
X1026838Y269110D01*
X1027045Y268880D01*
X1027200Y268573D01*
Y267807D01*
G01X1026580Y270907D02*
X1026942Y271137D01*
X1027148Y271443D01*
X1027200Y271788D01*
X1027148Y272095D01*
X1026890Y272402D01*
X1026580Y272593D01*
X1026270Y272632D01*
X1025908Y272555D01*
X1025650Y272287D01*
X1025547Y272018D01*
Y271673D01*
G01Y272018D02*
X1025392Y272248D01*
X1025133Y272440D01*
X1024823Y272517D01*
X1024513Y272440D01*
X1024255Y272248D01*
X1024100Y271903D01*
X1024152Y271558D01*
X1024358Y271213D01*
G01X1025908Y274122D02*
X1025547Y274390D01*
X1025340Y274620D01*
X1025237Y274927D01*
X1025340Y275195D01*
X1025547Y275387D01*
X1025857Y275540D01*
X1026218Y275578D01*
X1026528Y275540D01*
X1026838Y275387D01*
X1027097Y275157D01*
X1027200Y274888D01*
X1027097Y274582D01*
X1026787Y274313D01*
X1026322Y274160D01*
X1025805Y274122D01*
X1025133Y274198D01*
X1024772Y274313D01*
X1024410Y274505D01*
X1024152Y274773D01*
X1024100Y275042D01*
X1024203Y275310D01*
X1024462Y275502D01*
G01X1022762Y264635D02*
Y295727D01*
G01X1015035Y307351D02*
X1018235D01*
G01X1015035Y301151D02*
Y307351D01*
G01X1018235Y301151D02*
X1015035D01*
G01X1018235Y307351D02*
Y301151D01*
G01X1019035Y307351D02*
X1022235D01*
G01X1019035Y301151D02*
Y307351D01*
G01X1022235Y301151D02*
X1019035D01*
G01X1022235Y307351D02*
Y301151D01*
G01X1024149Y307351D02*
X1027349D01*
G01X1024149Y301151D02*
Y307351D01*
G01X1027349Y301151D02*
X1024149D01*
G01X1010235Y307351D02*
Y301151D01*
G01X1011035Y307351D02*
X1014235D01*
G01X1011035Y301151D02*
Y307351D01*
G01X1014235Y301151D02*
X1011035D01*
G01X1014235Y307351D02*
Y301151D01*
G01X1025714Y749349D02*
Y829743D01*
G01X1035556Y749349D02*
X1025714D01*
G01X1014795Y752946D02*
Y756146D01*
G01X1020995Y752946D02*
X1014795D01*
G01X1020995Y756146D02*
Y752946D01*
G01X1014795Y756146D02*
X1020995D01*
G01X1023735Y753046D02*
X1024003Y753098D01*
X1024310Y753253D01*
X1024502Y753511D01*
X1024578Y753873D01*
X1024502Y754234D01*
X1024272Y754544D01*
X1023927Y754699D01*
X1023543D01*
X1023313Y754803D01*
X1023122Y755061D01*
X1023045Y755423D01*
X1023160Y755784D01*
X1023428Y756043D01*
X1023735Y756146D01*
X1024042Y756043D01*
X1024310Y755784D01*
X1024425Y755423D01*
X1024348Y755061D01*
X1024157Y754803D01*
X1023927Y754699D01*
X1023543D01*
X1023198Y754544D01*
X1022968Y754234D01*
X1022892Y753873D01*
X1022968Y753511D01*
X1023160Y753253D01*
X1023467Y753098D01*
X1023735Y753046D01*
G01X1014795Y770374D02*
Y773574D01*
G01X1020995Y770374D02*
X1014795D01*
G01X1020995Y773574D02*
Y770374D01*
G01X1014795Y773574D02*
X1020995D01*
G01X1014795Y774374D02*
Y777574D01*
G01X1020995Y774374D02*
X1014795D01*
G01X1020995Y777574D02*
Y774374D01*
G01X1014795Y777574D02*
X1020995D01*
G01X1010270Y788438D02*
X1012492D01*
X1012957Y788591D01*
X1013267Y788898D01*
X1013370Y789281D01*
X1013267Y789664D01*
X1012957Y789971D01*
X1012492Y790124D01*
X1010270D01*
G01X1010787Y791653D02*
X1010477Y791883D01*
X1010322Y792151D01*
X1010270Y792458D01*
X1010373Y792841D01*
X1010632Y793109D01*
X1010942Y793186D01*
X1011252Y793148D01*
X1011510Y792994D01*
X1012027Y792228D01*
X1012388Y791883D01*
X1012905Y791653D01*
X1013370Y791576D01*
Y793186D01*
G01X1013008Y794829D02*
X1013267Y795098D01*
X1013370Y795404D01*
X1013267Y795711D01*
X1012957Y795979D01*
X1012492Y796171D01*
X1012027Y796248D01*
X1011458D01*
X1010993Y796171D01*
X1010580Y795979D01*
X1010373Y795749D01*
X1010270Y795481D01*
X1010373Y795174D01*
X1010580Y794944D01*
X1010890Y794791D01*
X1011303Y794714D01*
X1011665Y794791D01*
X1012027Y794983D01*
X1012233Y795213D01*
X1012285Y795481D01*
X1012182Y795788D01*
X1011923Y796018D01*
X1011458Y796248D01*
G01X1013370Y799041D02*
X1010270D01*
X1012492Y797623D01*
Y799539D01*
G01X1012299Y818500D02*
Y812300D01*
G01X1017322Y807415D02*
X1020522D01*
G01X1017322Y801215D02*
Y807415D01*
G01X1020522Y801215D02*
X1017322D01*
G01X1020522Y807415D02*
Y801215D01*
G01X1014758Y813446D02*
Y816646D01*
G01X1020958Y813446D02*
X1014758D01*
G01X1020958Y816646D02*
Y813446D01*
G01X1014795Y824381D02*
Y827581D01*
G01X1020995Y824381D02*
X1014795D01*
G01X1020995Y827581D02*
Y824381D01*
G01X1014795Y827581D02*
X1020995D01*
G01X1014758Y816646D02*
X1020958D01*
G01X1014795Y817374D02*
Y820574D01*
G01X1020995Y817374D02*
X1014795D01*
G01X1020995Y820574D02*
Y817374D01*
G01X1014795Y820574D02*
X1020995D01*
G01X1025714Y829743D02*
X1035556D01*
G01X1024203Y846159D02*
Y840159D01*
G01D02*
X1012203D01*
G01D02*
Y846159D01*
G01D02*
X1024203D01*
G01X1020303Y850280D02*
Y847080D01*
G01D02*
X1014103D01*
G01D02*
Y850280D01*
G01X1013603Y835259D02*
X1019803D01*
G01D02*
Y832059D01*
G01D02*
X1013603D01*
G01D02*
Y835259D01*
G01X1019803Y836059D02*
X1013603D01*
G01D02*
Y839259D01*
G01D02*
X1019803D01*
G01D02*
Y836059D01*
G01X1019074Y857677D02*
Y917913D01*
G01X1014103Y850280D02*
X1020303D01*
G01X1023731Y905545D02*
X1023679Y905813D01*
X1023524Y906120D01*
X1023266Y906312D01*
X1022904Y906388D01*
X1022543Y906312D01*
X1022233Y906082D01*
X1022078Y905737D01*
Y905353D01*
X1021974Y905123D01*
X1021716Y904932D01*
X1021354Y904855D01*
X1020993Y904970D01*
X1020734Y905238D01*
X1020631Y905545D01*
X1020734Y905852D01*
X1020993Y906120D01*
X1021354Y906235D01*
X1021716Y906158D01*
X1021974Y905967D01*
X1022078Y905737D01*
Y905353D01*
X1022233Y905008D01*
X1022543Y904778D01*
X1022904Y904702D01*
X1023266Y904778D01*
X1023524Y904970D01*
X1023679Y905277D01*
X1023731Y905545D01*
G01X1014830Y928018D02*
Y925796D01*
X1014983Y925331D01*
X1015290Y925021D01*
X1015673Y924918D01*
X1016056Y925021D01*
X1016363Y925331D01*
X1016516Y925796D01*
Y928018D01*
G01X1019233Y924918D02*
Y928018D01*
X1017815Y925796D01*
X1019731D01*
G01X1021030Y925538D02*
X1021260Y925176D01*
X1021566Y924970D01*
X1021911Y924918D01*
X1022218Y924970D01*
X1022525Y925228D01*
X1022716Y925538D01*
X1022755Y925848D01*
X1022678Y926210D01*
X1022410Y926468D01*
X1022141Y926571D01*
X1021796D01*
G01X1022141D02*
X1022371Y926726D01*
X1022563Y926985D01*
X1022640Y927295D01*
X1022563Y927605D01*
X1022371Y927863D01*
X1022026Y928018D01*
X1021681Y927966D01*
X1021336Y927760D01*
G01X1024245Y927501D02*
X1024475Y927811D01*
X1024743Y927966D01*
X1025050Y928018D01*
X1025433Y927915D01*
X1025701Y927656D01*
X1025778Y927346D01*
X1025740Y927036D01*
X1025586Y926778D01*
X1024820Y926261D01*
X1024475Y925900D01*
X1024245Y925383D01*
X1024168Y924918D01*
X1025778D01*
G01X1019319Y930722D02*
Y936722D01*
X1031319D01*
Y930722D01*
X1019319D01*
G01X1016419Y937012D02*
Y930812D01*
X1013219D01*
Y937012D01*
X1016419D01*
G01X1015215Y938714D02*
X1027223D01*
G01X1024619D02*
X1027223D01*
G01X1015215Y939518D02*
Y938714D01*
X1017519D01*
G01X1013319Y955822D02*
X1019519D01*
Y952622D01*
X1013319D01*
Y955822D01*
G01X1032005Y952622D02*
X1025805D01*
Y955822D01*
X1032005D01*
Y952622D01*
G01X1019519Y957222D02*
X1013319D01*
Y960422D01*
X1019519D01*
Y957222D01*
G01X1015215Y950722D02*
X1027223D01*
G01X1017319D02*
X1015215D01*
Y949918D01*
G01X1027223D02*
Y950722D01*
X1024719D01*
G01X1011609Y987631D02*
Y981431D01*
G01Y996631D02*
Y990431D01*
G01X1024409Y987631D02*
X1027609D01*
G01X1024409Y981431D02*
Y987631D01*
G01X1027609Y981431D02*
X1024409D01*
G01X1016409Y987631D02*
X1019609D01*
G01X1016409Y981431D02*
Y987631D01*
G01X1019609Y981431D02*
X1016409D01*
G01X1019609Y987631D02*
Y981431D01*
G01X1020409Y987631D02*
X1023609D01*
G01X1020409Y981431D02*
Y987631D01*
G01X1023609Y981431D02*
X1020409D01*
G01X1023609Y987631D02*
Y981431D01*
G01X1012409Y987631D02*
X1015609D01*
G01X1012409Y981431D02*
Y987631D01*
G01X1015609Y981431D02*
X1012409D01*
G01X1015609Y987631D02*
Y981431D01*
G01X1024409Y990431D02*
Y996631D01*
G01X1027609Y990431D02*
X1024409D01*
G01X1016409D02*
Y996631D01*
G01X1019609Y990431D02*
X1016409D01*
G01X1019609Y996631D02*
Y990431D01*
G01X1020409D02*
Y996631D01*
G01X1023609Y990431D02*
X1020409D01*
G01X1023609Y996631D02*
Y990431D01*
G01X1012409D02*
Y996631D01*
G01X1015609Y990431D02*
X1012409D01*
G01X1015609Y996631D02*
Y990431D01*
G01X1015337Y1003053D02*
Y1007653D01*
G01X1025537Y1003053D02*
X1015337D01*
G01X1025537Y1007653D02*
Y1003053D01*
G01X1015337Y1007653D02*
X1025537D01*
G01X1010271Y1005249D02*
Y1001499D01*
G01X1013382Y1015497D02*
Y1009297D01*
G01X1024409Y996631D02*
X1027609D01*
G01X1016409D02*
X1019609D01*
G01X1020409D02*
X1023609D01*
G01X1012409D02*
X1015609D01*
G01X1019044Y1029963D02*
Y1025363D01*
G01X1022131Y1022862D02*
X1026731D01*
G01X1022131Y1012662D02*
Y1022862D01*
G01X1026731Y1012662D02*
X1022131D01*
G01X1014931Y1011603D02*
Y1024483D01*
G01X1021331D02*
Y1011603D01*
G01X1014931Y1024483D02*
X1021331D01*
G01X1014931Y1011603D02*
X1021331D01*
G01X1010284Y1022777D02*
Y1019577D01*
G01X1020331Y1025333D02*
Y1028533D01*
G01X1026531Y1025333D02*
X1020331D01*
G01Y1028533D02*
X1026531D01*
G01X1026447Y1112608D02*
Y1106208D01*
G01X1039327D02*
X1026447D01*
G01X1017897Y1102002D02*
Y1112202D01*
G01X1022497Y1102002D02*
X1017897D01*
G01X1022497Y1112202D02*
Y1102002D01*
G01X1026447Y1125208D02*
Y1118808D01*
G01X1039327D02*
X1026447D01*
G01Y1112608D02*
X1039327D01*
G01X1017897Y1114602D02*
Y1124802D01*
G01X1022497Y1114602D02*
X1017897D01*
G01X1022497Y1124802D02*
Y1114602D01*
G01X1017897Y1112202D02*
X1022497D01*
G01X1026447Y1125208D02*
X1039327D01*
G01X1026447Y1137808D02*
Y1131408D01*
G01X1039327D02*
X1026447D01*
G01Y1137808D02*
X1039327D01*
G01X1017897Y1124802D02*
X1022497D01*
G01X1017897Y1137402D02*
X1022497D01*
G01X1017897Y1127202D02*
Y1137402D01*
G01X1022497Y1127202D02*
X1017897D01*
G01X1022497Y1137402D02*
Y1127202D01*
G01X1017897Y1139802D02*
Y1150002D01*
G01X1022497Y1139802D02*
X1017897D01*
G01X1022497Y1150002D02*
Y1139802D01*
G01X1026447Y1150408D02*
Y1144008D01*
G01X1039327D02*
X1026447D01*
G01Y1150408D02*
X1039327D01*
G01X1017897Y1150002D02*
X1022497D01*
G01X1017897Y1152402D02*
Y1162602D01*
G01X1022497Y1152402D02*
X1017897D01*
G01X1022497Y1162602D02*
Y1152402D01*
G01X1026447Y1163008D02*
Y1156608D01*
G01X1039327D02*
X1026447D01*
G01Y1163008D02*
X1039327D01*
G01X1026447Y1175608D02*
Y1169208D01*
G01X1039327D02*
X1026447D01*
G01X1017897Y1162602D02*
X1022497D01*
G01X1017897Y1165002D02*
Y1175202D01*
G01X1022497Y1165002D02*
X1017897D01*
G01X1022497Y1175202D02*
Y1165002D01*
G01X1026447Y1175608D02*
X1039327D01*
G01X1026447Y1188208D02*
Y1181808D01*
G01X1039327D02*
X1026447D01*
G01Y1188208D02*
X1039327D01*
G01X1017897Y1175202D02*
X1022497D01*
G01X1017897Y1187802D02*
X1022497D01*
G01X1017897Y1177602D02*
Y1187802D01*
G01X1022497Y1177602D02*
X1017897D01*
G01X1022497Y1187802D02*
Y1177602D01*
G01X1026591Y1202844D02*
X1024329Y1205106D01*
G01D02*
X1028713Y1209490D01*
G01X1023762Y1205673D02*
X1021500Y1207935D01*
G01X1028146Y1210057D02*
X1023762Y1205673D01*
G01X1025884Y1212319D02*
X1028146Y1210057D01*
G01X1021500Y1207935D02*
X1025884Y1212319D01*
G01X1017752Y1211683D02*
X1015490Y1213945D01*
G01X1022136Y1216067D02*
X1017752Y1211683D01*
G01X1019874Y1218329D02*
X1022136Y1216067D01*
G01X1015490Y1213945D02*
X1019874Y1218329D01*
G01X1023056Y1215147D02*
X1025318Y1212885D01*
G01X1018672Y1210763D02*
X1023056Y1215147D01*
G01X1020934Y1208501D02*
X1018672Y1210763D01*
G01X1025318Y1212885D02*
X1020934Y1208501D01*
G01X1018174Y1228126D02*
X1021374D01*
G01X1018174Y1221926D02*
Y1228126D01*
G01X1021374Y1221926D02*
X1018174D01*
G01X1021374Y1228126D02*
Y1221926D01*
G01X1022174Y1228126D02*
X1025374D01*
G01X1022174Y1221926D02*
Y1228126D01*
G01X1025374Y1221926D02*
X1022174D01*
G01X1025374Y1228126D02*
Y1221926D01*
G01X1019659Y1311922D02*
Y1318122D01*
X1022859D01*
Y1311922D01*
X1019659D01*
G01X1018929Y1318112D02*
Y1311912D01*
X1015729D01*
Y1318112D01*
X1018929D01*
G01X1023799Y1311901D02*
Y1318101D01*
X1026999D01*
Y1311901D01*
X1023799D01*
G01X1020478Y1310770D02*
Y1308548D01*
X1020631Y1308083D01*
X1020938Y1307773D01*
X1021321Y1307670D01*
X1021704Y1307773D01*
X1022011Y1308083D01*
X1022164Y1308548D01*
Y1310770D01*
G01X1024881Y1307670D02*
Y1310770D01*
X1023463Y1308548D01*
X1025379D01*
G01X1027981Y1307670D02*
Y1310770D01*
X1026563Y1308548D01*
X1028479D01*
G01X1030621Y1307670D02*
X1030889Y1307722D01*
X1031196Y1307877D01*
X1031388Y1308135D01*
X1031464Y1308497D01*
X1031388Y1308858D01*
X1031158Y1309168D01*
X1030813Y1309323D01*
X1030429D01*
X1030199Y1309427D01*
X1030008Y1309685D01*
X1029931Y1310047D01*
X1030046Y1310408D01*
X1030314Y1310667D01*
X1030621Y1310770D01*
X1030928Y1310667D01*
X1031196Y1310408D01*
X1031311Y1310047D01*
X1031234Y1309685D01*
X1031043Y1309427D01*
X1030813Y1309323D01*
X1030429D01*
X1030084Y1309168D01*
X1029854Y1308858D01*
X1029778Y1308497D01*
X1029854Y1308135D01*
X1030046Y1307877D01*
X1030353Y1307722D01*
X1030621Y1307670D01*
G01X1022515Y1329289D02*
Y1335489D01*
X1025715D01*
Y1329289D01*
X1022515D01*
G01X1021649Y1335436D02*
Y1329236D01*
X1018449D01*
Y1335436D01*
X1021649D01*
G01X1021271Y1349599D02*
Y1343399D01*
X1018071D01*
Y1349599D01*
X1021271D01*
G01X1032726Y1345200D02*
X1034635Y1342491D01*
X1040783D01*
Y1353909D01*
X1024669D01*
Y1342491D01*
X1030817D01*
X1032726Y1345200D01*
G01X1017328Y1339853D02*
Y1337631D01*
X1017481Y1337166D01*
X1017788Y1336856D01*
X1018171Y1336753D01*
X1018554Y1336856D01*
X1018861Y1337166D01*
X1019014Y1337631D01*
Y1339853D01*
G01X1021731Y1336753D02*
Y1339853D01*
X1020313Y1337631D01*
X1022229D01*
G01X1024831Y1336753D02*
Y1339853D01*
X1023413Y1337631D01*
X1025329D01*
G01X1026819Y1337115D02*
X1027088Y1336856D01*
X1027394Y1336753D01*
X1027701Y1336856D01*
X1027969Y1337166D01*
X1028161Y1337631D01*
X1028238Y1338096D01*
Y1338665D01*
X1028161Y1339130D01*
X1027969Y1339543D01*
X1027739Y1339750D01*
X1027471Y1339853D01*
X1027164Y1339750D01*
X1026934Y1339543D01*
X1026781Y1339233D01*
X1026704Y1338820D01*
X1026781Y1338458D01*
X1026973Y1338096D01*
X1027203Y1337890D01*
X1027471Y1337838D01*
X1027778Y1337941D01*
X1028008Y1338200D01*
X1028238Y1338665D01*
G01X1020857Y1368073D02*
Y1361873D01*
X1017657D01*
Y1368073D01*
X1020857D01*
G01X1035715Y1382862D02*
Y1371050D01*
X1023091D01*
Y1382862D01*
X1035715D01*
G01X1024299Y1465555D02*
Y1447051D01*
X1023366D01*
G01X1027152Y1447167D02*
X1026319D01*
Y1465671D01*
X1026952D01*
G01X1023666Y1465555D02*
X1024299D01*
G01X1021007Y1568518D02*
Y1544030D01*
G01X1024792Y1590307D02*
X1021212D01*
G01X1027800Y93499D02*
Y87299D01*
G01X1040772Y122172D02*
Y110172D01*
G01X1034772D02*
Y122172D01*
G01X1040772Y110172D02*
X1034772D01*
G01X1032155Y109424D02*
X1035355D01*
G01X1032155Y103224D02*
Y109424D01*
G01X1035355Y103224D02*
X1032155D01*
G01X1035355Y109424D02*
Y103224D01*
G01X1039849Y108095D02*
X1046049D01*
G01X1039849Y104895D02*
Y108095D01*
G01X1046049Y104895D02*
X1039849D01*
G01X1027355Y109424D02*
Y103224D01*
G01X1039849Y100895D02*
Y104095D01*
G01X1046049Y100895D02*
X1039849D01*
G01Y104095D02*
X1046049D01*
G01X1028155Y109424D02*
X1031355D01*
G01X1028155Y103224D02*
Y109424D01*
G01X1031355Y103224D02*
X1028155D01*
G01X1031355Y109424D02*
Y103224D01*
G01X1032371Y123508D02*
Y111734D01*
G01X1034772Y122172D02*
X1040772D01*
G01X1033380Y126223D02*
X1030180D01*
G01X1033380Y132423D02*
Y126223D01*
G01X1030180Y132423D02*
X1033380D01*
G01X1030180Y126223D02*
Y132423D01*
G01X1029380D02*
Y126223D01*
G01X1037434Y126228D02*
X1034234D01*
G01X1037434Y132428D02*
Y126228D01*
G01X1034234Y132428D02*
X1037434D01*
G01X1034234Y126228D02*
Y132428D01*
G01X1037613Y141337D02*
X1034413D01*
G01X1037613Y147537D02*
Y141337D01*
G01X1034413Y147537D02*
X1037613D01*
G01X1034413Y141337D02*
Y147537D01*
G01X1034278Y133238D02*
Y136438D01*
G01X1040478Y133238D02*
X1034278D01*
G01X1040478Y136438D02*
Y133238D01*
G01X1034278Y136438D02*
X1040478D01*
G01X1034278Y137238D02*
Y140438D01*
G01X1040478Y137238D02*
X1034278D01*
G01X1040478Y140438D02*
Y137238D01*
G01X1034278Y140438D02*
X1040478D01*
G01X1040824Y148437D02*
X1044024D01*
G01X1040824Y142237D02*
Y148437D01*
G01X1044024Y142237D02*
X1040824D01*
G01X1031659Y134995D02*
Y144395D01*
G01X1029282Y149950D02*
Y165304D01*
G01X1041960Y149950D02*
X1029282D01*
G01X1041960Y165304D02*
Y149950D01*
G01X1029479Y165304D02*
X1041960D01*
G01X1044780Y197645D02*
X1032780D01*
G01D02*
Y203645D01*
G01X1031957Y216506D02*
Y204506D01*
G01X1032780Y203645D02*
X1044780D01*
G01X1036533Y208464D02*
X1042733D01*
G01X1036533Y205264D02*
Y208464D01*
G01X1042733Y205264D02*
X1036533D01*
G01X1032757Y208306D02*
Y214506D01*
G01X1035957Y208306D02*
X1032757D01*
G01X1035957Y214506D02*
Y208306D01*
G01X1037563Y226801D02*
X1049767D01*
Y211497D01*
X1037563D01*
Y226801D01*
G01X1032757Y214506D02*
X1035957D01*
G01X1033123Y245521D02*
Y254969D01*
G01X1043959Y245521D02*
X1033123D01*
G01X1036699Y231334D02*
X1033499D01*
G01X1036699Y237534D02*
Y231334D01*
G01X1033499Y237534D02*
X1036699D01*
G01X1033499Y231334D02*
Y237534D01*
G01X1042226Y231446D02*
X1039026D01*
G01X1042226Y237646D02*
Y231446D01*
G01X1039026Y237646D02*
X1042226D01*
G01X1039026Y231446D02*
Y237646D01*
G01X1030955Y249971D02*
Y246771D01*
G01X1034925Y243678D02*
Y240478D01*
G01X1028725Y243678D02*
X1034925D01*
G01X1028725Y240478D02*
Y243678D01*
G01X1034925Y240478D02*
X1028725D01*
G01X1041904Y243678D02*
Y240478D01*
G01X1035704Y243678D02*
X1041904D01*
G01X1035704Y240478D02*
Y243678D01*
G01X1041904Y240478D02*
X1035704D01*
G01X1034483Y259028D02*
X1034176Y259080D01*
X1033908Y259286D01*
X1033678Y259596D01*
X1033525Y259958D01*
X1033448Y260371D01*
Y260785D01*
X1033525Y261198D01*
X1033678Y261560D01*
X1033908Y261870D01*
X1034176Y262076D01*
X1034483Y262128D01*
X1034790Y262076D01*
X1035058Y261870D01*
X1035288Y261560D01*
X1035441Y261198D01*
X1035518Y260785D01*
Y260371D01*
X1035441Y259958D01*
X1035288Y259596D01*
X1035058Y259286D01*
X1034790Y259080D01*
X1034483Y259028D01*
G01X1034790Y259855D02*
X1035250Y259028D01*
G01X1036855Y261611D02*
X1037085Y261921D01*
X1037353Y262076D01*
X1037660Y262128D01*
X1038043Y262025D01*
X1038311Y261766D01*
X1038388Y261456D01*
X1038350Y261146D01*
X1038196Y260888D01*
X1037430Y260371D01*
X1037085Y260010D01*
X1036855Y259493D01*
X1036778Y259028D01*
X1038388D01*
G01X1040683Y262128D02*
X1040376Y262025D01*
X1040146Y261766D01*
X1039993Y261456D01*
X1039878Y261043D01*
X1039840Y260578D01*
X1039878Y260113D01*
X1039993Y259700D01*
X1040146Y259390D01*
X1040376Y259131D01*
X1040683Y259028D01*
X1040990Y259131D01*
X1041220Y259390D01*
X1041373Y259700D01*
X1041488Y260113D01*
X1041526Y260578D01*
X1041488Y261043D01*
X1041373Y261456D01*
X1041220Y261766D01*
X1040990Y262025D01*
X1040683Y262128D01*
G01X1042940Y259493D02*
X1043170Y259235D01*
X1043438Y259080D01*
X1043783Y259028D01*
X1044128Y259131D01*
X1044396Y259338D01*
X1044588Y259700D01*
X1044626Y260113D01*
X1044550Y260526D01*
X1044358Y260785D01*
X1044090Y260991D01*
X1043821Y261043D01*
X1043553Y260991D01*
X1043208Y260785D01*
X1043323Y262128D01*
X1044358D01*
G01X1040541Y254969D02*
X1043959D01*
G01X1038541Y253245D02*
X1040541Y254969D01*
G01X1036541D02*
X1038541Y253245D01*
G01X1033123Y254969D02*
X1036541D01*
G01X1030955Y253971D02*
Y250771D01*
G01X1038986Y301151D02*
X1036870D01*
G01X1032186D02*
X1034230D01*
G01X1035386Y306414D02*
Y302018D01*
G01X1035786Y306414D02*
Y302018D01*
G01X1038986Y307351D02*
X1036840D01*
G01X1032186D02*
X1034320D01*
G01X1032186Y301151D02*
Y307351D01*
G01X1027349D02*
Y301151D01*
G01X1038986Y307351D02*
Y301151D01*
G01X1028039Y307351D02*
X1031239D01*
G01X1028039Y301151D02*
Y307351D01*
G01X1031239Y301151D02*
X1028039D01*
G01X1031239Y307351D02*
Y301151D01*
G01X1043096D02*
X1039896D01*
G01Y307351D02*
X1043096D01*
G01X1039896Y301151D02*
Y307351D01*
G01X1038098Y316167D02*
Y318215D01*
G01X1036050Y316167D02*
X1038098D01*
G01X1032907Y352300D02*
Y350078D01*
X1033060Y349613D01*
X1033367Y349303D01*
X1033750Y349200D01*
X1034133Y349303D01*
X1034440Y349613D01*
X1034593Y350078D01*
Y352300D01*
G01X1036850Y349200D02*
Y352300D01*
X1036390Y351680D01*
G01Y349200D02*
X1037310D01*
G01X1039950D02*
Y352300D01*
X1039490Y351680D01*
G01Y349200D02*
X1040410D01*
G01X1042207Y349820D02*
X1042437Y349458D01*
X1042743Y349252D01*
X1043088Y349200D01*
X1043395Y349252D01*
X1043702Y349510D01*
X1043893Y349820D01*
X1043932Y350130D01*
X1043855Y350492D01*
X1043587Y350750D01*
X1043318Y350853D01*
X1042973D01*
G01X1043318D02*
X1043548Y351008D01*
X1043740Y351267D01*
X1043817Y351577D01*
X1043740Y351887D01*
X1043548Y352145D01*
X1043203Y352300D01*
X1042858Y352248D01*
X1042513Y352042D01*
G01X1038098Y345615D02*
Y347663D01*
G01D02*
X1036050D01*
G01X1039808Y450181D02*
X1043008D01*
G01X1039808Y443981D02*
Y450181D01*
G01X1043008Y443981D02*
X1039808D01*
G01X1043008Y450981D02*
X1039808D01*
G01Y457181D02*
X1043008D01*
G01X1039808Y450981D02*
Y457181D01*
G01X1035556Y829743D02*
Y749349D01*
G01X1042074Y752370D02*
X1042384Y752562D01*
X1042591Y752792D01*
X1042694Y753060D01*
X1042591Y753367D01*
X1042384Y753597D01*
X1042074Y753827D01*
X1041661Y753904D01*
X1039594D01*
G01X1042694Y755470D02*
X1039594D01*
Y756390D01*
X1039749Y756697D01*
X1040111Y756927D01*
X1040524Y757004D01*
X1040937Y756927D01*
X1041247Y756735D01*
X1041402Y756390D01*
Y755470D01*
G01X1040111Y758609D02*
X1039801Y758839D01*
X1039646Y759107D01*
X1039594Y759414D01*
X1039697Y759797D01*
X1039956Y760065D01*
X1040266Y760142D01*
X1040576Y760104D01*
X1040834Y759950D01*
X1041351Y759184D01*
X1041712Y758839D01*
X1042229Y758609D01*
X1042694Y758532D01*
Y760142D01*
G01X1045345Y805226D02*
Y807466D01*
G01X1043720Y806253D02*
X1046970D01*
G01X1049245Y809353D02*
X1041045D01*
G01D02*
Y829753D01*
G01X1044578Y832390D02*
Y834816D01*
G01X1040000Y816907D02*
X1036900D01*
Y817673D01*
X1037055Y817980D01*
X1037262Y818210D01*
X1037572Y818402D01*
X1037933Y818555D01*
X1038450Y818593D01*
X1038967Y818555D01*
X1039328Y818402D01*
X1039638Y818210D01*
X1039845Y817980D01*
X1040000Y817673D01*
Y816907D01*
G01X1037417Y820122D02*
X1037107Y820352D01*
X1036952Y820620D01*
X1036900Y820927D01*
X1037003Y821310D01*
X1037262Y821578D01*
X1037572Y821655D01*
X1037882Y821617D01*
X1038140Y821463D01*
X1038657Y820697D01*
X1039018Y820352D01*
X1039535Y820122D01*
X1040000Y820045D01*
Y821655D01*
G01Y824410D02*
X1036900D01*
X1039122Y822992D01*
Y824908D01*
G01X1041045Y829253D02*
X1049245D01*
G01X1041045Y828753D02*
X1049245D01*
G01X1041045Y829753D02*
X1049245D01*
G01X1034588Y845622D02*
X1028388D01*
Y848822D01*
X1034588D01*
Y845622D01*
G01X1033057Y854010D02*
X1033249Y853700D01*
X1033479Y853493D01*
X1033747Y853390D01*
X1034054Y853493D01*
X1034284Y853700D01*
X1034514Y854010D01*
X1034591Y854423D01*
Y856490D01*
G01X1036157Y853390D02*
Y856490D01*
X1037077D01*
X1037384Y856335D01*
X1037614Y855973D01*
X1037691Y855560D01*
X1037614Y855147D01*
X1037422Y854837D01*
X1037077Y854682D01*
X1036157D01*
G01X1040791Y853390D02*
X1039257D01*
Y856490D01*
X1040791D01*
G01X1040177Y854992D02*
X1039257D01*
G01X1042319Y853390D02*
X1043929Y856490D01*
G01X1042319D02*
X1043929Y853390D01*
G01X1045496Y855973D02*
X1045726Y856283D01*
X1045994Y856438D01*
X1046301Y856490D01*
X1046684Y856387D01*
X1046952Y856128D01*
X1047029Y855818D01*
X1046991Y855508D01*
X1046837Y855250D01*
X1046071Y854733D01*
X1045726Y854372D01*
X1045496Y853855D01*
X1045419Y853390D01*
X1047029D01*
G01X1032119Y937722D02*
Y943922D01*
X1035319D01*
Y937722D01*
X1032119D01*
G01Y945136D02*
Y951336D01*
X1035319D01*
Y945136D01*
X1032119D01*
G01X1027223Y938714D02*
Y939518D01*
G01X1028409Y987631D02*
X1031609D01*
G01X1028409Y981431D02*
Y987631D01*
G01X1031609Y981431D02*
X1028409D01*
G01X1031609Y987631D02*
Y981431D01*
G01X1036409Y987631D02*
X1039609D01*
G01X1036409Y981431D02*
Y987631D01*
G01X1039609Y981431D02*
X1036409D01*
G01X1039609Y987631D02*
Y981431D01*
G01X1040409Y987631D02*
X1043609D01*
G01X1040409Y981431D02*
Y987631D01*
G01X1043609Y981431D02*
X1040409D01*
G01X1032409Y990431D02*
Y996631D01*
G01X1035609Y990431D02*
X1032409D01*
G01X1035609Y996631D02*
Y990431D01*
G01X1028409D02*
Y996631D01*
G01X1031609Y990431D02*
X1028409D01*
G01X1031609Y996631D02*
Y990431D01*
G01X1036409D02*
Y996631D01*
G01X1039609Y990431D02*
X1036409D01*
G01X1039609Y996631D02*
Y990431D01*
G01X1040409D02*
Y996631D01*
G01X1043609Y990431D02*
X1040409D01*
G01X1032409Y987631D02*
X1035609D01*
G01X1032409Y981431D02*
Y987631D01*
G01X1035609Y981431D02*
X1032409D01*
G01X1035609Y987631D02*
Y981431D01*
G01X1027609Y987631D02*
Y981431D01*
G01Y996631D02*
Y990431D01*
G01X1039152Y1008071D02*
Y1012671D01*
G01X1049352Y1008071D02*
X1039152D01*
G01X1029543Y1009265D02*
Y1019465D01*
G01X1034143Y1009265D02*
X1029543D01*
G01X1034143Y1019465D02*
Y1009265D01*
G01X1032409Y996631D02*
X1035609D01*
G01X1028409D02*
X1031609D01*
G01X1036409D02*
X1039609D01*
G01X1040409D02*
X1043609D01*
G01X1039152Y1012671D02*
X1049352D01*
G01X1039152Y1025271D02*
X1049352D01*
G01X1039152Y1020671D02*
Y1025271D01*
G01X1049352Y1020671D02*
X1039152D01*
G01X1026731Y1022862D02*
Y1012662D01*
G01X1050973Y1026071D02*
X1038093D01*
G01Y1032471D02*
Y1026071D01*
G01Y1019871D02*
X1050973D01*
G01Y1013471D02*
X1038093D01*
G01Y1019871D02*
Y1013471D01*
G01X1029543Y1019465D02*
X1034143D01*
G01X1029543Y1021865D02*
Y1032065D01*
G01X1034143Y1021865D02*
X1029543D01*
G01X1034143Y1032065D02*
Y1021865D01*
G01X1026531Y1028533D02*
Y1025333D01*
G01X1038093Y1032471D02*
X1050973D01*
G01X1029543Y1032065D02*
X1034143D01*
G01X1037706Y1105408D02*
Y1100808D01*
G01X1027506Y1105408D02*
X1037706D01*
G01X1027506Y1100808D02*
Y1105408D01*
G01X1037706Y1100808D02*
X1027506D01*
G01X1039327Y1112608D02*
Y1106208D01*
G01X1040177Y1107208D02*
X1043377D01*
G01X1040177Y1101008D02*
Y1107208D01*
G01X1043377Y1101008D02*
X1040177D01*
G01X1037706Y1118008D02*
Y1113408D01*
G01X1027506Y1118008D02*
X1037706D01*
G01X1027506Y1113408D02*
Y1118008D01*
G01X1037706Y1113408D02*
X1027506D01*
G01X1040127Y1108008D02*
Y1112608D01*
G01X1050327Y1108008D02*
X1040127D01*
G01Y1112608D02*
X1050327D01*
G01X1040127Y1120608D02*
Y1125208D01*
G01X1050327Y1120608D02*
X1040127D01*
G01X1039327Y1125208D02*
Y1118808D01*
G01X1040177Y1119808D02*
X1043377D01*
G01X1040177Y1113608D02*
Y1119808D01*
G01X1043377Y1113608D02*
X1040177D01*
G01X1037706Y1143208D02*
Y1138608D01*
G01X1027506D02*
Y1143208D01*
G01X1037706Y1138608D02*
X1027506D01*
G01X1037706Y1130608D02*
Y1126008D01*
G01X1027506Y1130608D02*
X1037706D01*
G01X1027506Y1126008D02*
Y1130608D01*
G01X1037706Y1126008D02*
X1027506D01*
G01X1040127Y1125208D02*
X1050327D01*
G01X1040127Y1133208D02*
Y1137808D01*
G01X1050327Y1133208D02*
X1040127D01*
G01Y1137808D02*
X1050327D01*
G01X1039327D02*
Y1131408D01*
G01X1040177Y1138808D02*
Y1145008D01*
G01X1043377Y1138808D02*
X1040177D01*
G01Y1132408D02*
X1043377D01*
G01X1040177Y1126208D02*
Y1132408D01*
G01X1043377Y1126208D02*
X1040177D01*
G01X1027506Y1143208D02*
X1037706D01*
G01Y1155808D02*
Y1151208D01*
G01X1027506Y1155808D02*
X1037706D01*
G01X1027506Y1151208D02*
Y1155808D01*
G01X1037706Y1151208D02*
X1027506D01*
G01X1040127Y1145808D02*
Y1150408D01*
G01X1050327Y1145808D02*
X1040127D01*
G01Y1150408D02*
X1050327D01*
G01X1039327D02*
Y1144008D01*
G01X1040177Y1145008D02*
X1043377D01*
G01X1040177Y1151408D02*
Y1157608D01*
G01X1043377Y1151408D02*
X1040177D01*
G01X1037706Y1168408D02*
Y1163808D01*
G01X1027506Y1168408D02*
X1037706D01*
G01X1027506Y1163808D02*
Y1168408D01*
G01X1037706Y1163808D02*
X1027506D01*
G01X1040127Y1158408D02*
Y1163008D01*
G01X1050327Y1158408D02*
X1040127D01*
G01Y1163008D02*
X1050327D01*
G01X1040127Y1171008D02*
Y1175608D01*
G01X1050327Y1171008D02*
X1040127D01*
G01X1039327Y1163008D02*
Y1156608D01*
G01Y1175608D02*
Y1169208D01*
G01X1040177Y1157608D02*
X1043377D01*
G01X1040177Y1170208D02*
X1043377D01*
G01X1040177Y1164008D02*
Y1170208D01*
G01X1043377Y1164008D02*
X1040177D01*
G01X1037706Y1181008D02*
Y1176408D01*
G01X1027506Y1181008D02*
X1037706D01*
G01X1027506Y1176408D02*
Y1181008D01*
G01X1037706Y1176408D02*
X1027506D01*
G01X1040127Y1175608D02*
X1050327D01*
G01X1040127Y1183608D02*
Y1188208D01*
G01X1050327Y1183608D02*
X1040127D01*
G01Y1188208D02*
X1050327D01*
G01X1039327D02*
Y1181808D01*
G01X1040177Y1182808D02*
X1043377D01*
G01X1040177Y1176608D02*
Y1182808D01*
G01X1043377Y1176608D02*
X1040177D01*
G01X1030975Y1207228D02*
X1026591Y1202844D01*
G01X1031541Y1206662D02*
X1033803Y1204400D01*
G01X1027157Y1202278D02*
X1031541Y1206662D01*
G01X1029419Y1200016D02*
X1027157Y1202278D01*
G01X1033803Y1204400D02*
X1029419Y1200016D01*
G01X1028713Y1209490D02*
X1030975Y1207228D01*
G01X1032253Y1221115D02*
X1029991Y1223377D01*
G01X1036637Y1225499D02*
X1032253Y1221115D01*
G01X1038476Y1214892D02*
X1042860Y1219276D01*
G01X1040738Y1212630D02*
X1038476Y1214892D01*
G01X1045122Y1217014D02*
X1040738Y1212630D01*
G01X1037910Y1215459D02*
X1035648Y1217721D01*
G01X1042294Y1219843D02*
X1037910Y1215459D01*
G01X1040032Y1222105D02*
X1042294Y1219843D01*
G01X1035648Y1217721D02*
X1040032Y1222105D01*
G01X1041305Y1212064D02*
X1045689Y1216448D01*
G01X1043567Y1209802D02*
X1041305Y1212064D01*
G01X1032818Y1220549D02*
X1037202Y1224933D01*
G01X1035080Y1218287D02*
X1032818Y1220549D01*
G01X1039464Y1222671D02*
X1035080Y1218287D01*
G01X1029426Y1223943D02*
X1027164Y1226205D01*
G01X1033810Y1228327D02*
X1029426Y1223943D01*
G01X1031548Y1230589D02*
X1033810Y1228327D01*
G01X1027164Y1226205D02*
X1031548Y1230589D01*
G01X1034375Y1227761D02*
X1036637Y1225499D01*
G01X1029991Y1223377D02*
X1034375Y1227761D01*
G01X1037202Y1224933D02*
X1039464Y1222671D01*
G01X1038563Y1311087D02*
X1044763D01*
Y1307887D01*
X1038563D01*
Y1311087D01*
G01X1045610Y1325454D02*
Y1313250D01*
X1029610D01*
Y1325454D01*
X1035610D01*
X1037610Y1322352D01*
X1039610Y1325454D01*
X1045610D01*
G01X1029581Y1340049D02*
Y1328081D01*
X1044293D01*
Y1340049D01*
X1029581D01*
G01X1034340Y1358972D02*
X1040540D01*
Y1355772D01*
X1034340D01*
Y1358972D01*
G01X1034283Y1362887D02*
X1040483D01*
Y1359687D01*
X1034283D01*
Y1362887D01*
G01X1040596Y1373167D02*
Y1366967D01*
X1037396D01*
Y1373167D01*
X1040596D01*
G01X1034291Y1366609D02*
X1040491D01*
Y1363409D01*
X1034291D01*
Y1366609D01*
G01X1029768Y1420967D02*
Y1393087D01*
G01X1032351Y1388786D02*
Y1386564D01*
X1032504Y1386099D01*
X1032811Y1385789D01*
X1033194Y1385686D01*
X1033577Y1385789D01*
X1033884Y1386099D01*
X1034037Y1386564D01*
Y1388786D01*
G01X1036754Y1385686D02*
Y1388786D01*
X1035336Y1386564D01*
X1037252D01*
G01X1038551Y1386306D02*
X1038781Y1385944D01*
X1039087Y1385738D01*
X1039432Y1385686D01*
X1039739Y1385738D01*
X1040046Y1385996D01*
X1040237Y1386306D01*
X1040276Y1386616D01*
X1040199Y1386978D01*
X1039931Y1387236D01*
X1039662Y1387339D01*
X1039317D01*
G01X1039662D02*
X1039892Y1387494D01*
X1040084Y1387753D01*
X1040161Y1388063D01*
X1040084Y1388373D01*
X1039892Y1388631D01*
X1039547Y1388786D01*
X1039202Y1388734D01*
X1038857Y1388528D01*
G01X1042417Y1385686D02*
X1042494Y1386358D01*
X1042609Y1386926D01*
X1042762Y1387443D01*
X1042954Y1388011D01*
X1043261Y1388786D01*
X1041727D01*
G01X1032324Y1411709D02*
Y1414809D01*
X1033244D01*
X1033551Y1414654D01*
X1033781Y1414292D01*
X1033858Y1413879D01*
X1033781Y1413466D01*
X1033589Y1413156D01*
X1033244Y1413001D01*
X1032324D01*
G01X1035348Y1411709D02*
Y1414809D01*
X1036114D01*
X1036421Y1414654D01*
X1036651Y1414447D01*
X1036843Y1414137D01*
X1036996Y1413776D01*
X1037034Y1413259D01*
X1036996Y1412742D01*
X1036843Y1412381D01*
X1036651Y1412071D01*
X1036421Y1411864D01*
X1036114Y1411709D01*
X1035348D01*
G01X1038563Y1414292D02*
X1038793Y1414602D01*
X1039061Y1414757D01*
X1039368Y1414809D01*
X1039751Y1414706D01*
X1040019Y1414447D01*
X1040096Y1414137D01*
X1040058Y1413827D01*
X1039904Y1413569D01*
X1039138Y1413052D01*
X1038793Y1412691D01*
X1038563Y1412174D01*
X1038486Y1411709D01*
X1040096D01*
G01X1029754Y1422649D02*
Y1425749D01*
X1030674D01*
X1030981Y1425594D01*
X1031211Y1425232D01*
X1031288Y1424819D01*
X1031211Y1424406D01*
X1031019Y1424096D01*
X1030674Y1423941D01*
X1029754D01*
G01X1033621Y1422649D02*
X1033314Y1422701D01*
X1033046Y1422907D01*
X1032816Y1423217D01*
X1032663Y1423579D01*
X1032586Y1423992D01*
Y1424406D01*
X1032663Y1424819D01*
X1032816Y1425181D01*
X1033046Y1425491D01*
X1033314Y1425697D01*
X1033621Y1425749D01*
X1033928Y1425697D01*
X1034196Y1425491D01*
X1034426Y1425181D01*
X1034579Y1424819D01*
X1034656Y1424406D01*
Y1423992D01*
X1034579Y1423579D01*
X1034426Y1423217D01*
X1034196Y1422907D01*
X1033928Y1422701D01*
X1033621Y1422649D01*
G01X1033928Y1423476D02*
X1034388Y1422649D01*
G01X1035993Y1423941D02*
X1036261Y1424302D01*
X1036491Y1424509D01*
X1036798Y1424612D01*
X1037066Y1424509D01*
X1037258Y1424302D01*
X1037411Y1423992D01*
X1037449Y1423631D01*
X1037411Y1423321D01*
X1037258Y1423011D01*
X1037028Y1422752D01*
X1036759Y1422649D01*
X1036453Y1422752D01*
X1036184Y1423062D01*
X1036031Y1423527D01*
X1035993Y1424044D01*
X1036069Y1424716D01*
X1036184Y1425077D01*
X1036376Y1425439D01*
X1036644Y1425697D01*
X1036913Y1425749D01*
X1037181Y1425646D01*
X1037373Y1425387D01*
G01X1039093Y1423941D02*
X1039361Y1424302D01*
X1039591Y1424509D01*
X1039898Y1424612D01*
X1040166Y1424509D01*
X1040358Y1424302D01*
X1040511Y1423992D01*
X1040549Y1423631D01*
X1040511Y1423321D01*
X1040358Y1423011D01*
X1040128Y1422752D01*
X1039859Y1422649D01*
X1039553Y1422752D01*
X1039284Y1423062D01*
X1039131Y1423527D01*
X1039093Y1424044D01*
X1039169Y1424716D01*
X1039284Y1425077D01*
X1039476Y1425439D01*
X1039744Y1425697D01*
X1040013Y1425749D01*
X1040281Y1425646D01*
X1040473Y1425387D01*
G01X1042921Y1425749D02*
X1042614Y1425646D01*
X1042384Y1425387D01*
X1042231Y1425077D01*
X1042116Y1424664D01*
X1042078Y1424199D01*
X1042116Y1423734D01*
X1042231Y1423321D01*
X1042384Y1423011D01*
X1042614Y1422752D01*
X1042921Y1422649D01*
X1043228Y1422752D01*
X1043458Y1423011D01*
X1043611Y1423321D01*
X1043726Y1423734D01*
X1043764Y1424199D01*
X1043726Y1424664D01*
X1043611Y1425077D01*
X1043458Y1425387D01*
X1043228Y1425646D01*
X1042921Y1425749D01*
G01X1045178Y1423114D02*
X1045408Y1422856D01*
X1045676Y1422701D01*
X1046021Y1422649D01*
X1046366Y1422752D01*
X1046634Y1422959D01*
X1046826Y1423321D01*
X1046864Y1423734D01*
X1046788Y1424147D01*
X1046596Y1424406D01*
X1046328Y1424612D01*
X1046059Y1424664D01*
X1045791Y1424612D01*
X1045446Y1424406D01*
X1045561Y1425749D01*
X1046596D01*
G01X1050204Y1515053D02*
G03X1101968Y1490945I20268J-24108D01*
G01X1037517Y1566448D02*
Y1569548D01*
G01X1039127D02*
Y1566448D01*
G01Y1567998D02*
X1037517D01*
G01X1041882Y1566448D02*
Y1569548D01*
X1040464Y1567326D01*
X1042380D01*
G01X1043794Y1567740D02*
X1044062Y1568101D01*
X1044292Y1568308D01*
X1044599Y1568411D01*
X1044867Y1568308D01*
X1045059Y1568101D01*
X1045212Y1567791D01*
X1045250Y1567430D01*
X1045212Y1567120D01*
X1045059Y1566810D01*
X1044829Y1566551D01*
X1044560Y1566448D01*
X1044254Y1566551D01*
X1043985Y1566861D01*
X1043832Y1567326D01*
X1043794Y1567843D01*
X1043870Y1568515D01*
X1043985Y1568876D01*
X1044177Y1569238D01*
X1044445Y1569496D01*
X1044714Y1569548D01*
X1044982Y1569445D01*
X1045174Y1569186D01*
G01X1062520Y1590307D02*
X1031212D01*
G01X1055176Y57756D02*
Y111397D01*
G01X1055472Y58150D02*
Y111397D01*
G01X1052380Y57933D02*
X1052690Y58125D01*
X1052897Y58355D01*
X1053000Y58623D01*
X1052897Y58930D01*
X1052690Y59160D01*
X1052380Y59390D01*
X1051967Y59467D01*
X1049900D01*
G01X1052380Y60957D02*
X1052742Y61187D01*
X1052948Y61493D01*
X1053000Y61838D01*
X1052948Y62145D01*
X1052690Y62452D01*
X1052380Y62643D01*
X1052070Y62682D01*
X1051708Y62605D01*
X1051450Y62337D01*
X1051347Y62068D01*
Y61723D01*
G01Y62068D02*
X1051192Y62298D01*
X1050933Y62490D01*
X1050623Y62567D01*
X1050313Y62490D01*
X1050055Y62298D01*
X1049900Y61953D01*
X1049952Y61608D01*
X1050158Y61263D01*
G01X1052638Y64248D02*
X1052897Y64517D01*
X1053000Y64823D01*
X1052897Y65130D01*
X1052587Y65398D01*
X1052122Y65590D01*
X1051657Y65667D01*
X1051088D01*
X1050623Y65590D01*
X1050210Y65398D01*
X1050003Y65168D01*
X1049900Y64900D01*
X1050003Y64593D01*
X1050210Y64363D01*
X1050520Y64210D01*
X1050933Y64133D01*
X1051295Y64210D01*
X1051657Y64402D01*
X1051863Y64632D01*
X1051915Y64900D01*
X1051812Y65207D01*
X1051553Y65437D01*
X1051088Y65667D01*
G01X1061557Y57756D02*
X1055176D01*
G01X1061152Y58150D02*
X1055472D01*
G01X1044033Y96067D02*
Y99267D01*
G01X1050233Y96067D02*
X1044033D01*
G01X1050233Y99267D02*
Y96067D01*
G01X1044033Y99267D02*
X1050233D01*
G01X1055472Y118848D02*
Y114048D01*
G01X1055176Y118848D02*
Y114048D01*
G01X1046049Y108095D02*
Y104895D01*
G01X1046906Y108086D02*
X1050106D01*
G01X1046906Y101886D02*
Y108086D01*
G01X1050106Y101886D02*
X1046906D01*
G01X1050106Y108086D02*
Y101886D01*
G01X1046049Y104095D02*
Y100895D01*
G01X1055472Y132607D02*
Y128340D01*
G01X1055176Y132607D02*
Y128340D01*
G01Y125781D02*
Y121219D01*
G01X1055472Y125781D02*
Y121219D01*
G01Y152756D02*
Y135647D01*
G01X1055176Y153150D02*
Y135647D01*
G01X1044024Y148437D02*
Y142237D01*
G01X1043500Y154107D02*
X1045722D01*
X1046187Y154260D01*
X1046497Y154567D01*
X1046600Y154950D01*
X1046497Y155333D01*
X1046187Y155640D01*
X1045722Y155793D01*
X1043500D01*
G01X1045980Y157207D02*
X1046342Y157437D01*
X1046548Y157743D01*
X1046600Y158088D01*
X1046548Y158395D01*
X1046290Y158702D01*
X1045980Y158893D01*
X1045670Y158932D01*
X1045308Y158855D01*
X1045050Y158587D01*
X1044947Y158318D01*
Y157973D01*
G01Y158318D02*
X1044792Y158548D01*
X1044533Y158740D01*
X1044223Y158817D01*
X1043913Y158740D01*
X1043655Y158548D01*
X1043500Y158203D01*
X1043552Y157858D01*
X1043758Y157513D01*
G01X1046600Y161073D02*
X1045928Y161150D01*
X1045360Y161265D01*
X1044843Y161418D01*
X1044275Y161610D01*
X1043500Y161917D01*
Y160383D01*
G01X1045980Y163407D02*
X1046342Y163637D01*
X1046548Y163943D01*
X1046600Y164288D01*
X1046548Y164595D01*
X1046290Y164902D01*
X1045980Y165093D01*
X1045670Y165132D01*
X1045308Y165055D01*
X1045050Y164787D01*
X1044947Y164518D01*
Y164173D01*
G01Y164518D02*
X1044792Y164748D01*
X1044533Y164940D01*
X1044223Y165017D01*
X1043913Y164940D01*
X1043655Y164748D01*
X1043500Y164403D01*
X1043552Y164058D01*
X1043758Y163713D01*
G01X1055176Y153150D02*
X1061557D01*
G01X1055472Y152756D02*
X1061152D01*
G01X1058903Y189535D02*
X1056477D01*
G01X1055363Y195583D02*
Y184087D01*
G01X1044780Y203645D02*
Y197645D01*
G01X1042733Y208464D02*
Y205264D01*
G01X1056630Y215265D02*
X1053530D01*
Y216185D01*
X1053685Y216492D01*
X1054047Y216722D01*
X1054460Y216799D01*
X1054873Y216722D01*
X1055183Y216530D01*
X1055338Y216185D01*
Y215265D01*
G01X1053530Y218289D02*
X1055752D01*
X1056217Y218442D01*
X1056527Y218749D01*
X1056630Y219132D01*
X1056527Y219515D01*
X1056217Y219822D01*
X1055752Y219975D01*
X1053530D01*
G01X1055338Y221504D02*
X1054977Y221772D01*
X1054770Y222002D01*
X1054667Y222309D01*
X1054770Y222577D01*
X1054977Y222769D01*
X1055287Y222922D01*
X1055648Y222960D01*
X1055958Y222922D01*
X1056268Y222769D01*
X1056527Y222539D01*
X1056630Y222270D01*
X1056527Y221964D01*
X1056217Y221695D01*
X1055752Y221542D01*
X1055235Y221504D01*
X1054563Y221580D01*
X1054202Y221695D01*
X1053840Y221887D01*
X1053582Y222155D01*
X1053530Y222424D01*
X1053633Y222692D01*
X1053892Y222884D01*
G01X1056630Y225792D02*
X1053530D01*
X1055752Y224374D01*
Y226290D01*
G01X1043959Y254969D02*
Y245521D01*
G01X1054336Y231459D02*
X1051136D01*
G01X1054336Y237659D02*
Y231459D01*
G01X1051136Y237659D02*
X1054336D01*
G01X1051136Y231459D02*
Y237659D01*
G01X1047136D02*
X1050336D01*
G01X1047136Y231459D02*
Y237659D01*
G01X1050336Y231459D02*
X1047136D01*
G01X1050336Y237659D02*
Y231459D01*
G01X1045762Y240081D02*
Y243281D01*
G01X1051962Y240081D02*
X1045762D01*
G01X1051962Y243281D02*
Y240081D01*
G01X1045762Y243281D02*
X1051962D01*
G01X1046101Y231434D02*
X1042901D01*
G01X1046101Y237634D02*
Y231434D01*
G01X1042901Y237634D02*
X1046101D01*
G01X1042901Y231434D02*
Y237634D01*
G01X1051566Y252199D02*
Y248999D01*
G01X1045366Y252199D02*
X1051566D01*
G01X1045366Y248999D02*
Y252199D01*
G01X1051566Y248999D02*
X1045366D01*
G01X1054125Y308974D02*
Y312174D01*
G01X1060325Y308974D02*
X1054125D01*
G01X1044050Y307351D02*
X1047250D01*
G01X1044050Y301151D02*
Y307351D01*
G01X1047250Y301151D02*
X1044050D01*
G01X1047250Y307351D02*
Y301151D01*
G01X1043096Y307351D02*
Y301151D01*
G01X1054125Y326556D02*
Y328686D01*
G01X1055088Y320843D02*
X1059424D01*
G01X1055088Y321243D02*
X1059424D01*
G01X1054125Y324443D02*
Y322390D01*
G01Y317643D02*
Y319642D01*
G01Y316139D02*
X1060325D01*
G01X1054125Y312939D02*
Y316139D01*
G01X1060325Y312939D02*
X1054125D01*
G01Y312174D02*
X1060325D01*
G01X1054125Y324443D02*
X1060325D01*
G01Y326556D02*
X1054125D01*
G01X1060325Y317643D02*
X1054125D01*
G01X1054995Y330156D02*
X1059453D01*
G01X1054995Y329756D02*
X1059453D01*
G01X1054125Y333356D02*
Y331207D01*
G01X1054012Y341109D02*
X1060212D01*
G01X1054012Y337909D02*
Y341109D01*
G01X1060212Y337909D02*
X1054012D01*
G01Y341909D02*
Y345109D01*
G01X1060212Y341909D02*
X1054012D01*
G01X1054125Y333356D02*
X1060325D01*
G01X1054012Y345109D02*
X1060212D01*
G01X1053604Y358551D02*
Y361751D01*
G01X1059804Y358551D02*
X1053604D01*
G01Y354551D02*
Y357751D01*
G01X1059804Y354551D02*
X1053604D01*
G01Y357751D02*
X1059804D01*
G01X1053604Y361751D02*
X1059804D01*
G01X1053604Y365876D02*
X1059804D01*
G01X1053604Y362676D02*
Y365876D01*
G01X1059804Y362676D02*
X1053604D01*
G01Y366676D02*
Y369876D01*
G01X1059804Y366676D02*
X1053604D01*
G01Y369876D02*
X1059804D01*
G01X1043008Y450181D02*
Y443981D01*
G01Y457181D02*
Y450981D01*
G01X1044669Y447404D02*
Y462758D01*
G01X1057347Y447404D02*
X1044669D01*
G01X1057347Y462758D02*
Y447404D01*
G01X1046057Y466900D02*
Y464678D01*
X1046210Y464213D01*
X1046517Y463903D01*
X1046900Y463800D01*
X1047283Y463903D01*
X1047590Y464213D01*
X1047743Y464678D01*
Y466900D01*
G01X1049272Y466383D02*
X1049502Y466693D01*
X1049770Y466848D01*
X1050077Y466900D01*
X1050460Y466797D01*
X1050728Y466538D01*
X1050805Y466228D01*
X1050767Y465918D01*
X1050613Y465660D01*
X1049847Y465143D01*
X1049502Y464782D01*
X1049272Y464265D01*
X1049195Y463800D01*
X1050805D01*
G01X1052448Y464162D02*
X1052717Y463903D01*
X1053023Y463800D01*
X1053330Y463903D01*
X1053598Y464213D01*
X1053790Y464678D01*
X1053867Y465143D01*
Y465712D01*
X1053790Y466177D01*
X1053598Y466590D01*
X1053368Y466797D01*
X1053100Y466900D01*
X1052793Y466797D01*
X1052563Y466590D01*
X1052410Y466280D01*
X1052333Y465867D01*
X1052410Y465505D01*
X1052602Y465143D01*
X1052832Y464937D01*
X1053100Y464885D01*
X1053407Y464988D01*
X1053637Y465247D01*
X1053867Y465712D01*
G01X1044866Y462758D02*
X1057347D01*
G01X1055534Y537250D02*
Y543450D01*
G01X1058734Y537250D02*
X1055534D01*
G01X1058734Y543450D02*
Y537250D01*
G01X1051544Y537291D02*
Y543491D01*
G01X1054744Y537291D02*
X1051544D01*
G01X1054744Y543491D02*
Y537291D01*
G01X1055534Y543450D02*
X1058734D01*
G01X1051544Y543491D02*
X1054744D01*
G01X1056761Y552955D02*
Y556155D01*
G01X1062961Y552955D02*
X1056761D01*
G01Y556155D02*
X1062961D01*
G01X1056761Y560155D02*
X1062961D01*
G01X1056761Y556955D02*
Y560155D01*
G01X1062961Y556955D02*
X1056761D01*
G01Y564155D02*
X1062961D01*
G01X1056761Y560955D02*
Y564155D01*
G01X1062961Y560955D02*
X1056761D01*
G01X1057055Y576556D02*
Y588556D01*
G01X1063055Y576556D02*
X1057055D01*
G01Y588556D02*
X1063055D01*
G01X1067225Y645047D02*
X1051625D01*
X1067225Y654017D01*
X1051625D01*
G01Y665092D02*
Y669772D01*
G01Y667432D02*
X1067225D01*
G01Y665092D02*
Y669772D01*
G01X1052925Y689622D02*
X1052145Y688452D01*
X1051625Y687087D01*
Y685527D01*
X1052405Y683772D01*
X1053705Y682407D01*
X1055265Y681432D01*
X1057865Y680652D01*
X1060205Y680457D01*
X1062545Y680847D01*
X1064105Y681432D01*
X1065665Y682602D01*
X1066705Y683967D01*
X1067225Y685332D01*
Y686697D01*
X1066705Y688062D01*
X1065925Y689232D01*
X1064885Y690207D01*
G01X1067225Y705572D02*
X1051625D01*
X1062805Y698357D01*
Y708107D01*
G01X1062466Y738802D02*
X1054966D01*
Y742348D01*
G01X1058591Y741042D02*
Y738802D01*
G01X1062466Y746208D02*
X1054966D01*
Y748448D01*
X1055341Y749195D01*
X1056216Y749755D01*
X1057216Y749942D01*
X1058216Y749755D01*
X1058966Y749288D01*
X1059341Y748448D01*
Y746208D01*
G01X1058716Y756135D02*
Y758002D01*
X1060966D01*
X1061716Y757442D01*
X1062216Y756788D01*
X1062466Y755855D01*
X1062216Y754922D01*
X1061716Y754268D01*
X1060966Y753708D01*
X1060091Y753335D01*
X1059091Y753148D01*
X1058216D01*
X1057466Y753335D01*
X1056591Y753708D01*
X1055841Y754268D01*
X1055341Y754828D01*
X1054966Y755575D01*
Y756228D01*
X1055216Y756975D01*
X1055716Y757535D01*
G01X1062466Y760742D02*
X1054966Y763075D01*
X1062466Y765408D01*
G01X1059841Y764568D02*
Y761582D01*
G01X1062466Y776208D02*
X1054966D01*
Y778448D01*
X1055341Y779195D01*
X1056216Y779755D01*
X1057216Y779942D01*
X1058216Y779755D01*
X1058966Y779288D01*
X1059341Y778448D01*
Y776208D01*
G01X1062466Y784268D02*
X1057466D01*
G01X1058466D02*
X1057966Y784735D01*
X1057591Y785202D01*
X1057466Y785855D01*
X1057591Y786322D01*
X1057966Y786882D01*
G01X1062466Y793075D02*
X1062341Y792515D01*
X1061841Y791955D01*
X1060966Y791582D01*
X1059966Y791395D01*
X1058966Y791582D01*
X1058091Y791955D01*
X1057591Y792515D01*
X1057466Y793075D01*
X1057591Y793635D01*
X1058091Y794195D01*
X1058966Y794568D01*
X1059966Y794662D01*
X1060966Y794568D01*
X1061841Y794195D01*
X1062341Y793635D01*
X1062466Y793075D01*
G01X1064341Y799268D02*
X1064841Y799922D01*
X1064966Y800668D01*
X1064841Y801322D01*
X1064216Y801882D01*
X1063341Y802255D01*
X1057466D01*
G01X1058466D02*
X1057966Y801882D01*
X1057591Y801322D01*
X1057466Y800668D01*
X1057716Y799922D01*
X1058216Y799455D01*
X1059091Y799082D01*
X1059966Y798895D01*
X1060716Y798988D01*
X1061591Y799362D01*
X1062216Y799922D01*
X1062466Y800668D01*
X1062341Y801228D01*
X1061841Y801882D01*
X1061341Y802255D01*
G01X1062466Y806768D02*
X1057466D01*
G01X1058466D02*
X1057966Y807235D01*
X1057591Y807702D01*
X1057466Y808355D01*
X1057591Y808822D01*
X1057966Y809382D01*
G01X1062466Y817255D02*
X1057466D01*
G01X1058341D02*
X1057841Y816882D01*
X1057591Y816322D01*
X1057466Y815668D01*
X1057716Y815015D01*
X1058216Y814455D01*
X1058966Y814082D01*
X1059966Y813895D01*
X1060966Y814082D01*
X1061716Y814455D01*
X1062216Y815015D01*
X1062466Y815668D01*
X1062341Y816322D01*
X1061966Y816882D01*
X1061466Y817255D01*
G01X1062466Y820275D02*
X1057466D01*
G01X1058841D02*
X1058216Y820555D01*
X1057716Y821022D01*
X1057466Y821675D01*
X1057716Y822328D01*
X1058216Y822795D01*
X1058841Y823075D01*
X1062466D01*
G01X1058841D02*
X1058216Y823355D01*
X1057716Y823822D01*
X1057466Y824475D01*
X1057716Y825128D01*
X1058216Y825595D01*
X1058966Y825875D01*
X1062466D01*
G01Y827775D02*
X1057466D01*
G01X1058841D02*
X1058216Y828055D01*
X1057716Y828522D01*
X1057466Y829175D01*
X1057716Y829828D01*
X1058216Y830295D01*
X1058841Y830575D01*
X1062466D01*
G01X1058841D02*
X1058216Y830855D01*
X1057716Y831322D01*
X1057466Y831975D01*
X1057716Y832628D01*
X1058216Y833095D01*
X1058966Y833375D01*
X1062466D01*
G01X1057466Y838075D02*
X1062466D01*
G01X1055466D02*
X1055341Y837888D01*
X1055091D01*
X1054966Y838075D01*
X1055091Y838262D01*
X1055341D01*
X1055466Y838075D01*
G01X1062466Y843988D02*
X1057466D01*
G01X1058716D02*
X1058091Y844362D01*
X1057591Y844922D01*
X1057466Y845668D01*
X1057591Y846322D01*
X1058091Y846882D01*
X1058966Y847162D01*
X1062466D01*
G01X1064341Y851768D02*
X1064841Y852422D01*
X1064966Y853168D01*
X1064841Y853822D01*
X1064216Y854382D01*
X1063341Y854755D01*
X1057466D01*
G01X1058466D02*
X1057966Y854382D01*
X1057591Y853822D01*
X1057466Y853168D01*
X1057716Y852422D01*
X1058216Y851955D01*
X1059091Y851582D01*
X1059966Y851395D01*
X1060716Y851488D01*
X1061591Y851862D01*
X1062216Y852422D01*
X1062466Y853168D01*
X1062341Y853728D01*
X1061841Y854382D01*
X1061341Y854755D01*
G01X1055527Y809459D02*
X1050927D01*
G01X1055527Y819659D02*
Y809459D01*
G01X1050927D02*
Y819659D01*
G01X1049245Y829753D02*
Y809353D01*
G01X1050927Y819659D02*
X1055527D01*
G01X1045045Y819753D02*
X1043245Y817153D01*
G01X1047245Y817053D02*
X1045045Y819753D01*
G01X1043145Y817053D02*
X1047245D01*
G01X1043145Y820053D02*
X1047245D01*
G01X1046551Y944796D02*
Y938796D01*
G01D02*
X1052551D01*
G01X1046551Y964387D02*
Y958387D01*
G01X1046404Y966698D02*
Y969798D01*
X1047401Y967215D01*
X1048398Y969798D01*
Y966698D01*
G01X1051268D02*
X1049734D01*
Y969798D01*
X1051268D01*
G01X1050654Y968300D02*
X1049734D01*
G01X1053601Y966698D02*
X1053869Y966750D01*
X1054176Y966905D01*
X1054368Y967163D01*
X1054444Y967525D01*
X1054368Y967886D01*
X1054138Y968196D01*
X1053793Y968351D01*
X1053409D01*
X1053179Y968455D01*
X1052988Y968713D01*
X1052911Y969075D01*
X1053026Y969436D01*
X1053294Y969695D01*
X1053601Y969798D01*
X1053908Y969695D01*
X1054176Y969436D01*
X1054291Y969075D01*
X1054214Y968713D01*
X1054023Y968455D01*
X1053793Y968351D01*
X1053409D01*
X1053064Y968196D01*
X1052834Y967886D01*
X1052758Y967525D01*
X1052834Y967163D01*
X1053026Y966905D01*
X1053333Y966750D01*
X1053601Y966698D01*
G01X1052551Y964387D02*
X1046551D01*
G01X1043609Y987631D02*
Y981431D01*
G01Y996631D02*
Y990431D01*
G01X1044409Y987631D02*
X1047609D01*
G01X1044409Y981431D02*
Y987631D01*
G01X1047609Y981431D02*
X1044409D01*
G01X1047609Y987631D02*
Y981431D01*
G01X1048409Y987631D02*
X1051609D01*
G01X1048409Y981431D02*
Y987631D01*
G01X1051609Y981431D02*
X1048409D01*
G01X1051609Y987631D02*
Y981431D01*
G01X1052409Y987631D02*
X1055609D01*
G01X1052409Y981431D02*
Y987631D01*
G01X1055609Y981431D02*
X1052409D01*
G01X1055609Y987631D02*
Y981431D01*
G01X1044409Y990431D02*
Y996631D01*
G01X1047609Y990431D02*
X1044409D01*
G01X1047609Y996631D02*
Y990431D01*
G01X1048409D02*
Y996631D01*
G01X1051609Y990431D02*
X1048409D01*
G01X1051609Y996631D02*
Y990431D01*
G01X1052409D02*
Y996631D01*
G01X1055609Y990431D02*
X1052409D01*
G01X1055609Y996631D02*
Y990431D01*
G01X1056409D02*
Y996631D01*
G01X1059609Y990431D02*
X1056409D01*
G01Y987631D02*
X1059609D01*
G01X1056409Y981431D02*
Y987631D01*
G01X1059609Y981431D02*
X1056409D01*
G01X1049352Y1012671D02*
Y1008071D01*
G01X1044409Y996631D02*
X1047609D01*
G01X1048409D02*
X1051609D01*
G01X1052409D02*
X1055609D01*
G01X1051823Y1008271D02*
Y1014471D01*
G01X1055023Y1008271D02*
X1051823D01*
G01X1055023Y1014471D02*
Y1008271D01*
G01X1056409Y996631D02*
X1059609D01*
G01X1049352Y1025271D02*
Y1020671D01*
G01X1051773Y1015271D02*
Y1019871D01*
G01X1061973Y1015271D02*
X1051773D01*
G01Y1019871D02*
X1061973D01*
G01X1050973Y1032471D02*
Y1026071D01*
G01Y1019871D02*
Y1013471D01*
G01X1051823Y1014471D02*
X1055023D01*
G01X1051823Y1020871D02*
Y1027071D01*
G01X1055023Y1020871D02*
X1051823D01*
G01X1055023Y1027071D02*
Y1020871D01*
G01X1051773Y1027871D02*
Y1032471D01*
G01X1061973Y1027871D02*
X1051773D01*
G01Y1032471D02*
X1061973D01*
G01X1051823Y1027071D02*
X1055023D01*
G01X1055511Y1258464D02*
Y1071456D01*
G01D02*
X1242519D01*
G01X1043377Y1107208D02*
Y1101008D01*
G01X1050327Y1112608D02*
Y1108008D01*
G01Y1125208D02*
Y1120608D01*
G01X1043377Y1119808D02*
Y1113608D01*
G01X1050327Y1137808D02*
Y1133208D01*
G01X1043377Y1145008D02*
Y1138808D01*
G01Y1132408D02*
Y1126208D01*
G01X1050327Y1150408D02*
Y1145808D01*
G01X1043377Y1157608D02*
Y1151408D01*
G01X1050327Y1163008D02*
Y1158408D01*
G01Y1175608D02*
Y1171008D01*
G01X1043377Y1170208D02*
Y1164008D01*
G01X1050327Y1188208D02*
Y1183608D01*
G01X1043377Y1182808D02*
Y1176608D01*
G01X1042860Y1219276D02*
X1045122Y1217014D01*
G01X1046396Y1206974D02*
X1044134Y1209236D01*
G01X1050780Y1211358D02*
X1046396Y1206974D01*
G01X1048518Y1213620D02*
X1050780Y1211358D01*
G01X1044134Y1209236D02*
X1048518Y1213620D01*
G01X1045689Y1216448D02*
X1047951Y1214186D01*
G01D02*
X1043567Y1209802D01*
G01X1242519Y1258464D02*
X1055511D01*
G01X1052887Y1313036D02*
X1059087D01*
Y1309836D01*
X1052887D01*
Y1313036D01*
G01X1052933Y1317205D02*
X1059133D01*
Y1314005D01*
X1052933D01*
Y1317205D01*
G01X1046836Y1325211D02*
X1053036D01*
Y1322011D01*
X1046836D01*
Y1325211D01*
G01X1046112Y1344581D02*
Y1342359D01*
X1046265Y1341894D01*
X1046572Y1341584D01*
X1046955Y1341481D01*
X1047338Y1341584D01*
X1047645Y1341894D01*
X1047798Y1342359D01*
Y1344581D01*
G01X1050515Y1341481D02*
Y1344581D01*
X1049097Y1342359D01*
X1051013D01*
G01X1052312Y1342101D02*
X1052542Y1341739D01*
X1052848Y1341533D01*
X1053193Y1341481D01*
X1053500Y1341533D01*
X1053807Y1341791D01*
X1053998Y1342101D01*
X1054037Y1342411D01*
X1053960Y1342773D01*
X1053692Y1343031D01*
X1053423Y1343134D01*
X1053078D01*
G01X1053423D02*
X1053653Y1343289D01*
X1053845Y1343548D01*
X1053922Y1343858D01*
X1053845Y1344168D01*
X1053653Y1344426D01*
X1053308Y1344581D01*
X1052963Y1344529D01*
X1052618Y1344323D01*
G01X1055527Y1342773D02*
X1055795Y1343134D01*
X1056025Y1343341D01*
X1056332Y1343444D01*
X1056600Y1343341D01*
X1056792Y1343134D01*
X1056945Y1342824D01*
X1056983Y1342463D01*
X1056945Y1342153D01*
X1056792Y1341843D01*
X1056562Y1341584D01*
X1056293Y1341481D01*
X1055987Y1341584D01*
X1055718Y1341894D01*
X1055565Y1342359D01*
X1055527Y1342876D01*
X1055603Y1343548D01*
X1055718Y1343909D01*
X1055910Y1344271D01*
X1056178Y1344529D01*
X1056447Y1344581D01*
X1056715Y1344478D01*
X1056907Y1344219D01*
G01X1062974Y1453196D02*
Y1440722D01*
X1050894D01*
Y1453196D01*
X1062974D01*
G01X1047185Y1465671D02*
Y1447167D01*
X1046252D01*
G01X1056735Y1458086D02*
X1062935D01*
Y1454886D01*
X1056735D01*
Y1458086D01*
G01X1046552Y1465671D02*
X1047185D01*
G01X1080056Y-62706D02*
Y-79306D01*
X1070456D01*
Y-62706D01*
X1080056D01*
G01X1061363Y-60739D02*
Y-57639D01*
X1062129D01*
X1062436Y-57794D01*
X1062666Y-58001D01*
X1062858Y-58311D01*
X1063011Y-58672D01*
X1063049Y-59189D01*
X1063011Y-59706D01*
X1062858Y-60067D01*
X1062666Y-60377D01*
X1062436Y-60584D01*
X1062129Y-60739D01*
X1061363D01*
G01X1066073D02*
X1064539D01*
Y-57639D01*
X1066073D01*
G01X1065459Y-59137D02*
X1064539D01*
G01X1068406Y-57639D02*
X1068099Y-57742D01*
X1067869Y-58001D01*
X1067716Y-58311D01*
X1067601Y-58724D01*
X1067563Y-59189D01*
X1067601Y-59654D01*
X1067716Y-60067D01*
X1067869Y-60377D01*
X1068099Y-60636D01*
X1068406Y-60739D01*
X1068713Y-60636D01*
X1068943Y-60377D01*
X1069096Y-60067D01*
X1069211Y-59654D01*
X1069249Y-59189D01*
X1069211Y-58724D01*
X1069096Y-58311D01*
X1068943Y-58001D01*
X1068713Y-57742D01*
X1068406Y-57639D01*
G01X1070663Y-60119D02*
X1070893Y-60481D01*
X1071199Y-60687D01*
X1071544Y-60739D01*
X1071851Y-60687D01*
X1072158Y-60429D01*
X1072349Y-60119D01*
X1072388Y-59809D01*
X1072311Y-59447D01*
X1072043Y-59189D01*
X1071774Y-59086D01*
X1071429D01*
G01X1071774D02*
X1072004Y-58931D01*
X1072196Y-58672D01*
X1072273Y-58362D01*
X1072196Y-58052D01*
X1072004Y-57794D01*
X1071659Y-57639D01*
X1071314Y-57691D01*
X1070969Y-57897D01*
G01X1073878Y-60739D02*
Y-57639D01*
X1075334D01*
G01X1074798Y-59137D02*
X1073878D01*
G01X1076556Y-61772D02*
X1078856D01*
G01X1080078Y-58156D02*
X1080308Y-57846D01*
X1080576Y-57691D01*
X1080883Y-57639D01*
X1081266Y-57742D01*
X1081534Y-58001D01*
X1081611Y-58311D01*
X1081573Y-58621D01*
X1081419Y-58879D01*
X1080653Y-59396D01*
X1080308Y-59757D01*
X1080078Y-60274D01*
X1080001Y-60739D01*
X1081611D01*
G01X1079980Y57756D02*
X1073599D01*
G01X1079684Y58150D02*
X1074004D01*
G01X1068630Y156615D02*
X1069377Y155990D01*
X1070217Y155615D01*
X1070963D01*
X1071710Y155990D01*
X1072270Y156615D01*
X1072550Y157490D01*
X1072363Y158365D01*
X1071897Y159115D01*
X1071057Y159615D01*
X1069937Y159865D01*
X1069283Y160365D01*
X1069003Y161240D01*
X1069190Y162115D01*
X1069657Y162740D01*
X1070310Y163115D01*
X1070963D01*
X1071617Y162865D01*
X1072177Y162240D01*
G01X1076130Y156615D02*
X1076877Y155990D01*
X1077717Y155615D01*
X1078463D01*
X1079210Y155990D01*
X1079770Y156615D01*
X1080050Y157490D01*
X1079863Y158365D01*
X1079397Y159115D01*
X1078557Y159615D01*
X1077437Y159865D01*
X1076783Y160365D01*
X1076503Y161240D01*
X1076690Y162115D01*
X1077157Y162740D01*
X1077810Y163115D01*
X1078463D01*
X1079117Y162865D01*
X1079677Y162240D01*
G01X1083537Y155615D02*
Y163115D01*
X1085403D01*
X1086150Y162740D01*
X1086710Y162240D01*
X1087177Y161490D01*
X1087550Y160615D01*
X1087643Y159365D01*
X1087550Y158115D01*
X1087177Y157240D01*
X1086710Y156490D01*
X1086150Y155990D01*
X1085403Y155615D01*
X1083537D01*
G01X1091503Y156490D02*
X1092157Y155865D01*
X1092903Y155615D01*
X1093650Y155865D01*
X1094303Y156615D01*
X1094770Y157740D01*
X1094957Y158865D01*
Y160240D01*
X1094770Y161365D01*
X1094303Y162365D01*
X1093743Y162865D01*
X1093090Y163115D01*
X1092343Y162865D01*
X1091783Y162365D01*
X1091410Y161615D01*
X1091223Y160615D01*
X1091410Y159740D01*
X1091877Y158865D01*
X1092437Y158365D01*
X1093090Y158240D01*
X1093837Y158490D01*
X1094397Y159115D01*
X1094957Y160240D01*
G01X1072080Y164436D02*
X1086880D01*
G01X1072080Y195440D02*
Y164436D01*
G01X1073599Y153150D02*
X1079980D01*
G01X1074004Y152756D02*
X1079684D01*
G01X1086880Y195440D02*
X1072080D01*
G01X1076083Y199912D02*
Y202338D01*
G01X1069400Y203983D02*
X1066300D01*
Y204903D01*
X1066455Y205210D01*
X1066817Y205440D01*
X1067230Y205517D01*
X1067643Y205440D01*
X1067953Y205248D01*
X1068108Y204903D01*
Y203983D01*
G01X1069400Y207007D02*
X1066300D01*
Y207773D01*
X1066455Y208080D01*
X1066662Y208310D01*
X1066972Y208502D01*
X1067333Y208655D01*
X1067850Y208693D01*
X1068367Y208655D01*
X1068728Y208502D01*
X1069038Y208310D01*
X1069245Y208080D01*
X1069400Y207773D01*
Y207007D01*
G01Y211410D02*
X1066300D01*
X1068522Y209992D01*
Y211908D01*
G01X1066817Y213322D02*
X1066507Y213552D01*
X1066352Y213820D01*
X1066300Y214127D01*
X1066403Y214510D01*
X1066662Y214778D01*
X1066972Y214855D01*
X1067282Y214817D01*
X1067540Y214663D01*
X1068057Y213897D01*
X1068418Y213552D01*
X1068935Y213322D01*
X1069400Y213245D01*
Y214855D01*
G01X1082131Y203452D02*
X1070635D01*
G01D02*
Y233011D01*
G01X1075983Y236652D02*
Y234412D01*
G01X1077608Y235625D02*
X1074358D01*
G01X1070635Y233011D02*
X1082131D01*
G01X1075852Y259204D02*
Y261630D01*
G01X1068800Y263183D02*
X1065700D01*
Y264103D01*
X1065855Y264410D01*
X1066217Y264640D01*
X1066630Y264717D01*
X1067043Y264640D01*
X1067353Y264448D01*
X1067508Y264103D01*
Y263183D01*
G01X1068800Y266207D02*
X1065700D01*
Y266973D01*
X1065855Y267280D01*
X1066062Y267510D01*
X1066372Y267702D01*
X1066733Y267855D01*
X1067250Y267893D01*
X1067767Y267855D01*
X1068128Y267702D01*
X1068438Y267510D01*
X1068645Y267280D01*
X1068800Y266973D01*
Y266207D01*
G01Y270150D02*
X1065700D01*
X1066320Y269690D01*
G01X1068800D02*
Y270610D01*
G01Y273250D02*
X1065700D01*
X1066320Y272790D01*
G01X1068800D02*
Y273710D01*
G01X1065700Y276350D02*
X1065803Y276043D01*
X1066062Y275813D01*
X1066372Y275660D01*
X1066785Y275545D01*
X1067250Y275507D01*
X1067715Y275545D01*
X1068128Y275660D01*
X1068438Y275813D01*
X1068697Y276043D01*
X1068800Y276350D01*
X1068697Y276657D01*
X1068438Y276887D01*
X1068128Y277040D01*
X1067715Y277155D01*
X1067250Y277193D01*
X1066785Y277155D01*
X1066372Y277040D01*
X1066062Y276887D01*
X1065803Y276657D01*
X1065700Y276350D01*
G01X1081900Y262744D02*
X1070404D01*
G01D02*
Y292303D01*
G01D02*
X1081900D01*
G01X1060325Y312174D02*
Y308974D01*
G01Y326556D02*
Y328686D01*
G01Y324443D02*
Y322236D01*
G01Y317643D02*
Y319641D01*
G01Y316139D02*
Y312939D01*
G01Y333356D02*
Y331058D01*
G01X1060212Y341109D02*
Y337909D01*
G01Y345109D02*
Y341909D01*
G01X1059804Y361751D02*
Y358551D01*
G01Y357751D02*
Y354551D01*
G01Y365876D02*
Y362676D01*
G01Y369876D02*
Y366676D01*
G01X1063673Y377000D02*
Y380200D01*
G01X1069873Y377000D02*
X1063673D01*
G01X1069873Y380200D02*
Y377000D01*
G01X1063673Y380200D02*
X1069873D01*
G01Y384200D02*
Y381000D01*
G01X1063673Y384200D02*
X1069873D01*
G01X1063673Y381000D02*
Y384200D01*
G01X1069873Y381000D02*
X1063673D01*
G01X1062173Y450700D02*
X1058973D01*
G01X1062173Y456900D02*
Y450700D01*
G01X1058973Y456900D02*
X1062173D01*
G01X1058973Y450700D02*
Y456900D01*
G01X1063673Y458000D02*
Y461200D01*
G01X1069873Y458000D02*
X1063673D01*
G01X1069873Y461200D02*
Y458000D01*
G01X1063673Y461200D02*
X1069873D01*
G01Y465200D02*
Y462000D01*
G01X1063673Y465200D02*
X1069873D01*
G01X1063673Y462000D02*
Y465200D01*
G01X1069873Y462000D02*
X1063673D01*
G01X1063761Y552955D02*
Y556155D01*
G01X1069961Y552955D02*
X1063761D01*
G01X1069961Y556155D02*
Y552955D01*
G01X1062961Y556155D02*
Y552955D01*
G01X1063761Y556155D02*
X1069961D01*
G01X1063761Y556955D02*
Y560155D01*
G01X1069961Y556955D02*
X1063761D01*
G01X1069961Y560155D02*
Y556955D01*
G01X1063761Y560155D02*
X1069961D01*
G01X1063793Y560967D02*
Y564167D01*
G01X1069993Y560967D02*
X1063793D01*
G01X1069993Y564167D02*
Y560967D01*
G01X1063793Y564167D02*
X1069993D01*
G01X1062961Y560155D02*
Y556955D01*
G01Y564155D02*
Y560955D01*
G01X1064055Y576556D02*
Y588556D01*
G01X1070055Y576556D02*
X1064055D01*
G01X1070055Y588556D02*
Y576556D01*
G01X1063055Y588556D02*
Y576556D01*
G01X1064055Y588556D02*
X1070055D01*
G01X1069241Y597188D02*
Y593988D01*
G01X1063041Y597188D02*
X1069241D01*
G01X1063041Y593988D02*
Y597188D01*
G01X1069241Y593988D02*
X1063041D01*
G01X1069241Y593188D02*
Y589988D01*
G01X1063041Y593188D02*
X1069241D01*
G01X1063041Y589988D02*
Y593188D01*
G01X1069241Y589988D02*
X1063041D01*
G01X1069273Y605200D02*
Y602000D01*
G01X1063073D02*
Y605200D01*
G01X1069273Y602000D02*
X1063073D01*
G01X1069241Y601188D02*
Y597988D01*
G01X1063041Y601188D02*
X1069241D01*
G01X1063041Y597988D02*
Y601188D01*
G01X1069241Y597988D02*
X1063041D01*
G01X1063073Y605200D02*
X1069273D01*
G01Y613200D02*
Y610000D01*
G01X1063073Y613200D02*
X1069273D01*
G01X1063073Y610000D02*
Y613200D01*
G01X1069273Y610000D02*
X1063073D01*
G01X1069273Y621200D02*
Y618000D01*
G01X1063073D02*
Y621200D01*
G01X1069273Y618000D02*
X1063073D01*
G01X1069241Y609188D02*
Y605988D01*
G01X1063041Y609188D02*
X1069241D01*
G01X1063041Y605988D02*
Y609188D01*
G01X1069241Y605988D02*
X1063041D01*
G01X1069273Y617200D02*
Y614000D01*
G01X1063073Y617200D02*
X1069273D01*
G01X1063073Y614000D02*
Y617200D01*
G01X1069273Y614000D02*
X1063073D01*
G01Y621200D02*
X1069273D01*
G01Y639569D02*
Y636369D01*
G01X1063073D02*
Y639569D01*
G01X1069273Y636369D02*
X1063073D01*
G01Y629821D02*
Y633021D01*
G01X1069273Y629821D02*
X1063073D01*
G01X1069273Y633021D02*
Y629821D01*
G01X1063073Y633021D02*
X1069273D01*
G01Y625200D02*
Y622000D01*
G01X1063073Y625200D02*
X1069273D01*
G01X1063073Y622000D02*
Y625200D01*
G01X1069273Y622000D02*
X1063073D01*
G01X1069273Y629200D02*
Y626000D01*
G01X1063073Y629200D02*
X1069273D01*
G01X1063073Y626000D02*
Y629200D01*
G01X1069273Y626000D02*
X1063073D01*
G01Y639569D02*
X1069273D01*
G01Y643574D02*
Y640374D01*
G01X1063073Y643574D02*
X1069273D01*
G01X1063073Y640374D02*
Y643574D01*
G01X1069273Y640374D02*
X1063073D01*
G01X1065419Y790585D02*
X1071419D01*
G01X1065419Y796585D02*
Y790585D01*
G01X1067092Y828585D02*
Y836085D01*
X1069519Y829835D01*
X1071946Y836085D01*
Y828585D01*
G01X1074686D02*
X1077019Y836085D01*
X1079352Y828585D01*
G01X1078512Y831210D02*
X1075526D01*
G01X1086572Y835460D02*
X1086012Y835835D01*
X1085359Y836085D01*
X1084612D01*
X1083772Y835710D01*
X1083119Y835085D01*
X1082652Y834335D01*
X1082279Y833085D01*
X1082186Y831960D01*
X1082372Y830835D01*
X1082652Y830085D01*
X1083212Y829335D01*
X1083866Y828835D01*
X1084519Y828585D01*
X1085172D01*
X1085826Y828835D01*
X1086386Y829210D01*
X1086852Y829710D01*
G01X1065972Y839152D02*
Y842252D01*
X1066969Y839669D01*
X1067966Y842252D01*
Y839152D01*
G01X1070836D02*
X1069302D01*
Y842252D01*
X1070836D01*
G01X1070222Y840754D02*
X1069302D01*
G01X1073092Y839152D02*
X1073169Y839824D01*
X1073284Y840392D01*
X1073437Y840909D01*
X1073629Y841477D01*
X1073936Y842252D01*
X1072402D01*
G01X1065419Y837829D02*
Y831829D01*
G01X1071419Y837829D02*
X1065419D01*
G01X1061401Y906943D02*
Y900943D01*
X1067401D01*
G01X1063041Y916643D02*
X1063788Y916018D01*
X1064628Y915643D01*
X1065374D01*
X1066121Y916018D01*
X1066681Y916643D01*
X1066961Y917518D01*
X1066774Y918393D01*
X1066308Y919143D01*
X1065468Y919643D01*
X1064348Y919893D01*
X1063694Y920393D01*
X1063414Y921268D01*
X1063601Y922143D01*
X1064068Y922768D01*
X1064721Y923143D01*
X1065374D01*
X1066028Y922893D01*
X1066588Y922268D01*
G01X1070821Y915393D02*
X1074181Y923143D01*
G01X1077854Y915643D02*
Y923143D01*
X1082148Y915643D01*
Y923143D01*
G01X1067401Y924565D02*
X1061401D01*
Y918565D01*
G01X1073690Y947841D02*
Y955341D01*
X1076024D01*
X1076770Y954966D01*
X1077237Y954466D01*
X1077424Y953466D01*
X1077237Y952466D01*
X1076677Y951841D01*
X1076024Y951466D01*
X1073690D01*
G01X1076024D02*
X1077424Y947841D01*
G01X1081657Y951216D02*
X1084644D01*
X1084364Y952091D01*
X1083897Y952591D01*
X1083244Y952841D01*
X1082590Y952716D01*
X1082030Y952341D01*
X1081657Y951466D01*
X1081470Y950716D01*
Y949966D01*
X1081657Y949216D01*
X1082124Y948466D01*
X1082684Y947966D01*
X1083337Y947841D01*
X1083990Y948091D01*
X1084644Y948841D01*
G01X1088224Y952841D02*
X1089344Y947841D01*
X1090557Y952841D01*
X1091770Y947841D01*
X1092890Y952841D01*
G01X1098057Y947841D02*
X1097497Y947966D01*
X1096937Y948466D01*
X1096564Y949341D01*
X1096377Y950341D01*
X1096564Y951341D01*
X1096937Y952216D01*
X1097497Y952716D01*
X1098057Y952841D01*
X1098617Y952716D01*
X1099177Y952216D01*
X1099550Y951341D01*
X1099644Y950341D01*
X1099550Y949341D01*
X1099177Y948466D01*
X1098617Y947966D01*
X1098057Y947841D01*
G01X1104250D02*
Y952841D01*
G01Y951841D02*
X1104717Y952341D01*
X1105184Y952716D01*
X1105837Y952841D01*
X1106304Y952716D01*
X1106864Y952341D01*
G01X1111470Y947841D02*
Y955341D01*
G01X1114457Y952841D02*
X1111470Y949966D01*
G01X1112684Y951091D02*
X1114644Y947841D01*
G01X1126377Y952841D02*
X1128057Y947841D01*
X1129737Y952841D01*
G01X1134157Y951216D02*
X1137144D01*
X1136864Y952091D01*
X1136397Y952591D01*
X1135744Y952841D01*
X1135090Y952716D01*
X1134530Y952341D01*
X1134157Y951466D01*
X1133970Y950716D01*
Y949966D01*
X1134157Y949216D01*
X1134624Y948466D01*
X1135184Y947966D01*
X1135837Y947841D01*
X1136490Y948091D01*
X1137144Y948841D01*
G01X1141750Y947841D02*
Y952841D01*
G01Y951841D02*
X1142217Y952341D01*
X1142684Y952716D01*
X1143337Y952841D01*
X1143804Y952716D01*
X1144364Y952341D01*
G01X1149157Y948716D02*
X1149624Y948216D01*
X1150277Y947841D01*
X1150837D01*
X1151397Y948091D01*
X1151770Y948466D01*
X1151957Y948966D01*
X1151864Y949716D01*
X1151490Y950091D01*
X1149810Y950841D01*
X1149437Y951716D01*
X1149624Y952341D01*
X1149997Y952716D01*
X1150557Y952841D01*
X1151117Y952716D01*
X1151677Y952341D01*
G01X1158057Y952841D02*
Y947841D01*
G01Y954841D02*
X1157870Y954966D01*
Y955216D01*
X1158057Y955341D01*
X1158244Y955216D01*
Y954966D01*
X1158057Y954841D01*
G01X1165557Y947841D02*
X1164997Y947966D01*
X1164437Y948466D01*
X1164064Y949341D01*
X1163877Y950341D01*
X1164064Y951341D01*
X1164437Y952216D01*
X1164997Y952716D01*
X1165557Y952841D01*
X1166117Y952716D01*
X1166677Y952216D01*
X1167050Y951341D01*
X1167144Y950341D01*
X1167050Y949341D01*
X1166677Y948466D01*
X1166117Y947966D01*
X1165557Y947841D01*
G01X1171470D02*
Y952841D01*
G01Y951591D02*
X1171844Y952216D01*
X1172404Y952716D01*
X1173150Y952841D01*
X1173804Y952716D01*
X1174364Y952216D01*
X1174644Y951341D01*
Y947841D01*
G01X1072409Y990431D02*
Y996631D01*
G01X1075609Y990431D02*
X1072409D01*
G01Y987631D02*
X1075609D01*
G01X1072409Y981431D02*
Y987631D01*
G01X1075609Y981431D02*
X1072409D01*
G01X1059609Y996631D02*
Y990431D01*
G01Y987631D02*
Y981431D01*
G01X1064409Y990431D02*
Y996631D01*
G01X1067609Y990431D02*
X1064409D01*
G01X1067609Y996631D02*
Y990431D01*
G01X1060409D02*
Y996631D01*
G01X1063609Y990431D02*
X1060409D01*
G01X1063609Y996631D02*
Y990431D01*
G01X1068409D02*
Y996631D01*
G01X1071609Y990431D02*
X1068409D01*
G01X1071609Y996631D02*
Y990431D01*
G01X1064409Y987631D02*
X1067609D01*
G01X1064409Y981431D02*
Y987631D01*
G01X1067609Y981431D02*
X1064409D01*
G01X1067609Y987631D02*
Y981431D01*
G01X1060409Y987631D02*
X1063609D01*
G01X1060409Y981431D02*
Y987631D01*
G01X1063609Y981431D02*
X1060409D01*
G01X1063609Y987631D02*
Y981431D01*
G01X1072409Y996631D02*
X1075609D01*
G01X1064409D02*
X1067609D01*
G01X1060409D02*
X1063609D01*
G01X1068409D02*
X1071609D01*
G01X1061973Y1019871D02*
Y1015271D01*
G01Y1032471D02*
Y1027871D01*
G01X1062401Y1066535D02*
G03X1062231Y1069799I-31496J-4D01*
G01X1062401Y1263304D02*
G03Y1263386I-31497J41D01*
G01X1064660Y1440866D02*
Y1447066D01*
X1067860D01*
Y1440866D01*
X1064660D01*
G01X1071305Y1452756D02*
Y1455856D01*
X1072225D01*
X1072532Y1455701D01*
X1072762Y1455339D01*
X1072839Y1454926D01*
X1072762Y1454513D01*
X1072570Y1454203D01*
X1072225Y1454048D01*
X1071305D01*
G01X1075172Y1452756D02*
X1074865Y1452808D01*
X1074597Y1453014D01*
X1074367Y1453324D01*
X1074214Y1453686D01*
X1074137Y1454099D01*
Y1454513D01*
X1074214Y1454926D01*
X1074367Y1455288D01*
X1074597Y1455598D01*
X1074865Y1455804D01*
X1075172Y1455856D01*
X1075479Y1455804D01*
X1075747Y1455598D01*
X1075977Y1455288D01*
X1076130Y1454926D01*
X1076207Y1454513D01*
Y1454099D01*
X1076130Y1453686D01*
X1075977Y1453324D01*
X1075747Y1453014D01*
X1075479Y1452808D01*
X1075172Y1452756D01*
G01X1075479Y1453583D02*
X1075939Y1452756D01*
G01X1077544Y1454048D02*
X1077812Y1454409D01*
X1078042Y1454616D01*
X1078349Y1454719D01*
X1078617Y1454616D01*
X1078809Y1454409D01*
X1078962Y1454099D01*
X1079000Y1453738D01*
X1078962Y1453428D01*
X1078809Y1453118D01*
X1078579Y1452859D01*
X1078310Y1452756D01*
X1078004Y1452859D01*
X1077735Y1453169D01*
X1077582Y1453634D01*
X1077544Y1454151D01*
X1077620Y1454823D01*
X1077735Y1455184D01*
X1077927Y1455546D01*
X1078195Y1455804D01*
X1078464Y1455856D01*
X1078732Y1455753D01*
X1078924Y1455494D01*
G01X1080644Y1454048D02*
X1080912Y1454409D01*
X1081142Y1454616D01*
X1081449Y1454719D01*
X1081717Y1454616D01*
X1081909Y1454409D01*
X1082062Y1454099D01*
X1082100Y1453738D01*
X1082062Y1453428D01*
X1081909Y1453118D01*
X1081679Y1452859D01*
X1081410Y1452756D01*
X1081104Y1452859D01*
X1080835Y1453169D01*
X1080682Y1453634D01*
X1080644Y1454151D01*
X1080720Y1454823D01*
X1080835Y1455184D01*
X1081027Y1455546D01*
X1081295Y1455804D01*
X1081564Y1455856D01*
X1081832Y1455753D01*
X1082024Y1455494D01*
G01X1084472Y1455856D02*
X1084165Y1455753D01*
X1083935Y1455494D01*
X1083782Y1455184D01*
X1083667Y1454771D01*
X1083629Y1454306D01*
X1083667Y1453841D01*
X1083782Y1453428D01*
X1083935Y1453118D01*
X1084165Y1452859D01*
X1084472Y1452756D01*
X1084779Y1452859D01*
X1085009Y1453118D01*
X1085162Y1453428D01*
X1085277Y1453841D01*
X1085315Y1454306D01*
X1085277Y1454771D01*
X1085162Y1455184D01*
X1085009Y1455494D01*
X1084779Y1455753D01*
X1084472Y1455856D01*
G01X1086844Y1454048D02*
X1087112Y1454409D01*
X1087342Y1454616D01*
X1087649Y1454719D01*
X1087917Y1454616D01*
X1088109Y1454409D01*
X1088262Y1454099D01*
X1088300Y1453738D01*
X1088262Y1453428D01*
X1088109Y1453118D01*
X1087879Y1452859D01*
X1087610Y1452756D01*
X1087304Y1452859D01*
X1087035Y1453169D01*
X1086882Y1453634D01*
X1086844Y1454151D01*
X1086920Y1454823D01*
X1087035Y1455184D01*
X1087227Y1455546D01*
X1087495Y1455804D01*
X1087764Y1455856D01*
X1088032Y1455753D01*
X1088224Y1455494D01*
G01X1074331Y1695110D02*
Y1576803D01*
G01X1062520Y1683299D02*
Y1590307D01*
G01X1079980Y57756D02*
Y104442D01*
G01X1079684Y58150D02*
Y104442D01*
G01X1087516Y86929D02*
X1084316D01*
G01X1087516Y93129D02*
Y86929D01*
G01X1084316Y93129D02*
X1087516D01*
G01X1084316Y86929D02*
Y93129D01*
G01X1091516Y86929D02*
X1088316D01*
G01Y93129D02*
X1091516D01*
G01X1088316Y86929D02*
Y93129D01*
G01X1085512Y97026D02*
Y103226D01*
G01X1088712Y97026D02*
X1085512D01*
G01X1088712Y103226D02*
Y97026D01*
G01X1079980Y111507D02*
Y107060D01*
G01X1079684Y111507D02*
Y107060D01*
G01Y118680D02*
Y114087D01*
G01X1079980Y118680D02*
Y114087D01*
G01X1085512Y103226D02*
X1088712D01*
G01X1079684Y132859D02*
Y128325D01*
G01X1079980Y132859D02*
Y128325D01*
G01Y125844D02*
Y121329D01*
G01X1079684Y125844D02*
Y121329D01*
G01Y152756D02*
Y135509D01*
G01X1079980Y153150D02*
Y135509D01*
G01X1089210Y145940D02*
Y149140D01*
G01X1095410Y145940D02*
X1089210D01*
G01Y149140D02*
X1095410D01*
G01X1086880Y164436D02*
Y195440D01*
G01X1089210Y153140D02*
X1095410D01*
G01X1089210Y149940D02*
Y153140D01*
G01X1095410Y149940D02*
X1089210D01*
G01X1091846Y171473D02*
X1088646D01*
G01Y177673D02*
X1091846D01*
G01X1088646Y171473D02*
Y177673D01*
G01X1084193Y213035D02*
Y225035D01*
G01X1090193Y213035D02*
X1084193D01*
G01X1090193Y225035D02*
Y213035D01*
G01X1082131Y233011D02*
Y203452D01*
G01X1084193Y225035D02*
X1090193D01*
G01X1091033Y226621D02*
Y232621D01*
G01X1103033Y226621D02*
X1091033D01*
G01Y232621D02*
X1103033D01*
G01X1083476Y250325D02*
Y234813D01*
G01D02*
X1114568D01*
G01X1081900Y292303D02*
Y262744D01*
G01X1083583Y251600D02*
Y254700D01*
X1084503D01*
X1084810Y254545D01*
X1085040Y254183D01*
X1085117Y253770D01*
X1085040Y253357D01*
X1084848Y253047D01*
X1084503Y252892D01*
X1083583D01*
G01X1086607Y251600D02*
Y254700D01*
X1087373D01*
X1087680Y254545D01*
X1087910Y254338D01*
X1088102Y254028D01*
X1088255Y253667D01*
X1088293Y253150D01*
X1088255Y252633D01*
X1088102Y252272D01*
X1087910Y251962D01*
X1087680Y251755D01*
X1087373Y251600D01*
X1086607D01*
G01X1091010D02*
Y254700D01*
X1089592Y252478D01*
X1091508D01*
G01X1094110Y251600D02*
Y254700D01*
X1092692Y252478D01*
X1094608D01*
G01X1114568Y250325D02*
X1083476D01*
G01X1083771Y271655D02*
Y283655D01*
G01X1089771Y271655D02*
X1083771D01*
G01X1089771Y283655D02*
Y271655D01*
G01X1083771Y283655D02*
X1089771D01*
G01X1080309Y297198D02*
Y294958D01*
G01X1081934Y296171D02*
X1078684D01*
G01X1093954Y283383D02*
X1090754D01*
G01Y289583D02*
X1093954D01*
G01X1090754Y283383D02*
Y289583D01*
G01X1082726Y366063D02*
Y391424D01*
G01X1080780Y365983D02*
X1081090Y366175D01*
X1081297Y366405D01*
X1081400Y366673D01*
X1081297Y366980D01*
X1081090Y367210D01*
X1080780Y367440D01*
X1080367Y367517D01*
X1078300D01*
G01X1078817Y369122D02*
X1078507Y369352D01*
X1078352Y369620D01*
X1078300Y369927D01*
X1078403Y370310D01*
X1078662Y370578D01*
X1078972Y370655D01*
X1079282Y370617D01*
X1079540Y370463D01*
X1080057Y369697D01*
X1080418Y369352D01*
X1080935Y369122D01*
X1081400Y369045D01*
Y370655D01*
G01Y373410D02*
X1078300D01*
X1080522Y371992D01*
Y373908D01*
G01X1082726Y366063D02*
X1098272D01*
G01X1082726Y398425D02*
Y393935D01*
G01Y405519D02*
Y401173D01*
G01Y412551D02*
Y408103D01*
G01Y419749D02*
Y415258D01*
G01Y426935D02*
Y422271D01*
G01Y433999D02*
Y429252D01*
G01Y441124D02*
Y436377D01*
G01Y469861D02*
Y443616D01*
G01Y477037D02*
Y472208D01*
G01Y484131D02*
Y479384D01*
G01Y491216D02*
Y486417D01*
G01Y513965D02*
Y493456D01*
G01Y521120D02*
Y516446D01*
G01Y639449D02*
Y537708D01*
G01Y528234D02*
Y523436D01*
G01Y535125D02*
Y530551D01*
G01X1076727Y653601D02*
X1075947Y652431D01*
X1075427Y651066D01*
Y649506D01*
X1076207Y647751D01*
X1077507Y646386D01*
X1079067Y645411D01*
X1081667Y644631D01*
X1084007Y644436D01*
X1086347Y644826D01*
X1087907Y645411D01*
X1089467Y646581D01*
X1090507Y647946D01*
X1091027Y649311D01*
Y650676D01*
X1090507Y652041D01*
X1089727Y653211D01*
X1088687Y654186D01*
G01X1082707Y668771D02*
X1081927Y669551D01*
X1080627Y670136D01*
X1078807Y670526D01*
X1077247Y670136D01*
X1076207Y669356D01*
X1075427Y667991D01*
Y662726D01*
X1091027D01*
Y669161D01*
X1089987Y670526D01*
X1088427Y671306D01*
X1086607Y671696D01*
X1084787Y671306D01*
X1083227Y670136D01*
X1082707Y668771D01*
Y662726D01*
G01X1075427Y681211D02*
X1091027D01*
Y689011D01*
G01X1096227Y697161D02*
Y708861D01*
G01X1075427Y720911D02*
X1091027D01*
G01X1075427Y716426D02*
Y725396D01*
G01X1091027Y738811D02*
X1090767Y737251D01*
X1089727Y735886D01*
X1088167Y734716D01*
X1086347Y733936D01*
X1084267Y733546D01*
X1082187D01*
X1080107Y733936D01*
X1078287Y734716D01*
X1076727Y735886D01*
X1075687Y737251D01*
X1075427Y738811D01*
X1075687Y740371D01*
X1076727Y741736D01*
X1078287Y742906D01*
X1080107Y743686D01*
X1082187Y744076D01*
X1084267D01*
X1086347Y743686D01*
X1088167Y742906D01*
X1089727Y741736D01*
X1090767Y740371D01*
X1091027Y738811D01*
G01Y752811D02*
X1075427D01*
Y757491D01*
X1076207Y759051D01*
X1078027Y760221D01*
X1080107Y760611D01*
X1082187Y760221D01*
X1083747Y759246D01*
X1084527Y757491D01*
Y752811D01*
G01X1098202Y639449D02*
X1082726D01*
G01X1084685Y868964D02*
Y862964D01*
X1090685D01*
G01X1085925Y878501D02*
X1086672Y877876D01*
X1087512Y877501D01*
X1088258D01*
X1089005Y877876D01*
X1089565Y878501D01*
X1089845Y879376D01*
X1089658Y880251D01*
X1089192Y881001D01*
X1088352Y881501D01*
X1087232Y881751D01*
X1086578Y882251D01*
X1086298Y883126D01*
X1086485Y884001D01*
X1086952Y884626D01*
X1087605Y885001D01*
X1088258D01*
X1088912Y884751D01*
X1089472Y884126D01*
G01X1093705Y877251D02*
X1097065Y885001D01*
G01X1100738Y877501D02*
Y885001D01*
X1105032Y877501D01*
Y885001D01*
G01X1085138Y887968D02*
Y891068D01*
X1086135Y888485D01*
X1087132Y891068D01*
Y887968D01*
G01X1090002D02*
X1088468D01*
Y891068D01*
X1090002D01*
G01X1089388Y889570D02*
X1088468D01*
G01X1092335Y887968D02*
Y891068D01*
X1091875Y890448D01*
G01Y887968D02*
X1092795D01*
G01X1095435Y891068D02*
X1095128Y890965D01*
X1094898Y890706D01*
X1094745Y890396D01*
X1094630Y889983D01*
X1094592Y889518D01*
X1094630Y889053D01*
X1094745Y888640D01*
X1094898Y888330D01*
X1095128Y888071D01*
X1095435Y887968D01*
X1095742Y888071D01*
X1095972Y888330D01*
X1096125Y888640D01*
X1096240Y889053D01*
X1096278Y889518D01*
X1096240Y889983D01*
X1096125Y890396D01*
X1095972Y890706D01*
X1095742Y890965D01*
X1095435Y891068D01*
G01X1090685Y886586D02*
X1084685D01*
Y880586D01*
G01X1075609Y996631D02*
Y990431D01*
G01Y987631D02*
Y981431D01*
G01X1087708Y1528108D02*
Y1521908D01*
X1084508D01*
Y1528108D01*
X1087708D01*
G01X1101968Y1490945D02*
G03X1076692Y1521821I-31496J0D01*
G01X1089398Y1525198D02*
Y1527849D01*
X1093398Y1530900D01*
X1089398Y1533951D01*
Y1536602D01*
X1101602D01*
Y1525198D01*
X1089398D01*
G01X1089304Y1591681D02*
Y1597881D01*
G01X1092504Y1591681D02*
X1089304D01*
G01X1088504D02*
X1085304D01*
G01X1088504Y1597881D02*
Y1591681D01*
G01X1085304D02*
Y1597881D01*
G01X1084869Y1580885D02*
Y1587085D01*
G01X1088069Y1580885D02*
X1084869D01*
G01X1088069Y1587085D02*
Y1580885D01*
G01X1084869Y1587085D02*
X1088069D01*
G01X1092069Y1580885D02*
X1088869D01*
G01D02*
Y1587085D01*
G01D02*
X1092069D01*
G01X1088806Y1610132D02*
Y1618332D01*
G01X1101208Y1610132D02*
X1088806D01*
G01X1089304Y1597881D02*
X1092504D01*
G01X1085304D02*
X1088504D01*
G01X1085335Y1602098D02*
X1082135D01*
G01X1085335Y1608298D02*
Y1602098D01*
G01X1082135Y1608298D02*
X1085335D01*
G01X1082135Y1602098D02*
Y1608298D01*
G01X1085335Y1610034D02*
X1082135D01*
G01X1085335Y1616234D02*
Y1610034D01*
G01X1082135D02*
Y1616234D01*
G01X1088806Y1618332D02*
X1101208D01*
G01X1082135Y1616234D02*
X1085335D01*
G01X1087874Y1636525D02*
X1091074D01*
G01Y1630325D02*
X1087874D01*
G01X1091074Y1636525D02*
Y1630325D01*
G01X1087874D02*
Y1636525D01*
G01X1087074Y1630325D02*
X1083874D01*
G01X1087074Y1636525D02*
Y1630325D01*
G01X1083874Y1636525D02*
X1087074D01*
G01X1083874Y1630325D02*
Y1636525D01*
G01X1098349Y42722D02*
Y45822D01*
G01X1099959D02*
Y42722D01*
G01Y44272D02*
X1098349D01*
G01X1101526Y44014D02*
X1101794Y44375D01*
X1102024Y44582D01*
X1102331Y44685D01*
X1102599Y44582D01*
X1102791Y44375D01*
X1102944Y44065D01*
X1102982Y43704D01*
X1102944Y43394D01*
X1102791Y43084D01*
X1102561Y42825D01*
X1102292Y42722D01*
X1101986Y42825D01*
X1101717Y43135D01*
X1101564Y43600D01*
X1101526Y44117D01*
X1101602Y44789D01*
X1101717Y45150D01*
X1101909Y45512D01*
X1102177Y45770D01*
X1102446Y45822D01*
X1102714Y45719D01*
X1102906Y45460D01*
G01X1104626Y45305D02*
X1104856Y45615D01*
X1105124Y45770D01*
X1105431Y45822D01*
X1105814Y45719D01*
X1106082Y45460D01*
X1106159Y45150D01*
X1106121Y44840D01*
X1105967Y44582D01*
X1105201Y44065D01*
X1104856Y43704D01*
X1104626Y43187D01*
X1104549Y42722D01*
X1106159D01*
G01X1106571Y66981D02*
Y70181D01*
G01X1112771Y66981D02*
X1106571D01*
G01X1095905Y74540D02*
Y77740D01*
G01X1102105Y74540D02*
X1095905D01*
G01X1102105Y77740D02*
Y74540D01*
G01X1095905Y77740D02*
X1102105D01*
G01X1095905Y78540D02*
Y81740D01*
G01X1102105Y78540D02*
X1095905D01*
G01X1102105Y81740D02*
Y78540D01*
G01X1095905Y81740D02*
X1102105D01*
G01X1095905Y82540D02*
Y85740D01*
G01X1102105Y82540D02*
X1095905D01*
G01X1102105Y85740D02*
Y82540D01*
G01X1106571Y70181D02*
X1112771D01*
G01X1106616Y70987D02*
Y74187D01*
G01X1112816Y70987D02*
X1106616D01*
G01Y74187D02*
X1112816D01*
G01X1106616Y74987D02*
Y78187D01*
G01X1112816Y74987D02*
X1106616D01*
G01Y78187D02*
X1112816D01*
G01X1106571Y82181D02*
X1112771D01*
G01X1106571Y78981D02*
Y82181D01*
G01X1112771Y78981D02*
X1106571D01*
G01X1091516Y93129D02*
Y86929D01*
G01X1095516D02*
X1092316D01*
G01X1095516Y93129D02*
Y86929D01*
G01X1092316Y93129D02*
X1095516D01*
G01X1092316Y86929D02*
Y93129D01*
G01X1095905Y85740D02*
X1102105D01*
G01X1099525Y86929D02*
X1096325D01*
G01X1099525Y93129D02*
Y86929D01*
G01X1096325Y93129D02*
X1099525D01*
G01X1096325Y86929D02*
Y93129D01*
G01X1091595Y96673D02*
Y102873D01*
G01X1094795Y96673D02*
X1091595D01*
G01X1094795Y102873D02*
Y96673D01*
G01X1095595D02*
Y102873D01*
G01X1098795Y96673D02*
X1095595D01*
G01X1098795Y102873D02*
Y96673D01*
G01X1101099Y95950D02*
Y102150D01*
G01X1104299Y95950D02*
X1101099D01*
G01X1104299Y102150D02*
Y95950D01*
G01X1105763Y95913D02*
Y111267D01*
G01X1118244Y95913D02*
X1105763D01*
G01X1091595Y102873D02*
X1094795D01*
G01X1095595D02*
X1098795D01*
G01X1101099Y102150D02*
X1104299D01*
G01X1101099Y109762D02*
X1104299D01*
G01X1101099Y103562D02*
Y109762D01*
G01X1104299Y103562D02*
X1101099D01*
G01X1104299Y109762D02*
Y103562D01*
G01X1105763Y111267D02*
X1118441D01*
G01X1097578Y144690D02*
Y154138D01*
G01X1108414Y144690D02*
X1097578D01*
G01X1095410Y149140D02*
Y145940D01*
G01X1100159Y139647D02*
Y142847D01*
G01X1106359Y139647D02*
X1100159D01*
G01X1106359Y142847D02*
Y139647D01*
G01X1100159Y142847D02*
X1106359D01*
G01X1093180Y139647D02*
Y142847D01*
G01X1099380Y139647D02*
X1093180D01*
G01X1099380Y142847D02*
Y139647D01*
G01X1093180Y142847D02*
X1099380D01*
G01X1098150Y155200D02*
X1097843Y155252D01*
X1097575Y155458D01*
X1097345Y155768D01*
X1097192Y156130D01*
X1097115Y156543D01*
Y156957D01*
X1097192Y157370D01*
X1097345Y157732D01*
X1097575Y158042D01*
X1097843Y158248D01*
X1098150Y158300D01*
X1098457Y158248D01*
X1098725Y158042D01*
X1098955Y157732D01*
X1099108Y157370D01*
X1099185Y156957D01*
Y156543D01*
X1099108Y156130D01*
X1098955Y155768D01*
X1098725Y155458D01*
X1098457Y155252D01*
X1098150Y155200D01*
G01X1098457Y156027D02*
X1098917Y155200D01*
G01X1100522Y157783D02*
X1100752Y158093D01*
X1101020Y158248D01*
X1101327Y158300D01*
X1101710Y158197D01*
X1101978Y157938D01*
X1102055Y157628D01*
X1102017Y157318D01*
X1101863Y157060D01*
X1101097Y156543D01*
X1100752Y156182D01*
X1100522Y155665D01*
X1100445Y155200D01*
X1102055D01*
G01X1103622Y157783D02*
X1103852Y158093D01*
X1104120Y158248D01*
X1104427Y158300D01*
X1104810Y158197D01*
X1105078Y157938D01*
X1105155Y157628D01*
X1105117Y157318D01*
X1104963Y157060D01*
X1104197Y156543D01*
X1103852Y156182D01*
X1103622Y155665D01*
X1103545Y155200D01*
X1105155D01*
G01X1106722Y156492D02*
X1106990Y156853D01*
X1107220Y157060D01*
X1107527Y157163D01*
X1107795Y157060D01*
X1107987Y156853D01*
X1108140Y156543D01*
X1108178Y156182D01*
X1108140Y155872D01*
X1107987Y155562D01*
X1107757Y155303D01*
X1107488Y155200D01*
X1107182Y155303D01*
X1106913Y155613D01*
X1106760Y156078D01*
X1106722Y156595D01*
X1106798Y157267D01*
X1106913Y157628D01*
X1107105Y157990D01*
X1107373Y158248D01*
X1107642Y158300D01*
X1107910Y158197D01*
X1108102Y157938D01*
G01X1104996Y154138D02*
X1108414D01*
G01X1102996Y152414D02*
X1104996Y154138D01*
G01X1100996D02*
X1102996Y152414D01*
G01X1097578Y154138D02*
X1100996D01*
G01X1095410Y153140D02*
Y149940D01*
G01X1100457Y175100D02*
Y172878D01*
X1100610Y172413D01*
X1100917Y172103D01*
X1101300Y172000D01*
X1101683Y172103D01*
X1101990Y172413D01*
X1102143Y172878D01*
Y175100D01*
G01X1104323Y172000D02*
X1104400Y172672D01*
X1104515Y173240D01*
X1104668Y173757D01*
X1104860Y174325D01*
X1105167Y175100D01*
X1103633D01*
G01X1106772Y174583D02*
X1107002Y174893D01*
X1107270Y175048D01*
X1107577Y175100D01*
X1107960Y174997D01*
X1108228Y174738D01*
X1108305Y174428D01*
X1108267Y174118D01*
X1108113Y173860D01*
X1107347Y173343D01*
X1107002Y172982D01*
X1106772Y172465D01*
X1106695Y172000D01*
X1108305D01*
G01X1100574Y176944D02*
Y178897D01*
G01X1102527Y176944D02*
X1100574D01*
G01X1095846Y171473D02*
X1092646D01*
G01X1095846Y177673D02*
Y171473D01*
G01X1092646Y177673D02*
X1095846D01*
G01X1092646Y171473D02*
Y177673D01*
G01X1091846D02*
Y171473D01*
G01X1098869Y170297D02*
Y167097D01*
G01X1092669Y170297D02*
X1098869D01*
G01X1092669Y167097D02*
Y170297D01*
G01X1098869Y167097D02*
X1092669D01*
G01X1100574Y188756D02*
X1102527D01*
G01X1100574Y186803D02*
Y188756D01*
G01X1096073Y182730D02*
X1092873D01*
G01X1096073Y188930D02*
Y182730D01*
G01X1092873Y188930D02*
X1096073D01*
G01X1092873Y182730D02*
Y188930D01*
G01X1099064Y193541D02*
Y190341D01*
G01X1092864Y193541D02*
X1099064D01*
G01X1092864Y190341D02*
Y193541D01*
G01X1099064Y190341D02*
X1092864D01*
G01X1098203Y201329D02*
Y204429D01*
X1099123D01*
X1099430Y204274D01*
X1099660Y203912D01*
X1099737Y203499D01*
X1099660Y203086D01*
X1099468Y202776D01*
X1099123Y202621D01*
X1098203D01*
G01X1101227Y204429D02*
Y202207D01*
X1101380Y201742D01*
X1101687Y201432D01*
X1102070Y201329D01*
X1102453Y201432D01*
X1102760Y201742D01*
X1102913Y202207D01*
Y204429D01*
G01X1105630Y201329D02*
Y204429D01*
X1104212Y202207D01*
X1106128D01*
G01X1108270Y204429D02*
X1107963Y204326D01*
X1107733Y204067D01*
X1107580Y203757D01*
X1107465Y203344D01*
X1107427Y202879D01*
X1107465Y202414D01*
X1107580Y202001D01*
X1107733Y201691D01*
X1107963Y201432D01*
X1108270Y201329D01*
X1108577Y201432D01*
X1108807Y201691D01*
X1108960Y202001D01*
X1109075Y202414D01*
X1109113Y202879D01*
X1109075Y203344D01*
X1108960Y203757D01*
X1108807Y204067D01*
X1108577Y204326D01*
X1108270Y204429D01*
G01X1113349Y220252D02*
Y208048D01*
X1098045D01*
Y220252D01*
X1113349D01*
G01X1103033Y232621D02*
Y226621D01*
G01X1095012Y215082D02*
X1091812D01*
G01X1095012Y221282D02*
Y215082D01*
G01X1091812Y221282D02*
X1095012D01*
G01X1091812Y215082D02*
Y221282D01*
G01X1101033Y225921D02*
Y222721D01*
G01X1094833Y225921D02*
X1101033D01*
G01X1094833Y222721D02*
Y225921D01*
G01X1101033Y222721D02*
X1094833D01*
G01X1091701Y258010D02*
Y264210D01*
G01X1094901Y258010D02*
X1091701D01*
G01X1094901Y264210D02*
Y258010D01*
G01X1099701D02*
Y264210D01*
G01X1102901Y258010D02*
X1099701D01*
G01X1102901Y264210D02*
Y258010D01*
G01X1098901D02*
X1095701D01*
G01X1098901Y264210D02*
Y258010D01*
G01X1095701D02*
Y264210D01*
G01X1091701D02*
X1094901D01*
G01X1099701D02*
X1102901D01*
G01X1107980Y273701D02*
X1104780D01*
G01D02*
Y279901D01*
G01X1095701Y264210D02*
X1098901D01*
G01X1102422Y279427D02*
Y267653D01*
G01X1092660D02*
Y279427D01*
G01X1102422Y267653D02*
X1092660D01*
G01X1093954Y289583D02*
Y283383D01*
G01X1104780Y279901D02*
X1107980D01*
G01X1097954Y283383D02*
X1094754D01*
G01X1097954Y289583D02*
Y283383D01*
G01X1094754Y289583D02*
X1097954D01*
G01X1094754Y283383D02*
Y289583D01*
G01X1098754Y283383D02*
Y289583D01*
X1101954D01*
Y283383D01*
X1098754D01*
G01X1106200Y282833D02*
X1103100D01*
Y283753D01*
X1103255Y284060D01*
X1103617Y284290D01*
X1104030Y284367D01*
X1104443Y284290D01*
X1104753Y284098D01*
X1104908Y283753D01*
Y282833D01*
G01X1103100Y285857D02*
X1105322D01*
X1105787Y286010D01*
X1106097Y286317D01*
X1106200Y286700D01*
X1106097Y287083D01*
X1105787Y287390D01*
X1105322Y287543D01*
X1103100D01*
G01X1106200Y289800D02*
X1103100D01*
X1103720Y289340D01*
G01X1106200D02*
Y290260D01*
G01Y292900D02*
X1103100D01*
X1103720Y292440D01*
G01X1106200D02*
Y293360D01*
G01X1103617Y295272D02*
X1103307Y295502D01*
X1103152Y295770D01*
X1103100Y296077D01*
X1103203Y296460D01*
X1103462Y296728D01*
X1103772Y296805D01*
X1104082Y296767D01*
X1104340Y296613D01*
X1104857Y295847D01*
X1105218Y295502D01*
X1105735Y295272D01*
X1106200Y295195D01*
Y296805D01*
G01X1092660Y279427D02*
X1102422D01*
G01X1098720Y651488D02*
Y659952D01*
G01X1111982Y651488D02*
X1098720D01*
G01X1098558Y664587D02*
Y662365D01*
X1098711Y661900D01*
X1099018Y661590D01*
X1099401Y661487D01*
X1099784Y661590D01*
X1100091Y661900D01*
X1100244Y662365D01*
Y664587D01*
G01X1101658Y662107D02*
X1101888Y661745D01*
X1102194Y661539D01*
X1102539Y661487D01*
X1102846Y661539D01*
X1103153Y661797D01*
X1103344Y662107D01*
X1103383Y662417D01*
X1103306Y662779D01*
X1103038Y663037D01*
X1102769Y663140D01*
X1102424D01*
G01X1102769D02*
X1102999Y663295D01*
X1103191Y663554D01*
X1103268Y663864D01*
X1103191Y664174D01*
X1102999Y664432D01*
X1102654Y664587D01*
X1102309Y664535D01*
X1101964Y664329D01*
G01X1105601Y664587D02*
X1105294Y664484D01*
X1105064Y664225D01*
X1104911Y663915D01*
X1104796Y663502D01*
X1104758Y663037D01*
X1104796Y662572D01*
X1104911Y662159D01*
X1105064Y661849D01*
X1105294Y661590D01*
X1105601Y661487D01*
X1105908Y661590D01*
X1106138Y661849D01*
X1106291Y662159D01*
X1106406Y662572D01*
X1106444Y663037D01*
X1106406Y663502D01*
X1106291Y663915D01*
X1106138Y664225D01*
X1105908Y664484D01*
X1105601Y664587D01*
G01X1103851Y659952D02*
X1105351Y658181D01*
G01X1098720Y659952D02*
X1103851D01*
G01X1106851D02*
X1111982D01*
G01X1105351Y658181D02*
X1106851Y659952D01*
G01X1105285Y669083D02*
Y685283D01*
G01X1118285Y669083D02*
X1105285D01*
G01Y685283D02*
X1118285D01*
G01X1100747Y1506183D02*
Y1509283D01*
G01X1102357D02*
Y1506183D01*
G01Y1507733D02*
X1100747D01*
G01X1104575Y1506183D02*
X1104652Y1506855D01*
X1104767Y1507423D01*
X1104920Y1507940D01*
X1105112Y1508508D01*
X1105419Y1509283D01*
X1103885D01*
G01X1107752Y1506183D02*
X1108020Y1506235D01*
X1108327Y1506390D01*
X1108519Y1506648D01*
X1108595Y1507010D01*
X1108519Y1507371D01*
X1108289Y1507681D01*
X1107944Y1507836D01*
X1107560D01*
X1107330Y1507940D01*
X1107139Y1508198D01*
X1107062Y1508560D01*
X1107177Y1508921D01*
X1107445Y1509180D01*
X1107752Y1509283D01*
X1108059Y1509180D01*
X1108327Y1508921D01*
X1108442Y1508560D01*
X1108365Y1508198D01*
X1108174Y1507940D01*
X1107944Y1507836D01*
X1107560D01*
X1107215Y1507681D01*
X1106985Y1507371D01*
X1106909Y1507010D01*
X1106985Y1506648D01*
X1107177Y1506390D01*
X1107484Y1506235D01*
X1107752Y1506183D01*
G01X1106800Y1524576D02*
X1103700D01*
Y1525496D01*
X1103855Y1525803D01*
X1104217Y1526033D01*
X1104630Y1526110D01*
X1105043Y1526033D01*
X1105353Y1525841D01*
X1105508Y1525496D01*
Y1524576D01*
G01X1103700Y1527600D02*
X1105922D01*
X1106387Y1527753D01*
X1106697Y1528060D01*
X1106800Y1528443D01*
X1106697Y1528826D01*
X1106387Y1529133D01*
X1105922Y1529286D01*
X1103700D01*
G01X1105508Y1530815D02*
X1105147Y1531083D01*
X1104940Y1531313D01*
X1104837Y1531620D01*
X1104940Y1531888D01*
X1105147Y1532080D01*
X1105457Y1532233D01*
X1105818Y1532271D01*
X1106128Y1532233D01*
X1106438Y1532080D01*
X1106697Y1531850D01*
X1106800Y1531581D01*
X1106697Y1531275D01*
X1106387Y1531006D01*
X1105922Y1530853D01*
X1105405Y1530815D01*
X1104733Y1530891D01*
X1104372Y1531006D01*
X1104010Y1531198D01*
X1103752Y1531466D01*
X1103700Y1531735D01*
X1103803Y1532003D01*
X1104062Y1532195D01*
G01X1105508Y1533915D02*
X1105147Y1534183D01*
X1104940Y1534413D01*
X1104837Y1534720D01*
X1104940Y1534988D01*
X1105147Y1535180D01*
X1105457Y1535333D01*
X1105818Y1535371D01*
X1106128Y1535333D01*
X1106438Y1535180D01*
X1106697Y1534950D01*
X1106800Y1534681D01*
X1106697Y1534375D01*
X1106387Y1534106D01*
X1105922Y1533953D01*
X1105405Y1533915D01*
X1104733Y1533991D01*
X1104372Y1534106D01*
X1104010Y1534298D01*
X1103752Y1534566D01*
X1103700Y1534835D01*
X1103803Y1535103D01*
X1104062Y1535295D01*
G01X1103700Y1537743D02*
X1103803Y1537436D01*
X1104062Y1537206D01*
X1104372Y1537053D01*
X1104785Y1536938D01*
X1105250Y1536900D01*
X1105715Y1536938D01*
X1106128Y1537053D01*
X1106438Y1537206D01*
X1106697Y1537436D01*
X1106800Y1537743D01*
X1106697Y1538050D01*
X1106438Y1538280D01*
X1106128Y1538433D01*
X1105715Y1538548D01*
X1105250Y1538586D01*
X1104785Y1538548D01*
X1104372Y1538433D01*
X1104062Y1538280D01*
X1103803Y1538050D01*
X1103700Y1537743D01*
G01X1106800Y1540843D02*
X1103700D01*
X1104320Y1540383D01*
G01X1106800D02*
Y1541303D01*
G01X1099976Y1552658D02*
X1096776D01*
G01X1099976Y1558858D02*
Y1552658D01*
G01X1096776Y1558858D02*
X1099976D01*
G01X1096776Y1552658D02*
Y1558858D01*
G01X1094976Y1552658D02*
X1091776D01*
G01X1094976Y1558858D02*
Y1552658D01*
G01X1091776Y1558858D02*
X1094976D01*
G01X1091776Y1552658D02*
Y1558858D01*
G01X1102910Y1565580D02*
X1105132D01*
X1105597Y1565733D01*
X1105907Y1566040D01*
X1106010Y1566423D01*
X1105907Y1566806D01*
X1105597Y1567113D01*
X1105132Y1567266D01*
X1102910D01*
G01X1106010Y1569523D02*
X1102910D01*
X1103530Y1569063D01*
G01X1106010D02*
Y1569983D01*
G01Y1573083D02*
X1102910D01*
X1105132Y1571665D01*
Y1573581D01*
G01X1104718Y1574995D02*
X1104357Y1575263D01*
X1104150Y1575493D01*
X1104047Y1575800D01*
X1104150Y1576068D01*
X1104357Y1576260D01*
X1104667Y1576413D01*
X1105028Y1576451D01*
X1105338Y1576413D01*
X1105648Y1576260D01*
X1105907Y1576030D01*
X1106010Y1575761D01*
X1105907Y1575455D01*
X1105597Y1575186D01*
X1105132Y1575033D01*
X1104615Y1574995D01*
X1103943Y1575071D01*
X1103582Y1575186D01*
X1103220Y1575378D01*
X1102962Y1575646D01*
X1102910Y1575915D01*
X1103013Y1576183D01*
X1103272Y1576375D01*
G01X1100664Y1577670D02*
Y1564070D01*
G01X1091864Y1569870D02*
Y1564070D01*
G01X1100664D02*
X1091864D01*
G01Y1577670D02*
Y1571870D01*
G01Y1577670D02*
X1100664D01*
G01X1093364Y1570870D02*
X1091864Y1569870D01*
G01Y1571870D02*
X1093364Y1570870D01*
G01X1094633Y1580908D02*
Y1587108D01*
G01X1097833Y1580908D02*
X1094633D01*
G01X1097833Y1587108D02*
Y1580908D01*
G01X1094633Y1587108D02*
X1097833D01*
G01X1101304Y1591681D02*
Y1597881D01*
G01X1104504Y1591681D02*
X1101304D01*
G01X1104504Y1597881D02*
Y1591681D01*
G01X1100504D02*
X1097304D01*
G01X1100504Y1597881D02*
Y1591681D01*
G01X1097304D02*
Y1597881D01*
G01X1092504D02*
Y1591681D01*
G01X1096504D02*
X1093304D01*
G01X1096504Y1597881D02*
Y1591681D01*
G01X1093304D02*
Y1597881D01*
G01X1105833Y1580908D02*
X1102633D01*
G01X1105833Y1587108D02*
Y1580908D01*
G01X1102633D02*
Y1587108D01*
G01D02*
X1105833D01*
G01X1101833Y1580908D02*
X1098633D01*
G01X1101833Y1587108D02*
Y1580908D01*
G01X1098633D02*
Y1587108D01*
G01D02*
X1101833D01*
G01X1092069Y1587085D02*
Y1580885D01*
G01X1104416Y1610949D02*
X1106638D01*
X1107103Y1611102D01*
X1107413Y1611409D01*
X1107516Y1611792D01*
X1107413Y1612175D01*
X1107103Y1612482D01*
X1106638Y1612635D01*
X1104416D01*
G01X1106896Y1614049D02*
X1107258Y1614279D01*
X1107464Y1614585D01*
X1107516Y1614930D01*
X1107464Y1615237D01*
X1107206Y1615544D01*
X1106896Y1615735D01*
X1106586Y1615774D01*
X1106224Y1615697D01*
X1105966Y1615429D01*
X1105863Y1615160D01*
Y1614815D01*
G01Y1615160D02*
X1105708Y1615390D01*
X1105449Y1615582D01*
X1105139Y1615659D01*
X1104829Y1615582D01*
X1104571Y1615390D01*
X1104416Y1615045D01*
X1104468Y1614700D01*
X1104674Y1614355D01*
G01X1104416Y1617992D02*
X1104519Y1617685D01*
X1104778Y1617455D01*
X1105088Y1617302D01*
X1105501Y1617187D01*
X1105966Y1617149D01*
X1106431Y1617187D01*
X1106844Y1617302D01*
X1107154Y1617455D01*
X1107413Y1617685D01*
X1107516Y1617992D01*
X1107413Y1618299D01*
X1107154Y1618529D01*
X1106844Y1618682D01*
X1106431Y1618797D01*
X1105966Y1618835D01*
X1105501Y1618797D01*
X1105088Y1618682D01*
X1104778Y1618529D01*
X1104519Y1618299D01*
X1104416Y1617992D01*
G01X1107516Y1621092D02*
X1107464Y1621360D01*
X1107309Y1621667D01*
X1107051Y1621859D01*
X1106689Y1621935D01*
X1106328Y1621859D01*
X1106018Y1621629D01*
X1105863Y1621284D01*
Y1620900D01*
X1105759Y1620670D01*
X1105501Y1620479D01*
X1105139Y1620402D01*
X1104778Y1620517D01*
X1104519Y1620785D01*
X1104416Y1621092D01*
X1104519Y1621399D01*
X1104778Y1621667D01*
X1105139Y1621782D01*
X1105501Y1621705D01*
X1105759Y1621514D01*
X1105863Y1621284D01*
Y1620900D01*
X1106018Y1620555D01*
X1106328Y1620325D01*
X1106689Y1620249D01*
X1107051Y1620325D01*
X1107309Y1620517D01*
X1107464Y1620824D01*
X1107516Y1621092D01*
G01X1101208Y1613232D02*
Y1610132D01*
G01X1106212Y1602077D02*
X1103012D01*
G01X1106212Y1608277D02*
Y1602077D01*
G01X1103012Y1608277D02*
X1106212D01*
G01X1103012Y1602077D02*
Y1608277D01*
G01X1101304Y1597881D02*
X1104504D01*
G01X1097304D02*
X1100504D01*
G01X1093304D02*
X1096504D01*
G01X1101208Y1613332D02*
X1100015Y1614232D01*
G01X1101208Y1618332D02*
Y1615232D01*
G01X1100015Y1614232D02*
X1101208Y1615232D01*
G01X1091874Y1636525D02*
X1095074D01*
G01X1091874Y1630325D02*
Y1636525D01*
G01X1095074Y1630325D02*
X1091874D01*
G01X1095074Y1636525D02*
Y1630325D01*
G01X1099874Y1636525D02*
X1103074D01*
G01X1099874Y1630325D02*
Y1636525D01*
G01X1103074Y1630325D02*
X1099874D01*
G01X1103074Y1636525D02*
Y1630325D01*
G01X1099074D02*
X1095874D01*
G01X1099074Y1636525D02*
Y1630325D01*
G01X1095874Y1636525D02*
X1099074D01*
G01X1095874Y1630325D02*
Y1636525D01*
G01X1103874D02*
X1107074D01*
G01Y1630325D02*
X1103874D01*
G01X1107074Y1636525D02*
Y1630325D01*
G01X1103874D02*
Y1636525D01*
G01X1127403Y67523D02*
X1115199D01*
G01D02*
Y70183D01*
G01X1122096Y59613D02*
Y56413D01*
G01X1115896Y59613D02*
X1122096D01*
G01X1115896Y56413D02*
Y59613D01*
G01X1122096Y56413D02*
X1115896D01*
G01X1112771Y70181D02*
Y66981D01*
G01X1115199Y79047D02*
X1127403D01*
G01X1115199Y76285D02*
Y79047D01*
G01X1118301Y73285D02*
X1115199Y76285D01*
G01Y70183D02*
X1118301Y73285D01*
G01X1112816Y74187D02*
Y70987D01*
G01Y78187D02*
Y74987D01*
G01X1112771Y82181D02*
Y78981D01*
G01X1113606Y93476D02*
X1116806D01*
G01X1113606Y87276D02*
Y93476D01*
G01X1116806Y87276D02*
X1113606D01*
G01X1116806Y93476D02*
Y87276D01*
G01X1126255Y87204D02*
X1123055D01*
G01Y93404D02*
X1126255D01*
G01X1123055Y87204D02*
Y93404D01*
G01X1122306Y87276D02*
X1119106D01*
G01X1122306Y93476D02*
Y87276D01*
G01X1119106Y93476D02*
X1122306D01*
G01X1119106Y87276D02*
Y93476D01*
G01X1119500Y98907D02*
X1121722D01*
X1122187Y99060D01*
X1122497Y99367D01*
X1122600Y99750D01*
X1122497Y100133D01*
X1122187Y100440D01*
X1121722Y100593D01*
X1119500D01*
G01X1122600Y103310D02*
X1119500D01*
X1121722Y101892D01*
Y103808D01*
G01X1122600Y105950D02*
X1119500D01*
X1120120Y105490D01*
G01X1122600D02*
Y106410D01*
G01X1121980Y108207D02*
X1122342Y108437D01*
X1122548Y108743D01*
X1122600Y109088D01*
X1122548Y109395D01*
X1122290Y109702D01*
X1121980Y109893D01*
X1121670Y109932D01*
X1121308Y109855D01*
X1121050Y109587D01*
X1120947Y109318D01*
Y108973D01*
G01Y109318D02*
X1120792Y109548D01*
X1120533Y109740D01*
X1120223Y109817D01*
X1119913Y109740D01*
X1119655Y109548D01*
X1119500Y109203D01*
X1119552Y108858D01*
X1119758Y108513D01*
G01X1118441Y111267D02*
Y95913D01*
G01X1119597Y111951D02*
Y118151D01*
G01X1122797Y111951D02*
X1119597D01*
G01X1122797Y118151D02*
Y111951D01*
G01X1118314Y116088D02*
Y112888D01*
G01X1112114Y116088D02*
X1118314D01*
G01X1112114Y112888D02*
Y116088D01*
G01X1118314Y112888D02*
X1112114D01*
G01X1119597Y118151D02*
X1122797D01*
G01X1117673Y119346D02*
X1114573D01*
Y120266D01*
X1114728Y120573D01*
X1115090Y120803D01*
X1115503Y120880D01*
X1115916Y120803D01*
X1116226Y120611D01*
X1116381Y120266D01*
Y119346D01*
G01X1114573Y122370D02*
X1116795D01*
X1117260Y122523D01*
X1117570Y122830D01*
X1117673Y123213D01*
X1117570Y123596D01*
X1117260Y123903D01*
X1116795Y124056D01*
X1114573D01*
G01X1117673Y126313D02*
X1114573D01*
X1115193Y125853D01*
G01X1117673D02*
Y126773D01*
G01X1115090Y128685D02*
X1114780Y128915D01*
X1114625Y129183D01*
X1114573Y129490D01*
X1114676Y129873D01*
X1114935Y130141D01*
X1115245Y130218D01*
X1115555Y130180D01*
X1115813Y130026D01*
X1116330Y129260D01*
X1116691Y128915D01*
X1117208Y128685D01*
X1117673Y128608D01*
Y130218D01*
G01X1117311Y131861D02*
X1117570Y132130D01*
X1117673Y132436D01*
X1117570Y132743D01*
X1117260Y133011D01*
X1116795Y133203D01*
X1116330Y133280D01*
X1115761D01*
X1115296Y133203D01*
X1114883Y133011D01*
X1114676Y132781D01*
X1114573Y132513D01*
X1114676Y132206D01*
X1114883Y131976D01*
X1115193Y131823D01*
X1115606Y131746D01*
X1115968Y131823D01*
X1116330Y132015D01*
X1116536Y132245D01*
X1116588Y132513D01*
X1116485Y132820D01*
X1116226Y133050D01*
X1115761Y133280D01*
G01X1108414Y154138D02*
Y144690D01*
G01X1116021Y151368D02*
Y148168D01*
G01X1109821D02*
Y151368D01*
G01X1116021Y148168D02*
X1109821D01*
G01X1124931Y146229D02*
X1121731D01*
G01D02*
Y152429D01*
G01X1109821Y144168D02*
Y147368D01*
G01X1116021Y144168D02*
X1109821D01*
G01X1116021Y147368D02*
Y144168D01*
G01X1109821Y147368D02*
X1116021D01*
G01X1116900Y135707D02*
X1119122D01*
X1119587Y135860D01*
X1119897Y136167D01*
X1120000Y136550D01*
X1119897Y136933D01*
X1119587Y137240D01*
X1119122Y137393D01*
X1116900D01*
G01X1119380Y138807D02*
X1119742Y139037D01*
X1119948Y139343D01*
X1120000Y139688D01*
X1119948Y139995D01*
X1119690Y140302D01*
X1119380Y140493D01*
X1119070Y140532D01*
X1118708Y140455D01*
X1118450Y140187D01*
X1118347Y139918D01*
Y139573D01*
G01Y139918D02*
X1118192Y140148D01*
X1117933Y140340D01*
X1117623Y140417D01*
X1117313Y140340D01*
X1117055Y140148D01*
X1116900Y139803D01*
X1116952Y139458D01*
X1117158Y139113D01*
G01X1119638Y142098D02*
X1119897Y142367D01*
X1120000Y142673D01*
X1119897Y142980D01*
X1119587Y143248D01*
X1119122Y143440D01*
X1118657Y143517D01*
X1118088D01*
X1117623Y143440D01*
X1117210Y143248D01*
X1117003Y143018D01*
X1116900Y142750D01*
X1117003Y142443D01*
X1117210Y142213D01*
X1117520Y142060D01*
X1117933Y141983D01*
X1118295Y142060D01*
X1118657Y142252D01*
X1118863Y142482D01*
X1118915Y142750D01*
X1118812Y143057D01*
X1118553Y143287D01*
X1118088Y143517D01*
G01X1119380Y145007D02*
X1119742Y145237D01*
X1119948Y145543D01*
X1120000Y145888D01*
X1119948Y146195D01*
X1119690Y146502D01*
X1119380Y146693D01*
X1119070Y146732D01*
X1118708Y146655D01*
X1118450Y146387D01*
X1118347Y146118D01*
Y145773D01*
G01Y146118D02*
X1118192Y146348D01*
X1117933Y146540D01*
X1117623Y146617D01*
X1117313Y146540D01*
X1117055Y146348D01*
X1116900Y146003D01*
X1116952Y145658D01*
X1117158Y145313D01*
G01X1123421Y144395D02*
Y135095D01*
G01X1134021Y144395D02*
X1123421D01*
G01Y134995D02*
X1134021D01*
G01X1109821Y151368D02*
X1116021D01*
G01X1121731Y152429D02*
X1124931D01*
G01X1121731Y159540D02*
X1124931D01*
G01X1121731Y153340D02*
Y159540D01*
G01X1124931Y153340D02*
X1121731D01*
G01X1112386Y178897D02*
Y176944D01*
G01D02*
X1110433D01*
G01X1116757Y179065D02*
Y182265D01*
G01X1122957Y179065D02*
X1116757D01*
G01X1122957Y182265D02*
Y179065D01*
G01X1116757Y171065D02*
Y174265D01*
G01X1122957Y171065D02*
X1116757D01*
G01X1122957Y174265D02*
Y171065D01*
G01X1116757Y174265D02*
X1122957D01*
G01X1114578Y170313D02*
Y167113D01*
G01X1108378Y170313D02*
X1114578D01*
G01X1108378Y167113D02*
Y170313D01*
G01X1114578Y167113D02*
X1108378D01*
G01X1116757Y175065D02*
Y178265D01*
G01X1122957Y175065D02*
X1116757D01*
G01X1122957Y178265D02*
Y175065D01*
G01X1116757Y178265D02*
X1122957D01*
G01X1116757Y167065D02*
Y170265D01*
G01X1122957Y167065D02*
X1116757D01*
G01X1122957Y170265D02*
Y167065D01*
G01X1116757Y170265D02*
X1122957D01*
G01X1112386Y188756D02*
Y186803D01*
G01X1110433Y188756D02*
X1112386D01*
G01X1124525Y189435D02*
X1126765D01*
G01X1125552Y191060D02*
Y187810D01*
G01X1116757Y182265D02*
X1122957D01*
G01X1116757Y187065D02*
Y190265D01*
G01X1122957Y187065D02*
X1116757D01*
G01X1122957Y190265D02*
Y187065D01*
G01X1116757Y190265D02*
X1122957D01*
G01Y194265D02*
Y191065D01*
G01X1116757Y194265D02*
X1122957D01*
G01X1116757Y191065D02*
Y194265D01*
G01X1122957Y191065D02*
X1116757D01*
G01X1122957Y198265D02*
Y195065D01*
G01X1116757D02*
Y198265D01*
G01X1122957Y195065D02*
X1116757D01*
G01Y183065D02*
Y186265D01*
G01X1122957Y183065D02*
X1116757D01*
G01X1122957Y186265D02*
Y183065D01*
G01X1116757Y186265D02*
X1122957D01*
G01X1116852Y202464D02*
X1123052D01*
Y199264D01*
X1116852D01*
Y202464D01*
G01X1116757Y198265D02*
X1122957D01*
G01X1116852Y207264D02*
Y210464D01*
G01X1123052Y207264D02*
X1116852D01*
G01X1123052Y210464D02*
Y207264D01*
G01X1116852Y210464D02*
X1123052D01*
G01Y206464D02*
Y203264D01*
G01X1116852Y206464D02*
X1123052D01*
G01X1116852Y203264D02*
Y206464D01*
G01X1123052Y203264D02*
X1116852D01*
G01Y214464D02*
X1123052D01*
Y211264D01*
X1116852D01*
Y214464D01*
G01Y215264D02*
Y218464D01*
G01X1123052Y215264D02*
X1116852D01*
G01X1123052Y218464D02*
Y215264D01*
G01X1116852Y218464D02*
X1123052D01*
G01X1116852Y220264D02*
Y223464D01*
G01X1123052Y220264D02*
X1116852D01*
G01X1123052Y223464D02*
Y220264D01*
G01X1116852Y223464D02*
X1123052D01*
G01X1116849Y227319D02*
X1123049D01*
Y224119D01*
X1116849D01*
Y227319D01*
G01X1114568Y234813D02*
Y250325D01*
G01X1109612Y264635D02*
X1125124D01*
G01X1109612Y295727D02*
Y264635D01*
G01X1107980Y279901D02*
Y273701D01*
G01X1125124Y295727D02*
X1109612D01*
G01X1122100Y330600D02*
Y327400D01*
G01X1115900D02*
Y330600D01*
G01X1122100Y327400D02*
X1115900D01*
G01Y330600D02*
X1122100D01*
G01Y335600D02*
Y332400D01*
G01X1115900Y335600D02*
X1122100D01*
G01X1115900Y332400D02*
Y335600D01*
G01X1122100Y332400D02*
X1115900D01*
G01X1122100Y340600D02*
Y337400D01*
G01X1115900Y340600D02*
X1122100D01*
G01X1115900Y337400D02*
Y340600D01*
G01X1122100Y337400D02*
X1115900D01*
G01X1118218Y366063D02*
Y391464D01*
G01X1110722Y366063D02*
X1118218D01*
G01Y408102D02*
Y412746D01*
G01Y401039D02*
Y405714D01*
G01Y393802D02*
Y398671D01*
G01Y422281D02*
Y426977D01*
G01Y415104D02*
Y419739D01*
G01Y436398D02*
Y441124D01*
G01Y429376D02*
Y433999D01*
G01Y451956D02*
Y443420D01*
G01Y472291D02*
Y476944D01*
G01Y459056D02*
Y469892D01*
G01Y486417D02*
Y491184D01*
G01Y479302D02*
Y484110D01*
G01Y493480D02*
Y514036D01*
G01Y516322D02*
Y521079D01*
G01Y580396D02*
Y537862D01*
G01Y530592D02*
Y535257D01*
G01Y523437D02*
Y528152D01*
G01Y587506D02*
Y639449D01*
G01X1111982Y659952D02*
Y651488D01*
G01X1116751Y651636D02*
X1113551D01*
G01X1116751Y657836D02*
Y651636D01*
G01X1113551D02*
Y657836D01*
G01X1120751Y651636D02*
X1117551D01*
G01X1120751Y657836D02*
Y651636D01*
G01X1117551D02*
Y657836D01*
G01X1118218Y639449D02*
X1110772D01*
G01X1118285Y675683D02*
Y669083D01*
G01X1117514Y667875D02*
Y664675D01*
G01X1111314Y667875D02*
X1117514D01*
G01X1111314Y664675D02*
Y667875D01*
G01X1117514Y664675D02*
X1111314D01*
G01X1113529Y658802D02*
Y662002D01*
G01X1119729Y658802D02*
X1113529D01*
G01X1119729Y662002D02*
Y658802D01*
G01X1113529Y662002D02*
X1119729D01*
G01X1113551Y657836D02*
X1116751D01*
G01X1117551D02*
X1120751D01*
G01X1119700Y670707D02*
X1121922D01*
X1122387Y670860D01*
X1122697Y671167D01*
X1122800Y671550D01*
X1122697Y671933D01*
X1122387Y672240D01*
X1121922Y672393D01*
X1119700D01*
G01X1122180Y673807D02*
X1122542Y674037D01*
X1122748Y674343D01*
X1122800Y674688D01*
X1122748Y674995D01*
X1122490Y675302D01*
X1122180Y675493D01*
X1121870Y675532D01*
X1121508Y675455D01*
X1121250Y675187D01*
X1121147Y674918D01*
Y674573D01*
G01Y674918D02*
X1120992Y675148D01*
X1120733Y675340D01*
X1120423Y675417D01*
X1120113Y675340D01*
X1119855Y675148D01*
X1119700Y674803D01*
X1119752Y674458D01*
X1119958Y674113D01*
G01X1122800Y677750D02*
X1119700D01*
X1120320Y677290D01*
G01X1122800D02*
Y678210D01*
G01X1115785Y677183D02*
X1118285Y675683D01*
G01Y678683D02*
X1115785Y677183D01*
G01X1118285Y685283D02*
Y678683D01*
G01X1125000Y696750D02*
X1124948Y696443D01*
X1124742Y696175D01*
X1124432Y695945D01*
X1124070Y695792D01*
X1123657Y695715D01*
X1123243D01*
X1122830Y695792D01*
X1122468Y695945D01*
X1122158Y696175D01*
X1121952Y696443D01*
X1121900Y696750D01*
X1121952Y697057D01*
X1122158Y697325D01*
X1122468Y697555D01*
X1122830Y697708D01*
X1123243Y697785D01*
X1123657D01*
X1124070Y697708D01*
X1124432Y697555D01*
X1124742Y697325D01*
X1124948Y697057D01*
X1125000Y696750D01*
G01X1124173Y697057D02*
X1125000Y697517D01*
G01X1124535Y699007D02*
X1124793Y699237D01*
X1124948Y699505D01*
X1125000Y699850D01*
X1124897Y700195D01*
X1124690Y700463D01*
X1124328Y700655D01*
X1123915Y700693D01*
X1123502Y700617D01*
X1123243Y700425D01*
X1123037Y700157D01*
X1122985Y699888D01*
X1123037Y699620D01*
X1123243Y699275D01*
X1121900Y699390D01*
Y700425D01*
G01X1120627Y696206D02*
X1118296Y698537D01*
G01X1120627Y693097D02*
Y696206D01*
G01X1111965Y693097D02*
X1120627D01*
G01X1111965Y703977D02*
Y693097D01*
G01X1120627Y700868D02*
Y703977D01*
G01X1118296Y698537D02*
X1120627Y700868D01*
G01X1117550Y688094D02*
Y691294D01*
G01X1123750Y688094D02*
X1117550D01*
G01X1123750Y691294D02*
Y688094D01*
G01X1117550Y691294D02*
X1123750D01*
G01X1120627Y703977D02*
X1111965D01*
G01X1119630Y711729D02*
Y708529D01*
G01X1113430Y711729D02*
X1119630D01*
G01X1113430Y708529D02*
Y711729D01*
G01X1119630Y708529D02*
X1113430D01*
G01X1115118Y1425158D02*
Y1689331D01*
G01X1228110Y1425158D02*
X1115118D01*
G01Y1689331D02*
X1228110D01*
G01X1127403Y79047D02*
Y67523D01*
G01X1128700Y68707D02*
X1130922D01*
X1131387Y68860D01*
X1131697Y69167D01*
X1131800Y69550D01*
X1131697Y69933D01*
X1131387Y70240D01*
X1130922Y70393D01*
X1128700D01*
G01X1131800Y72650D02*
X1128700D01*
X1129320Y72190D01*
G01X1131800D02*
Y73110D01*
G01X1131180Y74907D02*
X1131542Y75137D01*
X1131748Y75443D01*
X1131800Y75788D01*
X1131748Y76095D01*
X1131490Y76402D01*
X1131180Y76593D01*
X1130870Y76632D01*
X1130508Y76555D01*
X1130250Y76287D01*
X1130147Y76018D01*
Y75673D01*
G01Y76018D02*
X1129992Y76248D01*
X1129733Y76440D01*
X1129423Y76517D01*
X1129113Y76440D01*
X1128855Y76248D01*
X1128700Y75903D01*
X1128752Y75558D01*
X1128958Y75213D01*
G01X1131335Y78007D02*
X1131593Y78237D01*
X1131748Y78505D01*
X1131800Y78850D01*
X1131697Y79195D01*
X1131490Y79463D01*
X1131128Y79655D01*
X1130715Y79693D01*
X1130302Y79617D01*
X1130043Y79425D01*
X1129837Y79157D01*
X1129785Y78888D01*
X1129837Y78620D01*
X1130043Y78275D01*
X1128700Y78390D01*
Y79425D01*
G01X1130162Y87299D02*
X1126962D01*
G01X1130162Y93499D02*
Y87299D01*
G01X1126962Y93499D02*
X1130162D01*
G01X1126962Y87299D02*
Y93499D01*
G01X1126255Y93404D02*
Y87204D01*
G01X1137134Y110172D02*
Y122172D01*
G01X1143134Y110172D02*
X1137134D01*
G01X1134517Y109424D02*
X1137717D01*
G01X1134517Y103224D02*
Y109424D01*
G01X1137717Y103224D02*
X1134517D01*
G01X1137717Y109424D02*
Y103224D01*
G01X1130517Y109424D02*
X1133717D01*
G01X1130517Y103224D02*
Y109424D01*
G01X1133717Y103224D02*
X1130517D01*
G01X1133717Y109424D02*
Y103224D01*
G01X1126517Y109424D02*
X1129717D01*
G01X1126517Y103224D02*
Y109424D01*
G01X1129717Y103224D02*
X1126517D01*
G01X1129717Y109424D02*
Y103224D01*
G01X1124971Y111734D02*
Y123508D01*
G01X1134733Y111734D02*
X1124971D01*
G01X1134733Y123508D02*
Y111734D01*
G01X1137134Y122172D02*
X1143134D01*
G01X1135742Y126223D02*
X1132542D01*
G01X1135742Y132423D02*
Y126223D01*
G01X1132542Y132423D02*
X1135742D01*
G01X1132542Y126223D02*
Y132423D01*
G01X1127742Y126223D02*
X1124542D01*
G01X1127742Y132423D02*
Y126223D01*
G01X1124542Y132423D02*
X1127742D01*
G01X1124542Y126223D02*
Y132423D01*
G01X1128542D02*
X1131742D01*
G01X1128542Y126223D02*
Y132423D01*
G01X1131742Y126223D02*
X1128542D01*
G01X1131742Y132423D02*
Y126223D01*
G01X1139796Y126228D02*
X1136596D01*
G01X1139796Y132428D02*
Y126228D01*
G01X1136596Y132428D02*
X1139796D01*
G01X1136596Y126228D02*
Y132428D01*
G01X1124971Y123508D02*
X1134733D01*
G01X1139975Y141337D02*
X1136775D01*
G01X1139975Y147537D02*
Y141337D01*
G01X1136775Y147537D02*
X1139975D01*
G01X1136775Y141337D02*
Y147537D01*
G01X1136640Y133238D02*
Y136438D01*
G01X1142840Y133238D02*
X1136640D01*
G01Y136438D02*
X1142840D01*
G01X1136640Y137238D02*
Y140438D01*
G01X1142840Y137238D02*
X1136640D01*
G01Y140438D02*
X1142840D01*
G01X1124931Y152429D02*
Y146229D01*
G01X1134021Y134995D02*
Y144395D01*
G01X1124931Y159540D02*
Y153340D01*
G01X1131644Y149950D02*
Y165304D01*
G01X1144322Y149950D02*
X1131644D01*
G01X1131841Y165304D02*
X1144322D01*
G01X1128583Y179600D02*
Y182700D01*
X1129503D01*
X1129810Y182545D01*
X1130040Y182183D01*
X1130117Y181770D01*
X1130040Y181357D01*
X1129848Y181047D01*
X1129503Y180892D01*
X1128583D01*
G01X1131607Y179600D02*
Y182700D01*
X1132373D01*
X1132680Y182545D01*
X1132910Y182338D01*
X1133102Y182028D01*
X1133255Y181667D01*
X1133293Y181150D01*
X1133255Y180633D01*
X1133102Y180272D01*
X1132910Y179962D01*
X1132680Y179755D01*
X1132373Y179600D01*
X1131607D01*
G01X1135473D02*
X1135550Y180272D01*
X1135665Y180840D01*
X1135818Y181357D01*
X1136010Y181925D01*
X1136317Y182700D01*
X1134783D01*
G01X1137922Y182183D02*
X1138152Y182493D01*
X1138420Y182648D01*
X1138727Y182700D01*
X1139110Y182597D01*
X1139378Y182338D01*
X1139455Y182028D01*
X1139417Y181718D01*
X1139263Y181460D01*
X1138497Y180943D01*
X1138152Y180582D01*
X1137922Y180065D01*
X1137845Y179600D01*
X1139455D01*
G01X1128166Y195583D02*
X1157725D01*
G01X1128166Y184087D02*
Y195583D01*
G01X1157725Y184087D02*
X1128166D01*
G01X1147142Y197645D02*
X1135142D01*
G01D02*
Y203645D01*
G01D02*
X1147142D01*
G01X1128319Y204506D02*
Y216506D01*
G01X1134319Y204506D02*
X1128319D01*
G01X1134319Y216506D02*
Y204506D01*
G01X1135119Y208306D02*
Y214506D01*
G01X1138319Y208306D02*
X1135119D01*
G01X1138319Y214506D02*
Y208306D01*
G01X1138895Y208464D02*
X1145095D01*
G01X1138895Y205264D02*
Y208464D01*
G01X1145095Y205264D02*
X1138895D01*
G01X1139925Y226801D02*
X1152129D01*
Y211497D01*
X1139925D01*
Y226801D01*
G01X1128319Y216506D02*
X1134319D01*
G01X1135119Y214506D02*
X1138319D01*
G01X1135485Y245521D02*
Y254969D01*
G01X1146321Y245521D02*
X1135485D01*
G01X1139061Y231334D02*
X1135861D01*
G01X1139061Y237534D02*
Y231334D01*
G01X1135861Y237534D02*
X1139061D01*
G01X1135861Y231334D02*
Y237534D01*
G01X1137287Y243678D02*
Y240478D01*
G01X1131087Y243678D02*
X1137287D01*
G01X1131087Y240478D02*
Y243678D01*
G01X1137287Y240478D02*
X1131087D01*
G01X1138066Y243678D02*
X1144266D01*
G01X1138066Y240478D02*
Y243678D01*
G01X1144266Y240478D02*
X1138066D01*
G01X1127117Y246771D02*
Y249971D01*
G01X1133317Y246771D02*
X1127117D01*
G01X1133317Y249971D02*
Y246771D01*
G01X1136350Y256000D02*
X1136043Y256052D01*
X1135775Y256258D01*
X1135545Y256568D01*
X1135392Y256930D01*
X1135315Y257343D01*
Y257757D01*
X1135392Y258170D01*
X1135545Y258532D01*
X1135775Y258842D01*
X1136043Y259048D01*
X1136350Y259100D01*
X1136657Y259048D01*
X1136925Y258842D01*
X1137155Y258532D01*
X1137308Y258170D01*
X1137385Y257757D01*
Y257343D01*
X1137308Y256930D01*
X1137155Y256568D01*
X1136925Y256258D01*
X1136657Y256052D01*
X1136350Y256000D01*
G01X1136657Y256827D02*
X1137117Y256000D01*
G01X1138722Y258583D02*
X1138952Y258893D01*
X1139220Y259048D01*
X1139527Y259100D01*
X1139910Y258997D01*
X1140178Y258738D01*
X1140255Y258428D01*
X1140217Y258118D01*
X1140063Y257860D01*
X1139297Y257343D01*
X1138952Y256982D01*
X1138722Y256465D01*
X1138645Y256000D01*
X1140255D01*
G01X1142550Y259100D02*
X1142243Y258997D01*
X1142013Y258738D01*
X1141860Y258428D01*
X1141745Y258015D01*
X1141707Y257550D01*
X1141745Y257085D01*
X1141860Y256672D01*
X1142013Y256362D01*
X1142243Y256103D01*
X1142550Y256000D01*
X1142857Y256103D01*
X1143087Y256362D01*
X1143240Y256672D01*
X1143355Y257085D01*
X1143393Y257550D01*
X1143355Y258015D01*
X1143240Y258428D01*
X1143087Y258738D01*
X1142857Y258997D01*
X1142550Y259100D01*
G01X1144922Y257292D02*
X1145190Y257653D01*
X1145420Y257860D01*
X1145727Y257963D01*
X1145995Y257860D01*
X1146187Y257653D01*
X1146340Y257343D01*
X1146378Y256982D01*
X1146340Y256672D01*
X1146187Y256362D01*
X1145957Y256103D01*
X1145688Y256000D01*
X1145382Y256103D01*
X1145113Y256413D01*
X1144960Y256878D01*
X1144922Y257395D01*
X1144998Y258067D01*
X1145113Y258428D01*
X1145305Y258790D01*
X1145573Y259048D01*
X1145842Y259100D01*
X1146110Y258997D01*
X1146302Y258738D01*
G01X1138903Y254969D02*
X1140903Y253245D01*
G01X1135485Y254969D02*
X1138903D01*
G01X1127117Y249971D02*
X1133317D01*
G01Y253971D02*
Y250771D01*
G01X1127117Y253971D02*
X1133317D01*
G01X1127117Y250771D02*
Y253971D01*
G01X1133317Y250771D02*
X1127117D01*
G01X1129600Y264783D02*
X1126500D01*
Y265703D01*
X1126655Y266010D01*
X1127017Y266240D01*
X1127430Y266317D01*
X1127843Y266240D01*
X1128153Y266048D01*
X1128308Y265703D01*
Y264783D01*
G01X1129600Y267807D02*
X1126500D01*
Y268573D01*
X1126655Y268880D01*
X1126862Y269110D01*
X1127172Y269302D01*
X1127533Y269455D01*
X1128050Y269493D01*
X1128567Y269455D01*
X1128928Y269302D01*
X1129238Y269110D01*
X1129445Y268880D01*
X1129600Y268573D01*
Y267807D01*
G01Y271750D02*
X1126500D01*
X1127120Y271290D01*
G01X1129600D02*
Y272210D01*
G01Y274850D02*
X1126500D01*
X1127120Y274390D01*
G01X1129600D02*
Y275310D01*
G01X1127017Y277222D02*
X1126707Y277452D01*
X1126552Y277720D01*
X1126500Y278027D01*
X1126603Y278410D01*
X1126862Y278678D01*
X1127172Y278755D01*
X1127482Y278717D01*
X1127740Y278563D01*
X1128257Y277797D01*
X1128618Y277452D01*
X1129135Y277222D01*
X1129600Y277145D01*
Y278755D01*
G01X1125124Y264635D02*
Y295727D01*
G01X1130600Y330600D02*
Y327400D01*
G01X1124400D02*
Y330600D01*
G01X1130600Y327400D02*
X1124400D01*
G01Y330600D02*
X1130600D01*
G01Y335600D02*
Y332400D01*
G01X1124400Y335600D02*
X1130600D01*
G01X1124400Y332400D02*
Y335600D01*
G01X1130600Y332400D02*
X1124400D01*
G01X1130600Y340600D02*
Y337400D01*
G01X1124400Y340600D02*
X1130600D01*
G01X1124400Y337400D02*
Y340600D01*
G01X1130600Y337400D02*
X1124400D01*
G01X1137073Y460400D02*
Y457200D01*
G01X1130873D02*
Y460400D01*
G01X1137073Y457200D02*
X1130873D01*
G01Y460400D02*
X1137073D01*
G01X1130873Y461200D02*
Y464400D01*
G01X1137073Y461200D02*
X1130873D01*
G01X1137073Y464400D02*
Y461200D01*
G01X1130873Y464400D02*
X1137073D01*
G01X1131073Y548200D02*
Y551400D01*
G01X1137273Y548200D02*
X1131073D01*
G01X1137273Y551400D02*
Y548200D01*
G01X1131073Y551400D02*
X1137273D01*
G01Y547400D02*
Y544200D01*
G01X1131073Y547400D02*
X1137273D01*
G01X1131073Y544200D02*
Y547400D01*
G01X1137273Y544200D02*
X1131073D01*
G01X1139673Y548100D02*
Y551300D01*
G01X1145873Y548100D02*
X1139673D01*
G01Y551300D02*
X1145873D01*
G01X1139673Y555300D02*
X1145873D01*
G01X1139673Y552100D02*
Y555300D01*
G01X1145873Y552100D02*
X1139673D01*
G01Y559300D02*
X1145873D01*
G01X1139673Y556100D02*
Y559300D01*
G01X1145873Y556100D02*
X1139673D01*
G01X1137273Y560400D02*
Y557200D01*
G01X1131073Y560400D02*
X1137273D01*
G01X1131073Y557200D02*
Y560400D01*
G01X1137273Y557200D02*
X1131073D01*
G01X1137273Y564400D02*
Y561200D01*
G01X1131073Y564400D02*
X1137273D01*
G01X1131073Y561200D02*
Y564400D01*
G01X1137273Y561200D02*
X1131073D01*
G01X1131473Y619800D02*
Y623000D01*
G01X1137673Y619800D02*
X1131473D01*
G01X1137673Y623000D02*
Y619800D01*
G01X1131473Y623000D02*
X1137673D01*
G01X1131473Y623800D02*
Y627000D01*
G01X1137673Y623800D02*
X1131473D01*
G01X1137673Y627000D02*
Y623800D01*
G01X1131473Y627000D02*
X1137673D01*
G01X1132348Y790585D02*
Y796585D01*
G01X1126348Y790585D02*
X1132348D01*
G01Y837829D02*
X1126348D01*
G01X1132348Y831829D02*
Y837829D01*
G01X1136820Y1021330D02*
Y1029330D01*
X1139220D01*
X1140020Y1028930D01*
X1140620Y1027997D01*
X1140820Y1026930D01*
X1140620Y1025863D01*
X1140120Y1025063D01*
X1139220Y1024663D01*
X1136820D01*
G01X1148820Y1021330D02*
X1144820D01*
Y1029330D01*
X1148820D01*
G01X1147220Y1025463D02*
X1144820D01*
G01X1152720Y1021330D02*
X1156920Y1029330D01*
G01X1152720D02*
X1156920Y1021330D01*
G01X1160920Y1027997D02*
X1161520Y1028797D01*
X1162220Y1029197D01*
X1163020Y1029330D01*
X1164020Y1029063D01*
X1164720Y1028397D01*
X1164920Y1027597D01*
X1164820Y1026796D01*
X1164420Y1026130D01*
X1162420Y1024797D01*
X1161520Y1023863D01*
X1160920Y1022530D01*
X1160720Y1021330D01*
X1164920D01*
G01X1130971Y1419282D02*
X1132838D01*
Y1417032D01*
X1132278Y1416282D01*
X1131624Y1415782D01*
X1130691Y1415532D01*
X1129758Y1415782D01*
X1129104Y1416282D01*
X1128544Y1417032D01*
X1128171Y1417907D01*
X1127984Y1418907D01*
Y1419782D01*
X1128171Y1420532D01*
X1128544Y1421407D01*
X1129104Y1422157D01*
X1129664Y1422657D01*
X1130411Y1423032D01*
X1131064D01*
X1131811Y1422782D01*
X1132371Y1422282D01*
G01X1136044Y1415532D02*
Y1423032D01*
X1138284D01*
X1139031Y1422657D01*
X1139591Y1421782D01*
X1139778Y1420782D01*
X1139591Y1419782D01*
X1139124Y1419032D01*
X1138284Y1418657D01*
X1136044D01*
G01X1143358Y1423032D02*
Y1417657D01*
X1143731Y1416532D01*
X1144478Y1415782D01*
X1145411Y1415532D01*
X1146344Y1415782D01*
X1147091Y1416532D01*
X1147464Y1417657D01*
Y1423032D01*
G01X1150111Y1413032D02*
X1155711D01*
G01X1158358Y1415532D02*
Y1423032D01*
X1160224D01*
X1160971Y1422657D01*
X1161531Y1422157D01*
X1161998Y1421407D01*
X1162371Y1420532D01*
X1162464Y1419282D01*
X1162371Y1418032D01*
X1161998Y1417157D01*
X1161531Y1416407D01*
X1160971Y1415907D01*
X1160224Y1415532D01*
X1158358D01*
G01X1126929Y1677520D02*
Y1436969D01*
G01D02*
X1216299D01*
G01X1126929Y1647993D02*
X1216299D01*
G01Y1677520D02*
X1126929D01*
G01X1154580Y57933D02*
X1154890Y58125D01*
X1155097Y58355D01*
X1155200Y58623D01*
X1155097Y58930D01*
X1154890Y59160D01*
X1154580Y59390D01*
X1154167Y59467D01*
X1152100D01*
G01X1155200Y62260D02*
X1152100D01*
X1154322Y60842D01*
Y62758D01*
G01X1152100Y64900D02*
X1152203Y64593D01*
X1152462Y64363D01*
X1152772Y64210D01*
X1153185Y64095D01*
X1153650Y64057D01*
X1154115Y64095D01*
X1154528Y64210D01*
X1154838Y64363D01*
X1155097Y64593D01*
X1155200Y64900D01*
X1155097Y65207D01*
X1154838Y65437D01*
X1154528Y65590D01*
X1154115Y65705D01*
X1153650Y65743D01*
X1153185Y65705D01*
X1152772Y65590D01*
X1152462Y65437D01*
X1152203Y65207D01*
X1152100Y64900D01*
G01X1146395Y96067D02*
Y99267D01*
G01X1152595Y96067D02*
X1146395D01*
G01X1152595Y99267D02*
Y96067D01*
G01X1146395Y99267D02*
X1152595D01*
G01X1143134Y122172D02*
Y110172D01*
G01X1148411Y108095D02*
Y104895D01*
G01X1142211Y108095D02*
X1148411D01*
G01X1142211Y104895D02*
Y108095D01*
G01X1148411Y104895D02*
X1142211D01*
G01X1149268Y108086D02*
X1152468D01*
G01X1149268Y101886D02*
Y108086D01*
G01X1152468Y101886D02*
X1149268D01*
G01X1152468Y108086D02*
Y101886D01*
G01X1142211Y100895D02*
Y104095D01*
G01X1148411Y100895D02*
X1142211D01*
G01X1148411Y104095D02*
Y100895D01*
G01X1142211Y104095D02*
X1148411D01*
G01X1142840Y136438D02*
Y133238D01*
G01Y140438D02*
Y137238D01*
G01X1143186Y148437D02*
X1146386D01*
G01X1143186Y142237D02*
Y148437D01*
G01X1146386Y142237D02*
X1143186D01*
G01X1146386Y148437D02*
Y142237D01*
G01X1145500Y152707D02*
X1147722D01*
X1148187Y152860D01*
X1148497Y153167D01*
X1148600Y153550D01*
X1148497Y153933D01*
X1148187Y154240D01*
X1147722Y154393D01*
X1145500D01*
G01X1147980Y155807D02*
X1148342Y156037D01*
X1148548Y156343D01*
X1148600Y156688D01*
X1148548Y156995D01*
X1148290Y157302D01*
X1147980Y157493D01*
X1147670Y157532D01*
X1147308Y157455D01*
X1147050Y157187D01*
X1146947Y156918D01*
Y156573D01*
G01Y156918D02*
X1146792Y157148D01*
X1146533Y157340D01*
X1146223Y157417D01*
X1145913Y157340D01*
X1145655Y157148D01*
X1145500Y156803D01*
X1145552Y156458D01*
X1145758Y156113D01*
G01X1148600Y159673D02*
X1147928Y159750D01*
X1147360Y159865D01*
X1146843Y160018D01*
X1146275Y160210D01*
X1145500Y160517D01*
Y158983D01*
G01X1148135Y162007D02*
X1148393Y162237D01*
X1148548Y162505D01*
X1148600Y162850D01*
X1148497Y163195D01*
X1148290Y163463D01*
X1147928Y163655D01*
X1147515Y163693D01*
X1147102Y163617D01*
X1146843Y163425D01*
X1146637Y163157D01*
X1146585Y162888D01*
X1146637Y162620D01*
X1146843Y162275D01*
X1145500Y162390D01*
Y163425D01*
G01X1144322Y165304D02*
Y149950D01*
G01X1147142Y203645D02*
Y197645D01*
G01X1145095Y208464D02*
Y205264D01*
G01X1158270Y214687D02*
X1155170D01*
Y215607D01*
X1155325Y215914D01*
X1155687Y216144D01*
X1156100Y216221D01*
X1156513Y216144D01*
X1156823Y215952D01*
X1156978Y215607D01*
Y214687D01*
G01X1155170Y217711D02*
X1157392D01*
X1157857Y217864D01*
X1158167Y218171D01*
X1158270Y218554D01*
X1158167Y218937D01*
X1157857Y219244D01*
X1157392Y219397D01*
X1155170D01*
G01X1156978Y220926D02*
X1156617Y221194D01*
X1156410Y221424D01*
X1156307Y221731D01*
X1156410Y221999D01*
X1156617Y222191D01*
X1156927Y222344D01*
X1157288Y222382D01*
X1157598Y222344D01*
X1157908Y222191D01*
X1158167Y221961D01*
X1158270Y221692D01*
X1158167Y221386D01*
X1157857Y221117D01*
X1157392Y220964D01*
X1156875Y220926D01*
X1156203Y221002D01*
X1155842Y221117D01*
X1155480Y221309D01*
X1155222Y221577D01*
X1155170Y221846D01*
X1155273Y222114D01*
X1155532Y222306D01*
G01X1156978Y224026D02*
X1156617Y224294D01*
X1156410Y224524D01*
X1156307Y224831D01*
X1156410Y225099D01*
X1156617Y225291D01*
X1156927Y225444D01*
X1157288Y225482D01*
X1157598Y225444D01*
X1157908Y225291D01*
X1158167Y225061D01*
X1158270Y224792D01*
X1158167Y224486D01*
X1157857Y224217D01*
X1157392Y224064D01*
X1156875Y224026D01*
X1156203Y224102D01*
X1155842Y224217D01*
X1155480Y224409D01*
X1155222Y224677D01*
X1155170Y224946D01*
X1155273Y225214D01*
X1155532Y225406D01*
G01X1146321Y254969D02*
Y245521D01*
G01X1144588Y231446D02*
X1141388D01*
G01X1144588Y237646D02*
Y231446D01*
G01X1141388Y237646D02*
X1144588D01*
G01X1141388Y231446D02*
Y237646D01*
G01X1156698Y231459D02*
X1153498D01*
G01Y237659D02*
X1156698D01*
G01X1153498Y231459D02*
Y237659D01*
G01X1144266Y243678D02*
Y240478D01*
G01X1148463Y231434D02*
X1145263D01*
G01X1148463Y237634D02*
Y231434D01*
G01X1145263Y237634D02*
X1148463D01*
G01X1145263Y231434D02*
Y237634D01*
G01X1149498Y237659D02*
X1152698D01*
G01X1149498Y231459D02*
Y237659D01*
G01X1152698Y231459D02*
X1149498D01*
G01X1152698Y237659D02*
Y231459D01*
G01X1148124Y240081D02*
Y243281D01*
G01X1154324Y240081D02*
X1148124D01*
G01X1154324Y243281D02*
Y240081D01*
G01X1148124Y243281D02*
X1154324D01*
G01X1142903Y254969D02*
X1146321D01*
G01X1140903Y253245D02*
X1142903Y254969D01*
G01X1153928Y252199D02*
Y248999D01*
G01X1147728Y252199D02*
X1153928D01*
G01X1147728Y248999D02*
Y252199D01*
G01X1153928Y248999D02*
X1147728D01*
G01X1155712Y321748D02*
X1166912D01*
G01X1155712Y341548D02*
Y321748D01*
G01X1159512Y341548D02*
X1155712D01*
G01X1149537Y394318D02*
Y391118D01*
G01X1143337D02*
Y394318D01*
G01X1149537Y391118D02*
X1143337D01*
G01Y387118D02*
Y390318D01*
G01X1149537Y387118D02*
X1143337D01*
G01X1149537Y390318D02*
Y387118D01*
G01X1143337Y390318D02*
X1149537D01*
G01Y386318D02*
Y383118D01*
G01X1143337Y386318D02*
X1149537D01*
G01X1143337Y383118D02*
Y386318D01*
G01X1149537Y383118D02*
X1143337D01*
G01X1149537Y382318D02*
Y379118D01*
G01X1143337Y382318D02*
X1149537D01*
G01X1143337Y379118D02*
Y382318D01*
G01X1149537Y379118D02*
X1143337D01*
G01Y394318D02*
X1149537D01*
G01Y406318D02*
Y403118D01*
G01X1143337Y406318D02*
X1149537D01*
G01X1143337Y403118D02*
Y406318D01*
G01X1149537Y403118D02*
X1143337D01*
G01X1149537Y410318D02*
Y407118D01*
G01X1143337D02*
Y410318D01*
G01X1149537Y407118D02*
X1143337D01*
G01X1149537Y398318D02*
Y395118D01*
G01X1143337Y398318D02*
X1149537D01*
G01X1143337Y395118D02*
Y398318D01*
G01X1149537Y395118D02*
X1143337D01*
G01X1149537Y402318D02*
Y399118D01*
G01X1143337Y402318D02*
X1149537D01*
G01X1143337Y399118D02*
Y402318D01*
G01X1149537Y399118D02*
X1143337D01*
G01X1149537Y414318D02*
Y411118D01*
G01X1143337Y414318D02*
X1149537D01*
G01X1143337Y411118D02*
Y414318D01*
G01X1149537Y411118D02*
X1143337D01*
G01Y410318D02*
X1149537D01*
G01X1145873Y551300D02*
Y548100D01*
G01Y555300D02*
Y552100D01*
G01Y559300D02*
Y556100D01*
G01X1159051Y619263D02*
X1155851D01*
G01D02*
Y625463D01*
G01X1154000Y632550D02*
X1153948Y632243D01*
X1153742Y631975D01*
X1153432Y631745D01*
X1153070Y631592D01*
X1152657Y631515D01*
X1152243D01*
X1151830Y631592D01*
X1151468Y631745D01*
X1151158Y631975D01*
X1150952Y632243D01*
X1150900Y632550D01*
X1150952Y632857D01*
X1151158Y633125D01*
X1151468Y633355D01*
X1151830Y633508D01*
X1152243Y633585D01*
X1152657D01*
X1153070Y633508D01*
X1153432Y633355D01*
X1153742Y633125D01*
X1153948Y632857D01*
X1154000Y632550D01*
G01X1153173Y632857D02*
X1154000Y633317D01*
G01Y635650D02*
X1150900D01*
X1151520Y635190D01*
G01X1154000D02*
Y636110D01*
G01X1151417Y638022D02*
X1151107Y638252D01*
X1150952Y638520D01*
X1150900Y638827D01*
X1151003Y639210D01*
X1151262Y639478D01*
X1151572Y639555D01*
X1151882Y639517D01*
X1152140Y639363D01*
X1152657Y638597D01*
X1153018Y638252D01*
X1153535Y638022D01*
X1154000Y637945D01*
Y639555D01*
G01Y641850D02*
X1150900D01*
X1151520Y641390D01*
G01X1154000D02*
Y642310D01*
G01X1155480Y635329D02*
X1157204Y637329D01*
G01X1155480Y631911D02*
Y635329D01*
G01X1164928Y631911D02*
X1155480D01*
G01X1155851Y625463D02*
X1159051D01*
G01X1155480Y639329D02*
Y642747D01*
G01X1157204Y637329D02*
X1155480Y639329D01*
G01Y642747D02*
X1164928D01*
G01X1154675Y649146D02*
Y655346D01*
G01X1157875Y649146D02*
X1154675D01*
G01Y655346D02*
X1157875D01*
G01X1154256Y658013D02*
Y673013D01*
G01X1167256Y658013D02*
X1154256D01*
G01X1154498Y677432D02*
X1160698D01*
G01X1154498Y674232D02*
Y677432D01*
G01X1160698Y674232D02*
X1154498D01*
G01X1154256Y673013D02*
X1167256D01*
G01X1158085Y766042D02*
X1154885D01*
G01D02*
Y772242D01*
G01X1154085Y766042D02*
X1150885D01*
G01X1154085Y772242D02*
Y766042D01*
G01X1150885D02*
Y772242D01*
G01X1154885D02*
X1158085D01*
G01X1150885D02*
X1154085D01*
G01X1154847Y789960D02*
X1174925D01*
G01X1154847Y804676D02*
Y789960D01*
G01X1174925Y804676D02*
X1154847D01*
G01X1153885Y843742D02*
X1157085D01*
G01X1153885Y837542D02*
Y843742D01*
G01X1157085Y837542D02*
X1153885D01*
G01X1145614Y862964D02*
X1151614D01*
Y868964D01*
G01Y880586D02*
Y886586D01*
X1145614D01*
G01X1157834Y58150D02*
Y111508D01*
G01X1157538Y57756D02*
Y111508D01*
G01X1163919Y57756D02*
X1157538D01*
G01X1163514Y58150D02*
X1157834D01*
G01Y118848D02*
Y114048D01*
G01X1157538Y118848D02*
Y114048D01*
G01X1157834Y132607D02*
Y128340D01*
G01X1157538Y132607D02*
Y128340D01*
G01Y125781D02*
Y121219D01*
G01X1157834Y125781D02*
Y121219D01*
G01X1157538Y153150D02*
Y135400D01*
G01X1157834Y152756D02*
Y135400D01*
G01X1170992Y156615D02*
X1171739Y155990D01*
X1172579Y155615D01*
X1173325D01*
X1174072Y155990D01*
X1174632Y156615D01*
X1174912Y157490D01*
X1174725Y158365D01*
X1174259Y159115D01*
X1173419Y159615D01*
X1172299Y159865D01*
X1171645Y160365D01*
X1171365Y161240D01*
X1171552Y162115D01*
X1172019Y162740D01*
X1172672Y163115D01*
X1173325D01*
X1173979Y162865D01*
X1174539Y162240D01*
G01X1178492Y156615D02*
X1179239Y155990D01*
X1180079Y155615D01*
X1180825D01*
X1181572Y155990D01*
X1182132Y156615D01*
X1182412Y157490D01*
X1182225Y158365D01*
X1181759Y159115D01*
X1180919Y159615D01*
X1179799Y159865D01*
X1179145Y160365D01*
X1178865Y161240D01*
X1179052Y162115D01*
X1179519Y162740D01*
X1180172Y163115D01*
X1180825D01*
X1181479Y162865D01*
X1182039Y162240D01*
G01X1185899Y155615D02*
Y163115D01*
X1187765D01*
X1188512Y162740D01*
X1189072Y162240D01*
X1189539Y161490D01*
X1189912Y160615D01*
X1190005Y159365D01*
X1189912Y158115D01*
X1189539Y157240D01*
X1189072Y156490D01*
X1188512Y155990D01*
X1187765Y155615D01*
X1185899D01*
G01X1195452D02*
Y163115D01*
X1194332Y161615D01*
G01Y155615D02*
X1196572D01*
G01X1202952Y163115D02*
X1202205Y162865D01*
X1201645Y162240D01*
X1201272Y161490D01*
X1200992Y160490D01*
X1200899Y159365D01*
X1200992Y158240D01*
X1201272Y157240D01*
X1201645Y156490D01*
X1202205Y155865D01*
X1202952Y155615D01*
X1203699Y155865D01*
X1204259Y156490D01*
X1204632Y157240D01*
X1204912Y158240D01*
X1205005Y159365D01*
X1204912Y160490D01*
X1204632Y161490D01*
X1204259Y162240D01*
X1203699Y162865D01*
X1202952Y163115D01*
G01X1157538Y153150D02*
X1163919D01*
G01X1157834Y152756D02*
X1163514D01*
G01X1161265Y189535D02*
X1158839D01*
G01X1157725Y195583D02*
Y184087D01*
G01X1171400Y204183D02*
X1168300D01*
Y205103D01*
X1168455Y205410D01*
X1168817Y205640D01*
X1169230Y205717D01*
X1169643Y205640D01*
X1169953Y205448D01*
X1170108Y205103D01*
Y204183D01*
G01X1171400Y207207D02*
X1168300D01*
Y207973D01*
X1168455Y208280D01*
X1168662Y208510D01*
X1168972Y208702D01*
X1169333Y208855D01*
X1169850Y208893D01*
X1170367Y208855D01*
X1170728Y208702D01*
X1171038Y208510D01*
X1171245Y208280D01*
X1171400Y207973D01*
Y207207D01*
G01Y211150D02*
X1168300D01*
X1168920Y210690D01*
G01X1171400D02*
Y211610D01*
G01Y214250D02*
X1168300D01*
X1168920Y213790D01*
G01X1171400D02*
Y214710D01*
G01Y217810D02*
X1168300D01*
X1170522Y216392D01*
Y218308D01*
G01X1156698Y237659D02*
Y231459D01*
G01X1171400Y262983D02*
X1168300D01*
Y263903D01*
X1168455Y264210D01*
X1168817Y264440D01*
X1169230Y264517D01*
X1169643Y264440D01*
X1169953Y264248D01*
X1170108Y263903D01*
Y262983D01*
G01X1171400Y266007D02*
X1168300D01*
Y266773D01*
X1168455Y267080D01*
X1168662Y267310D01*
X1168972Y267502D01*
X1169333Y267655D01*
X1169850Y267693D01*
X1170367Y267655D01*
X1170728Y267502D01*
X1171038Y267310D01*
X1171245Y267080D01*
X1171400Y266773D01*
Y266007D01*
G01Y270410D02*
X1168300D01*
X1170522Y268992D01*
Y270908D01*
G01X1170108Y272322D02*
X1169747Y272590D01*
X1169540Y272820D01*
X1169437Y273127D01*
X1169540Y273395D01*
X1169747Y273587D01*
X1170057Y273740D01*
X1170418Y273778D01*
X1170728Y273740D01*
X1171038Y273587D01*
X1171297Y273357D01*
X1171400Y273088D01*
X1171297Y272782D01*
X1170987Y272513D01*
X1170522Y272360D01*
X1170005Y272322D01*
X1169333Y272398D01*
X1168972Y272513D01*
X1168610Y272705D01*
X1168352Y272973D01*
X1168300Y273242D01*
X1168403Y273510D01*
X1168662Y273702D01*
G01X1166912Y321748D02*
Y341548D01*
G01X1159507Y346100D02*
Y343878D01*
X1159660Y343413D01*
X1159967Y343103D01*
X1160350Y343000D01*
X1160733Y343103D01*
X1161040Y343413D01*
X1161193Y343878D01*
Y346100D01*
G01X1163373Y343000D02*
X1163450Y343672D01*
X1163565Y344240D01*
X1163718Y344757D01*
X1163910Y345325D01*
X1164217Y346100D01*
X1162683D01*
G01X1161312Y339748D02*
X1159512Y341548D01*
G01X1163112D02*
X1161312Y339748D01*
G01X1166912Y341548D02*
X1163112D01*
G01X1167973Y455473D02*
Y452273D01*
G01X1161773Y455473D02*
X1167973D01*
G01X1161773Y452273D02*
Y455473D01*
G01X1167973Y452273D02*
X1161773D01*
G01Y444273D02*
Y447473D01*
G01X1167973Y444273D02*
X1161773D01*
G01X1167973Y447473D02*
Y444273D01*
G01X1161773Y447473D02*
X1167973D01*
G01X1161773Y448273D02*
Y451473D01*
G01X1167973Y448273D02*
X1161773D01*
G01X1167973Y451473D02*
Y448273D01*
G01X1161773Y451473D02*
X1167973D01*
G01Y460459D02*
Y457259D01*
G01X1161773D02*
Y460459D01*
G01X1167973Y457259D02*
X1161773D01*
G01Y460459D02*
X1167973D01*
G01X1161773Y461259D02*
Y464459D01*
G01X1167973Y461259D02*
X1161773D01*
G01X1167973Y464459D02*
Y461259D01*
G01X1161773Y464459D02*
X1167973D01*
G01X1167158Y544312D02*
Y541112D01*
G01X1160958Y544312D02*
X1167158D01*
G01X1160958Y541112D02*
Y544312D01*
G01X1167158Y541112D02*
X1160958D01*
G01Y545112D02*
Y548312D01*
G01X1167158Y545112D02*
X1160958D01*
G01X1167158Y548312D02*
Y545112D01*
G01X1160958Y548312D02*
X1167158D01*
G01X1159051Y625463D02*
Y619263D01*
G01X1163051D02*
X1159851D01*
G01X1163051Y625463D02*
Y619263D01*
G01X1159851D02*
Y625463D01*
G01X1167051Y619263D02*
X1163851D01*
G01X1167051Y625463D02*
Y619263D01*
G01X1163851D02*
Y625463D01*
G01X1164928Y642747D02*
Y631911D01*
G01X1159851Y625463D02*
X1163051D01*
G01X1163851D02*
X1167051D01*
G01X1157875Y655346D02*
Y649146D01*
G01X1158675D02*
Y655346D01*
G01X1161875Y649146D02*
X1158675D01*
G01X1161875Y655346D02*
Y649146D01*
G01X1162675D02*
Y655346D01*
G01X1165875Y649146D02*
X1162675D01*
G01X1165875Y655346D02*
Y649146D01*
G01X1158675Y655346D02*
X1161875D01*
G01X1162675D02*
X1165875D01*
G01X1168500Y660057D02*
X1170722D01*
X1171187Y660210D01*
X1171497Y660517D01*
X1171600Y660900D01*
X1171497Y661283D01*
X1171187Y661590D01*
X1170722Y661743D01*
X1168500D01*
G01X1170980Y663157D02*
X1171342Y663387D01*
X1171548Y663693D01*
X1171600Y664038D01*
X1171548Y664345D01*
X1171290Y664652D01*
X1170980Y664843D01*
X1170670Y664882D01*
X1170308Y664805D01*
X1170050Y664537D01*
X1169947Y664268D01*
Y663923D01*
G01Y664268D02*
X1169792Y664498D01*
X1169533Y664690D01*
X1169223Y664767D01*
X1168913Y664690D01*
X1168655Y664498D01*
X1168500Y664153D01*
X1168552Y663808D01*
X1168758Y663463D01*
G01X1169017Y666372D02*
X1168707Y666602D01*
X1168552Y666870D01*
X1168500Y667177D01*
X1168603Y667560D01*
X1168862Y667828D01*
X1169172Y667905D01*
X1169482Y667867D01*
X1169740Y667713D01*
X1170257Y666947D01*
X1170618Y666602D01*
X1171135Y666372D01*
X1171600Y666295D01*
Y667905D01*
G01X1167256Y673013D02*
Y658013D01*
G01X1160698Y677432D02*
Y674232D01*
G01X1161338Y674289D02*
Y677489D01*
G01X1167538Y674289D02*
X1161338D01*
G01X1167538Y677489D02*
Y674289D01*
G01X1161338Y677489D02*
X1167538D01*
G01X1170085Y765910D02*
X1166885D01*
G01X1170085Y772110D02*
Y765910D01*
G01X1166885D02*
Y772110D01*
G01X1162085Y766042D02*
X1158885D01*
G01X1162085Y772242D02*
Y766042D01*
G01X1158885D02*
Y772242D01*
G01X1166085Y766042D02*
X1162885D01*
G01X1166085Y772242D02*
Y766042D01*
G01X1162885D02*
Y772242D01*
G01X1158085D02*
Y766042D01*
G01X1166885Y772110D02*
X1170085D01*
G01X1158885Y772242D02*
X1162085D01*
G01X1162885D02*
X1166085D01*
G01X1174925Y793279D02*
X1170886Y797318D01*
G01D02*
X1174925Y801357D01*
G01X1165885Y830242D02*
X1169085D01*
G01X1165885Y824042D02*
Y830242D01*
G01X1169085Y824042D02*
X1165885D01*
G01X1169085Y830242D02*
Y824042D01*
G01X1157885Y830242D02*
X1161085D01*
G01X1157885Y824042D02*
Y830242D01*
G01X1161085Y824042D02*
X1157885D01*
G01X1161085Y830242D02*
Y824042D01*
G01X1169885Y843742D02*
X1173085D01*
G01X1169885Y837542D02*
Y843742D01*
G01X1173085Y837542D02*
X1169885D01*
G01X1161885Y843742D02*
X1165085D01*
G01X1161885Y837542D02*
Y843742D01*
G01X1165085Y837542D02*
X1161885D01*
G01X1165085Y843742D02*
Y837542D01*
G01X1165885Y843742D02*
X1169085D01*
G01X1165885Y837542D02*
Y843742D01*
G01X1169085Y837542D02*
X1165885D01*
G01X1169085Y843742D02*
Y837542D01*
G01X1157885Y843742D02*
X1161085D01*
G01X1157885Y837542D02*
Y843742D01*
G01X1161085Y837542D02*
X1157885D01*
G01X1161085Y843742D02*
Y837542D01*
G01X1157085Y843742D02*
Y837542D01*
G01X1167700Y906943D02*
Y900943D01*
X1161700D01*
G01Y924565D02*
X1167700D01*
Y918565D01*
G01X1169329Y1726490D02*
Y1723990D01*
X1179329D01*
Y1724540D01*
G01X1169329Y1736490D02*
Y1731490D01*
G01X1168974Y1745190D02*
X1170584Y1748290D01*
G01X1168974D02*
X1170584Y1745190D01*
G01X1172802D02*
X1172879Y1745862D01*
X1172994Y1746430D01*
X1173147Y1746947D01*
X1173339Y1747515D01*
X1173646Y1748290D01*
X1172112D01*
G01X1175251Y1747773D02*
X1175481Y1748083D01*
X1175749Y1748238D01*
X1176056Y1748290D01*
X1176439Y1748187D01*
X1176707Y1747928D01*
X1176784Y1747618D01*
X1176746Y1747308D01*
X1176592Y1747050D01*
X1175826Y1746533D01*
X1175481Y1746172D01*
X1175251Y1745655D01*
X1175174Y1745190D01*
X1176784D01*
G01X1179329Y1743440D02*
Y1743990D01*
X1169329D01*
G01D02*
Y1741490D01*
G01X1169123Y1773514D02*
Y1771014D01*
X1179123D01*
Y1771564D01*
G01X1169123Y1783514D02*
Y1778514D01*
G01Y1791014D02*
Y1788514D01*
G01X1168768Y1792214D02*
X1170378Y1795314D01*
G01X1168768D02*
X1170378Y1792214D01*
G01X1171945Y1793506D02*
X1172213Y1793867D01*
X1172443Y1794074D01*
X1172750Y1794177D01*
X1173018Y1794074D01*
X1173210Y1793867D01*
X1173363Y1793557D01*
X1173401Y1793196D01*
X1173363Y1792886D01*
X1173210Y1792576D01*
X1172980Y1792317D01*
X1172711Y1792214D01*
X1172405Y1792317D01*
X1172136Y1792627D01*
X1171983Y1793092D01*
X1171945Y1793609D01*
X1172021Y1794281D01*
X1172136Y1794642D01*
X1172328Y1795004D01*
X1172596Y1795262D01*
X1172865Y1795314D01*
X1173133Y1795211D01*
X1173325Y1794952D01*
G01X1175121Y1792576D02*
X1175390Y1792317D01*
X1175696Y1792214D01*
X1176003Y1792317D01*
X1176271Y1792627D01*
X1176463Y1793092D01*
X1176540Y1793557D01*
Y1794126D01*
X1176463Y1794591D01*
X1176271Y1795004D01*
X1176041Y1795211D01*
X1175773Y1795314D01*
X1175466Y1795211D01*
X1175236Y1795004D01*
X1175083Y1794694D01*
X1175006Y1794281D01*
X1175083Y1793919D01*
X1175275Y1793557D01*
X1175505Y1793351D01*
X1175773Y1793299D01*
X1176080Y1793402D01*
X1176310Y1793661D01*
X1176540Y1794126D01*
G01X1179123Y1790464D02*
Y1791014D01*
X1169123D01*
G01X1182046Y58150D02*
Y104541D01*
G01X1182342Y57756D02*
Y104541D01*
G01Y57756D02*
X1175961D01*
G01X1182046Y58150D02*
X1176366D01*
G01X1187874Y97026D02*
Y103226D01*
G01X1191074Y97026D02*
X1187874D01*
G01X1189878Y86929D02*
X1186678D01*
G01Y93129D02*
X1189878D01*
G01X1186678Y86929D02*
Y93129D01*
G01X1182342Y111507D02*
Y107060D01*
G01X1182046Y111507D02*
Y107060D01*
G01Y118680D02*
Y114087D01*
G01X1182342Y118680D02*
Y114087D01*
G01X1187874Y103226D02*
X1191074D01*
G01X1182046Y132859D02*
Y128325D01*
G01X1182342Y132859D02*
Y128325D01*
G01Y125844D02*
Y121329D01*
G01X1182046Y125844D02*
Y121329D01*
G01X1182342Y153150D02*
Y135558D01*
G01X1182046Y152756D02*
Y135558D01*
G01X1174442Y164436D02*
X1189242D01*
G01X1174442Y195440D02*
Y164436D01*
G01X1175961Y153150D02*
X1182342D01*
G01X1176366Y152756D02*
X1182046D01*
G01X1189242Y195440D02*
X1174442D01*
G01X1186555Y213035D02*
Y225035D01*
G01X1192555Y213035D02*
X1186555D01*
G01X1178445Y199912D02*
Y202338D01*
G01X1184493Y203452D02*
X1172997D01*
G01X1184493Y233011D02*
Y203452D01*
G01X1172997D02*
Y233011D01*
G01X1186555Y225035D02*
X1192555D01*
G01X1178345Y236652D02*
Y234412D01*
G01X1179970Y235625D02*
X1176720D01*
G01X1172997Y233011D02*
X1184493D01*
G01X1185838Y250325D02*
Y234813D01*
G01D02*
X1216930D01*
G01X1178214Y259204D02*
Y261630D01*
G01X1184262Y262744D02*
X1172766D01*
G01X1184262Y292303D02*
Y262744D01*
G01X1172766D02*
Y292303D01*
G01X1186017Y251936D02*
Y255036D01*
X1186937D01*
X1187244Y254881D01*
X1187474Y254519D01*
X1187551Y254106D01*
X1187474Y253693D01*
X1187282Y253383D01*
X1186937Y253228D01*
X1186017D01*
G01X1189041Y251936D02*
Y255036D01*
X1189807D01*
X1190114Y254881D01*
X1190344Y254674D01*
X1190536Y254364D01*
X1190689Y254003D01*
X1190727Y253486D01*
X1190689Y252969D01*
X1190536Y252608D01*
X1190344Y252298D01*
X1190114Y252091D01*
X1189807Y251936D01*
X1189041D01*
G01X1193444D02*
Y255036D01*
X1192026Y252814D01*
X1193942D01*
G01X1196084Y251936D02*
X1196352Y251988D01*
X1196659Y252143D01*
X1196851Y252401D01*
X1196927Y252763D01*
X1196851Y253124D01*
X1196621Y253434D01*
X1196276Y253589D01*
X1195892D01*
X1195662Y253693D01*
X1195471Y253951D01*
X1195394Y254313D01*
X1195509Y254674D01*
X1195777Y254933D01*
X1196084Y255036D01*
X1196391Y254933D01*
X1196659Y254674D01*
X1196774Y254313D01*
X1196697Y253951D01*
X1196506Y253693D01*
X1196276Y253589D01*
X1195892D01*
X1195547Y253434D01*
X1195317Y253124D01*
X1195241Y252763D01*
X1195317Y252401D01*
X1195509Y252143D01*
X1195816Y251988D01*
X1196084Y251936D01*
G01X1216930Y250325D02*
X1185838D01*
G01X1186133Y271655D02*
Y283655D01*
G01X1192133Y271655D02*
X1186133D01*
G01Y283655D02*
X1192133D01*
G01X1178328Y297486D02*
Y295246D01*
G01X1179953Y296459D02*
X1176703D01*
G01X1172766Y292303D02*
X1184262D01*
G01X1188684Y325742D02*
Y322542D01*
G01X1182484Y325742D02*
X1188684D01*
G01X1182484Y322542D02*
Y325742D01*
G01X1188684Y322542D02*
X1182484D01*
G01X1187364Y327798D02*
Y330998D01*
G01X1193564Y327798D02*
X1187364D01*
G01X1178236Y337503D02*
Y340703D01*
G01X1184436Y337503D02*
X1178236D01*
G01X1184436Y340703D02*
Y337503D01*
G01X1178236Y340703D02*
X1184436D01*
G01X1187364Y330998D02*
X1193564D01*
G01X1177380Y367383D02*
X1177690Y367575D01*
X1177897Y367805D01*
X1178000Y368073D01*
X1177897Y368380D01*
X1177690Y368610D01*
X1177380Y368840D01*
X1176967Y368917D01*
X1174900D01*
G01X1175417Y370522D02*
X1175107Y370752D01*
X1174952Y371020D01*
X1174900Y371327D01*
X1175003Y371710D01*
X1175262Y371978D01*
X1175572Y372055D01*
X1175882Y372017D01*
X1176140Y371863D01*
X1176657Y371097D01*
X1177018Y370752D01*
X1177535Y370522D01*
X1178000Y370445D01*
Y372055D01*
G01X1177535Y373507D02*
X1177793Y373737D01*
X1177948Y374005D01*
X1178000Y374350D01*
X1177897Y374695D01*
X1177690Y374963D01*
X1177328Y375155D01*
X1176915Y375193D01*
X1176502Y375117D01*
X1176243Y374925D01*
X1176037Y374657D01*
X1175985Y374388D01*
X1176037Y374120D01*
X1176243Y373775D01*
X1174900Y373890D01*
Y374925D01*
G01X1179813Y366063D02*
X1187259D01*
G01X1179813Y418006D02*
Y366063D01*
G01Y425116D02*
Y467638D01*
G01Y474925D02*
Y470260D01*
G01Y481999D02*
Y477273D01*
G01Y489023D02*
Y484398D01*
G01Y511780D02*
Y491483D01*
G01Y519090D02*
Y514395D01*
G01Y526062D02*
Y521356D01*
G01Y533279D02*
Y528543D01*
G01Y546456D02*
Y535678D01*
G01Y553556D02*
Y562026D01*
G01Y569098D02*
Y564383D01*
G01Y576183D02*
Y571518D01*
G01Y583287D02*
Y578613D01*
G01Y590310D02*
Y585655D01*
G01Y597384D02*
Y592730D01*
G01Y604489D02*
Y599824D01*
G01Y639449D02*
Y613966D01*
G01Y611543D02*
Y606908D01*
G01X1195490Y645269D02*
X1179890D01*
X1195490Y654239D01*
X1179890D01*
G01Y665314D02*
Y669994D01*
G01Y667654D02*
X1195490D01*
G01Y665314D02*
Y669994D01*
G01X1181190Y689844D02*
X1180410Y688674D01*
X1179890Y687309D01*
Y685749D01*
X1180670Y683994D01*
X1181970Y682629D01*
X1183530Y681654D01*
X1186130Y680874D01*
X1188470Y680679D01*
X1190810Y681069D01*
X1192370Y681654D01*
X1193930Y682824D01*
X1194970Y684189D01*
X1195490Y685554D01*
Y686919D01*
X1194970Y688284D01*
X1194190Y689454D01*
X1193150Y690429D01*
G01Y699164D02*
X1194450Y700334D01*
X1195230Y701699D01*
X1195490Y703454D01*
X1194970Y705209D01*
X1193930Y706574D01*
X1192110Y707549D01*
X1190030Y707744D01*
X1187950Y707354D01*
X1186650Y706379D01*
X1185610Y705014D01*
X1185350Y703649D01*
X1185610Y702284D01*
X1186650Y700529D01*
X1179890Y701114D01*
Y706379D01*
G01X1187309Y639449D02*
X1179813D01*
G01X1182315Y777368D02*
X1179115D01*
G01X1182315Y783568D02*
Y777368D01*
G01X1179115D02*
Y783568D01*
G01X1179270Y776034D02*
Y772834D01*
G01X1173070Y776034D02*
X1179270D01*
G01X1173070Y772834D02*
Y776034D01*
G01X1179270Y772834D02*
X1173070D01*
G01X1179115Y783568D02*
X1182315D01*
G01X1176700Y793507D02*
X1178922D01*
X1179387Y793660D01*
X1179697Y793967D01*
X1179800Y794350D01*
X1179697Y794733D01*
X1179387Y795040D01*
X1178922Y795193D01*
X1176700D01*
G01X1178508Y796722D02*
X1178147Y796990D01*
X1177940Y797220D01*
X1177837Y797527D01*
X1177940Y797795D01*
X1178147Y797987D01*
X1178457Y798140D01*
X1178818Y798178D01*
X1179128Y798140D01*
X1179438Y797987D01*
X1179697Y797757D01*
X1179800Y797488D01*
X1179697Y797182D01*
X1179387Y796913D01*
X1178922Y796760D01*
X1178405Y796722D01*
X1177733Y796798D01*
X1177372Y796913D01*
X1177010Y797105D01*
X1176752Y797373D01*
X1176700Y797642D01*
X1176803Y797910D01*
X1177062Y798102D01*
G01X1179180Y799707D02*
X1179542Y799937D01*
X1179748Y800243D01*
X1179800Y800588D01*
X1179748Y800895D01*
X1179490Y801202D01*
X1179180Y801393D01*
X1178870Y801432D01*
X1178508Y801355D01*
X1178250Y801087D01*
X1178147Y800818D01*
Y800473D01*
G01Y800818D02*
X1177992Y801048D01*
X1177733Y801240D01*
X1177423Y801317D01*
X1177113Y801240D01*
X1176855Y801048D01*
X1176700Y800703D01*
X1176752Y800358D01*
X1176958Y800013D01*
G01X1174925Y789960D02*
Y793279D01*
G01Y801357D02*
Y804676D01*
G01X1181885Y830242D02*
X1185085D01*
G01X1181885Y824042D02*
Y830242D01*
G01X1185085Y824042D02*
X1181885D01*
G01X1185085Y830242D02*
Y824042D01*
G01X1173885Y830242D02*
X1177085D01*
G01X1173885Y824042D02*
Y830242D01*
G01X1177085Y824042D02*
X1173885D01*
G01X1177085Y830242D02*
Y824042D01*
G01X1181885Y843742D02*
X1185085D01*
G01X1181885Y837542D02*
Y843742D01*
G01X1185085Y837542D02*
X1181885D01*
G01X1185085Y843742D02*
Y837542D01*
G01X1177885Y843742D02*
X1181085D01*
G01X1177885Y837542D02*
Y843742D01*
G01X1181085Y837542D02*
X1177885D01*
G01X1181085Y843742D02*
Y837542D01*
G01X1173085Y843742D02*
Y837542D01*
G01X1173885Y843742D02*
X1177085D01*
G01X1173885Y837542D02*
Y843742D01*
G01X1177085Y837542D02*
X1173885D01*
G01X1177085Y843742D02*
Y837542D01*
G01X1179329Y1733440D02*
Y1734540D01*
G01X1179123Y1780464D02*
Y1781564D01*
G01X1198267Y82540D02*
Y85740D01*
G01X1204467Y82540D02*
X1198267D01*
G01X1204467Y85740D02*
Y82540D01*
G01X1198267Y74540D02*
Y77740D01*
G01X1204467Y74540D02*
X1198267D01*
G01X1204467Y77740D02*
Y74540D01*
G01X1198267Y77740D02*
X1204467D01*
G01X1198267Y78540D02*
Y81740D01*
G01X1204467Y78540D02*
X1198267D01*
G01X1204467Y81740D02*
Y78540D01*
G01X1198267Y81740D02*
X1204467D01*
G01X1191074Y103226D02*
Y97026D01*
G01X1189878Y93129D02*
Y86929D01*
G01X1198267Y85740D02*
X1204467D01*
G01X1197878Y86929D02*
X1194678D01*
G01X1197878Y93129D02*
Y86929D01*
G01X1194678Y93129D02*
X1197878D01*
G01X1194678Y86929D02*
Y93129D01*
G01X1201887Y86929D02*
X1198687D01*
G01X1201887Y93129D02*
Y86929D01*
G01X1198687Y93129D02*
X1201887D01*
G01X1198687Y86929D02*
Y93129D01*
G01X1193878Y86929D02*
X1190678D01*
G01X1193878Y93129D02*
Y86929D01*
G01X1190678Y93129D02*
X1193878D01*
G01X1190678Y86929D02*
Y93129D01*
G01X1193957Y96673D02*
Y102873D01*
G01X1197157Y96673D02*
X1193957D01*
G01X1197157Y102873D02*
Y96673D01*
G01X1197957D02*
Y102873D01*
G01X1201157Y96673D02*
X1197957D01*
G01X1201157Y102873D02*
Y96673D01*
G01X1203461Y95950D02*
Y102150D01*
G01X1206661Y95950D02*
X1203461D01*
G01X1193957Y102873D02*
X1197157D01*
G01X1197957D02*
X1201157D01*
G01X1203461Y102150D02*
X1206661D01*
G01X1203461Y109762D02*
X1206661D01*
G01X1203461Y103562D02*
Y109762D01*
G01X1206661Y103562D02*
X1203461D01*
G01X1199940Y144690D02*
Y154138D01*
G01X1210776Y144690D02*
X1199940D01*
G01X1202521Y139647D02*
Y142847D01*
G01X1208721Y139647D02*
X1202521D01*
G01Y142847D02*
X1208721D01*
G01X1195542Y139647D02*
Y142847D01*
G01X1201742Y139647D02*
X1195542D01*
G01X1201742Y142847D02*
Y139647D01*
G01X1195542Y142847D02*
X1201742D01*
G01X1191572Y145940D02*
Y149140D01*
G01X1197772Y145940D02*
X1191572D01*
G01X1197772Y149140D02*
Y145940D01*
G01X1191572Y149140D02*
X1197772D01*
G01X1189242Y164436D02*
Y195440D01*
G01X1203358Y154138D02*
X1205358Y152414D01*
G01X1199940Y154138D02*
X1203358D01*
G01X1197772Y153140D02*
Y149940D01*
G01X1191572Y153140D02*
X1197772D01*
G01X1191572Y149940D02*
Y153140D01*
G01X1197772Y149940D02*
X1191572D01*
G01X1203057Y174900D02*
Y172678D01*
X1203210Y172213D01*
X1203517Y171903D01*
X1203900Y171800D01*
X1204283Y171903D01*
X1204590Y172213D01*
X1204743Y172678D01*
Y174900D01*
G01X1206923Y171800D02*
X1207000Y172472D01*
X1207115Y173040D01*
X1207268Y173557D01*
X1207460Y174125D01*
X1207767Y174900D01*
X1206233D01*
G01X1209257Y172420D02*
X1209487Y172058D01*
X1209793Y171852D01*
X1210138Y171800D01*
X1210445Y171852D01*
X1210752Y172110D01*
X1210943Y172420D01*
X1210982Y172730D01*
X1210905Y173092D01*
X1210637Y173350D01*
X1210368Y173453D01*
X1210023D01*
G01X1210368D02*
X1210598Y173608D01*
X1210790Y173867D01*
X1210867Y174177D01*
X1210790Y174487D01*
X1210598Y174745D01*
X1210253Y174900D01*
X1209908Y174848D01*
X1209563Y174642D01*
G01X1202936Y176944D02*
Y178897D01*
G01X1204889Y176944D02*
X1202936D01*
G01X1198208Y171473D02*
X1195008D01*
G01X1198208Y177673D02*
Y171473D01*
G01X1195008Y177673D02*
X1198208D01*
G01X1195008Y171473D02*
Y177673D01*
G01X1194208Y171473D02*
X1191008D01*
G01X1194208Y177673D02*
Y171473D01*
G01X1191008Y177673D02*
X1194208D01*
G01X1191008Y171473D02*
Y177673D01*
G01X1201231Y170297D02*
Y167097D01*
G01X1195031Y170297D02*
X1201231D01*
G01X1195031Y167097D02*
Y170297D01*
G01X1201231Y167097D02*
X1195031D01*
G01X1202936Y188756D02*
X1204889D01*
G01X1202936Y186803D02*
Y188756D01*
G01X1198435Y182730D02*
X1195235D01*
G01X1198435Y188930D02*
Y182730D01*
G01X1195235Y188930D02*
X1198435D01*
G01X1195235Y182730D02*
Y188930D01*
G01X1201426Y193541D02*
Y190341D01*
G01X1195226Y193541D02*
X1201426D01*
G01X1195226Y190341D02*
Y193541D01*
G01X1201426Y190341D02*
X1195226D01*
G01X1192555Y225035D02*
Y213035D01*
G01X1201431Y201906D02*
Y205006D01*
X1202351D01*
X1202658Y204851D01*
X1202888Y204489D01*
X1202965Y204076D01*
X1202888Y203663D01*
X1202696Y203353D01*
X1202351Y203198D01*
X1201431D01*
G01X1204455Y205006D02*
Y202784D01*
X1204608Y202319D01*
X1204915Y202009D01*
X1205298Y201906D01*
X1205681Y202009D01*
X1205988Y202319D01*
X1206141Y202784D01*
Y205006D01*
G01X1208858Y201906D02*
Y205006D01*
X1207440Y202784D01*
X1209356D01*
G01X1210770Y204489D02*
X1211000Y204799D01*
X1211268Y204954D01*
X1211575Y205006D01*
X1211958Y204903D01*
X1212226Y204644D01*
X1212303Y204334D01*
X1212265Y204024D01*
X1212111Y203766D01*
X1211345Y203249D01*
X1211000Y202888D01*
X1210770Y202371D01*
X1210693Y201906D01*
X1212303D01*
G01X1215711Y220252D02*
Y208048D01*
X1200407D01*
Y220252D01*
X1215711D01*
G01X1193395Y226621D02*
Y232621D01*
G01X1205395Y226621D02*
X1193395D01*
G01X1197374Y215082D02*
X1194174D01*
G01X1197374Y221282D02*
Y215082D01*
G01X1194174Y221282D02*
X1197374D01*
G01X1194174Y215082D02*
Y221282D01*
G01X1203395Y225921D02*
Y222721D01*
G01X1197195Y225921D02*
X1203395D01*
G01X1197195Y222721D02*
Y225921D01*
G01X1203395Y222721D02*
X1197195D01*
G01X1193395Y232621D02*
X1205395D01*
G01X1194063Y258010D02*
Y264210D01*
G01X1197263Y258010D02*
X1194063D01*
G01X1197263Y264210D02*
Y258010D01*
G01X1202063D02*
Y264210D01*
G01X1205263Y258010D02*
X1202063D01*
G01X1201263D02*
X1198063D01*
G01X1201263Y264210D02*
Y258010D01*
G01X1198063D02*
Y264210D01*
G01X1192133Y283655D02*
Y271655D01*
G01X1194063Y264210D02*
X1197263D01*
G01X1202063D02*
X1205263D01*
G01X1198063D02*
X1201263D01*
G01X1204784Y279427D02*
Y267653D01*
G01X1195022D02*
Y279427D01*
G01X1204784Y267653D02*
X1195022D01*
G01X1196316Y283383D02*
X1193116D01*
G01X1196316Y289583D02*
Y283383D01*
G01X1193116Y289583D02*
X1196316D01*
G01X1193116Y283383D02*
Y289583D01*
G01X1200316Y283383D02*
X1197116D01*
G01X1200316Y289583D02*
Y283383D01*
G01X1197116Y289583D02*
X1200316D01*
G01X1197116Y283383D02*
Y289583D01*
G01X1201116Y283383D02*
Y289583D01*
X1204316D01*
Y283383D01*
X1201116D01*
G01X1195022Y279427D02*
X1204784D01*
G01X1199588Y316273D02*
Y319473D01*
G01X1205788Y316273D02*
X1199588D01*
G01Y319473D02*
X1205788D01*
G01X1193564Y330998D02*
Y327798D01*
G01X1199829Y366063D02*
X1215305D01*
G01X1204992Y653823D02*
X1204212Y652653D01*
X1203692Y651288D01*
Y649728D01*
X1204472Y647973D01*
X1205772Y646608D01*
X1207332Y645633D01*
X1209932Y644853D01*
X1212272Y644658D01*
X1214612Y645048D01*
X1216172Y645633D01*
X1217732Y646803D01*
X1218772Y648168D01*
X1219292Y649533D01*
Y650898D01*
X1218772Y652263D01*
X1217992Y653433D01*
X1216952Y654408D01*
G01X1210972Y668993D02*
X1210192Y669773D01*
X1208892Y670358D01*
X1207072Y670748D01*
X1205512Y670358D01*
X1204472Y669578D01*
X1203692Y668213D01*
Y662948D01*
X1219292D01*
Y669383D01*
X1218252Y670748D01*
X1216692Y671528D01*
X1214872Y671918D01*
X1213052Y671528D01*
X1211492Y670358D01*
X1210972Y668993D01*
Y662948D01*
G01X1203692Y681433D02*
X1219292D01*
Y689233D01*
G01X1224492Y697383D02*
Y709083D01*
G01X1210972Y722693D02*
X1210192Y723473D01*
X1208892Y724058D01*
X1207072Y724448D01*
X1205512Y724058D01*
X1204472Y723278D01*
X1203692Y721913D01*
Y716648D01*
X1219292D01*
Y723083D01*
X1218252Y724448D01*
X1216692Y725228D01*
X1214872Y725618D01*
X1213052Y725228D01*
X1211492Y724058D01*
X1210972Y722693D01*
Y716648D01*
G01X1219292Y739033D02*
X1219032Y737473D01*
X1217992Y736108D01*
X1216432Y734938D01*
X1214612Y734158D01*
X1212532Y733768D01*
X1210452D01*
X1208372Y734158D01*
X1206552Y734938D01*
X1204992Y736108D01*
X1203952Y737473D01*
X1203692Y739033D01*
X1203952Y740593D01*
X1204992Y741958D01*
X1206552Y743128D01*
X1208372Y743908D01*
X1210452Y744298D01*
X1212532D01*
X1214612Y743908D01*
X1216432Y743128D01*
X1217992Y741958D01*
X1219032Y740593D01*
X1219292Y739033D01*
G01X1203692Y756933D02*
X1219292D01*
G01X1203692Y752448D02*
Y761418D01*
G01X1215305Y639449D02*
X1199759D01*
G01X1202063Y938796D02*
X1196063D01*
G01X1202063Y944796D02*
Y938796D01*
G01Y964387D02*
Y958387D01*
G01X1196063Y964387D02*
X1202063D01*
G01X1220407Y-60600D02*
Y-57500D01*
X1221173D01*
X1221480Y-57655D01*
X1221710Y-57862D01*
X1221902Y-58172D01*
X1222055Y-58533D01*
X1222093Y-59050D01*
X1222055Y-59567D01*
X1221902Y-59928D01*
X1221710Y-60238D01*
X1221480Y-60445D01*
X1221173Y-60600D01*
X1220407D01*
G01X1225117D02*
X1223583D01*
Y-57500D01*
X1225117D01*
G01X1224503Y-58998D02*
X1223583D01*
G01X1227450Y-57500D02*
X1227143Y-57603D01*
X1226913Y-57862D01*
X1226760Y-58172D01*
X1226645Y-58585D01*
X1226607Y-59050D01*
X1226645Y-59515D01*
X1226760Y-59928D01*
X1226913Y-60238D01*
X1227143Y-60497D01*
X1227450Y-60600D01*
X1227757Y-60497D01*
X1227987Y-60238D01*
X1228140Y-59928D01*
X1228255Y-59515D01*
X1228293Y-59050D01*
X1228255Y-58585D01*
X1228140Y-58172D01*
X1227987Y-57862D01*
X1227757Y-57603D01*
X1227450Y-57500D01*
G01X1229707Y-59980D02*
X1229937Y-60342D01*
X1230243Y-60548D01*
X1230588Y-60600D01*
X1230895Y-60548D01*
X1231202Y-60290D01*
X1231393Y-59980D01*
X1231432Y-59670D01*
X1231355Y-59308D01*
X1231087Y-59050D01*
X1230818Y-58947D01*
X1230473D01*
G01X1230818D02*
X1231048Y-58792D01*
X1231240Y-58533D01*
X1231317Y-58223D01*
X1231240Y-57913D01*
X1231048Y-57655D01*
X1230703Y-57500D01*
X1230358Y-57552D01*
X1230013Y-57758D01*
G01X1232922Y-60600D02*
Y-57500D01*
X1234378D01*
G01X1233842Y-58998D02*
X1232922D01*
G01X1235600Y-61633D02*
X1237900D01*
G01X1239850Y-60600D02*
Y-57500D01*
X1239390Y-58120D01*
G01Y-60600D02*
X1240310D01*
G01X1229765Y67523D02*
X1217561D01*
G01D02*
Y70183D01*
G01X1218258Y59613D02*
X1224458D01*
G01X1218258Y56413D02*
Y59613D01*
G01X1224458Y56413D02*
X1218258D01*
G01X1215133Y70181D02*
Y66981D01*
G01X1208933D02*
Y70181D01*
G01X1215133Y66981D02*
X1208933D01*
G01X1217561Y79047D02*
X1229765D01*
G01X1217561Y76285D02*
Y79047D01*
G01X1220663Y73285D02*
X1217561Y76285D01*
G01Y70183D02*
X1220663Y73285D01*
G01X1208933Y70181D02*
X1215133D01*
G01X1208978Y70987D02*
Y74187D01*
G01X1215178Y70987D02*
X1208978D01*
G01X1215178Y74187D02*
Y70987D01*
G01X1208978Y74187D02*
X1215178D01*
G01X1208978Y74987D02*
Y78187D01*
G01X1215178Y74987D02*
X1208978D01*
G01X1215178Y78187D02*
Y74987D01*
G01X1208978Y78187D02*
X1215178D01*
G01X1215133Y82181D02*
Y78981D01*
G01X1208933Y82181D02*
X1215133D01*
G01X1208933Y78981D02*
Y82181D01*
G01X1215133Y78981D02*
X1208933D01*
G01X1215968Y93476D02*
X1219168D01*
G01X1215968Y87276D02*
Y93476D01*
G01X1219168Y87276D02*
X1215968D01*
G01X1219168Y93476D02*
Y87276D01*
G01X1206661Y102150D02*
Y95950D01*
G01X1220803Y111267D02*
Y95913D01*
G01X1208125D02*
Y111267D01*
G01X1220606Y95913D02*
X1208125D01*
G01X1220676Y116088D02*
Y112888D01*
G01X1214476Y116088D02*
X1220676D01*
G01X1214476Y112888D02*
Y116088D01*
G01X1220676Y112888D02*
X1214476D01*
G01X1206661Y109762D02*
Y103562D01*
G01X1208125Y111267D02*
X1220803D01*
G01X1220503Y119402D02*
X1217403D01*
Y120322D01*
X1217558Y120629D01*
X1217920Y120859D01*
X1218333Y120936D01*
X1218746Y120859D01*
X1219056Y120667D01*
X1219211Y120322D01*
Y119402D01*
G01X1217403Y122426D02*
X1219625D01*
X1220090Y122579D01*
X1220400Y122886D01*
X1220503Y123269D01*
X1220400Y123652D01*
X1220090Y123959D01*
X1219625Y124112D01*
X1217403D01*
G01X1220503Y126369D02*
X1217403D01*
X1218023Y125909D01*
G01X1220503D02*
Y126829D01*
G01X1219883Y128626D02*
X1220245Y128856D01*
X1220451Y129162D01*
X1220503Y129507D01*
X1220451Y129814D01*
X1220193Y130121D01*
X1219883Y130312D01*
X1219573Y130351D01*
X1219211Y130274D01*
X1218953Y130006D01*
X1218850Y129737D01*
Y129392D01*
G01Y129737D02*
X1218695Y129967D01*
X1218436Y130159D01*
X1218126Y130236D01*
X1217816Y130159D01*
X1217558Y129967D01*
X1217403Y129622D01*
X1217455Y129277D01*
X1217661Y128932D01*
G01X1217403Y132569D02*
X1217506Y132262D01*
X1217765Y132032D01*
X1218075Y131879D01*
X1218488Y131764D01*
X1218953Y131726D01*
X1219418Y131764D01*
X1219831Y131879D01*
X1220141Y132032D01*
X1220400Y132262D01*
X1220503Y132569D01*
X1220400Y132876D01*
X1220141Y133106D01*
X1219831Y133259D01*
X1219418Y133374D01*
X1218953Y133412D01*
X1218488Y133374D01*
X1218075Y133259D01*
X1217765Y133106D01*
X1217506Y132876D01*
X1217403Y132569D01*
G01X1210776Y154138D02*
Y144690D01*
G01X1218383Y151368D02*
Y148168D01*
G01X1212183D02*
Y151368D01*
G01X1218383Y148168D02*
X1212183D01*
G01Y144168D02*
Y147368D01*
G01X1218383Y144168D02*
X1212183D01*
G01X1218383Y147368D02*
Y144168D01*
G01X1212183Y147368D02*
X1218383D01*
G01X1208721Y142847D02*
Y139647D01*
G01X1219300Y135707D02*
X1221522D01*
X1221987Y135860D01*
X1222297Y136167D01*
X1222400Y136550D01*
X1222297Y136933D01*
X1221987Y137240D01*
X1221522Y137393D01*
X1219300D01*
G01X1221780Y138807D02*
X1222142Y139037D01*
X1222348Y139343D01*
X1222400Y139688D01*
X1222348Y139995D01*
X1222090Y140302D01*
X1221780Y140493D01*
X1221470Y140532D01*
X1221108Y140455D01*
X1220850Y140187D01*
X1220747Y139918D01*
Y139573D01*
G01Y139918D02*
X1220592Y140148D01*
X1220333Y140340D01*
X1220023Y140417D01*
X1219713Y140340D01*
X1219455Y140148D01*
X1219300Y139803D01*
X1219352Y139458D01*
X1219558Y139113D01*
G01X1222038Y142098D02*
X1222297Y142367D01*
X1222400Y142673D01*
X1222297Y142980D01*
X1221987Y143248D01*
X1221522Y143440D01*
X1221057Y143517D01*
X1220488D01*
X1220023Y143440D01*
X1219610Y143248D01*
X1219403Y143018D01*
X1219300Y142750D01*
X1219403Y142443D01*
X1219610Y142213D01*
X1219920Y142060D01*
X1220333Y141983D01*
X1220695Y142060D01*
X1221057Y142252D01*
X1221263Y142482D01*
X1221315Y142750D01*
X1221212Y143057D01*
X1220953Y143287D01*
X1220488Y143517D01*
G01X1219817Y145122D02*
X1219507Y145352D01*
X1219352Y145620D01*
X1219300Y145927D01*
X1219403Y146310D01*
X1219662Y146578D01*
X1219972Y146655D01*
X1220282Y146617D01*
X1220540Y146463D01*
X1221057Y145697D01*
X1221418Y145352D01*
X1221935Y145122D01*
X1222400Y145045D01*
Y146655D01*
G01X1209068Y155600D02*
X1208761Y155652D01*
X1208493Y155858D01*
X1208263Y156168D01*
X1208110Y156530D01*
X1208033Y156943D01*
Y157357D01*
X1208110Y157770D01*
X1208263Y158132D01*
X1208493Y158442D01*
X1208761Y158648D01*
X1209068Y158700D01*
X1209375Y158648D01*
X1209643Y158442D01*
X1209873Y158132D01*
X1210026Y157770D01*
X1210103Y157357D01*
Y156943D01*
X1210026Y156530D01*
X1209873Y156168D01*
X1209643Y155858D01*
X1209375Y155652D01*
X1209068Y155600D01*
G01X1209375Y156427D02*
X1209835Y155600D01*
G01X1211440Y158183D02*
X1211670Y158493D01*
X1211938Y158648D01*
X1212245Y158700D01*
X1212628Y158597D01*
X1212896Y158338D01*
X1212973Y158028D01*
X1212935Y157718D01*
X1212781Y157460D01*
X1212015Y156943D01*
X1211670Y156582D01*
X1211440Y156065D01*
X1211363Y155600D01*
X1212973D01*
G01X1214540Y158183D02*
X1214770Y158493D01*
X1215038Y158648D01*
X1215345Y158700D01*
X1215728Y158597D01*
X1215996Y158338D01*
X1216073Y158028D01*
X1216035Y157718D01*
X1215881Y157460D01*
X1215115Y156943D01*
X1214770Y156582D01*
X1214540Y156065D01*
X1214463Y155600D01*
X1216073D01*
G01X1218291D02*
X1218368Y156272D01*
X1218483Y156840D01*
X1218636Y157357D01*
X1218828Y157925D01*
X1219135Y158700D01*
X1217601D01*
G01X1207358Y154138D02*
X1210776D01*
G01X1205358Y152414D02*
X1207358Y154138D01*
G01X1212183Y151368D02*
X1218383D01*
G01X1214748Y178897D02*
Y176944D01*
G01D02*
X1212795D01*
G01X1219119Y179065D02*
Y182265D01*
G01X1225319Y179065D02*
X1219119D01*
G01Y171065D02*
Y174265D01*
G01X1225319Y171065D02*
X1219119D01*
G01Y174265D02*
X1225319D01*
G01X1219119Y175065D02*
Y178265D01*
G01X1225319Y175065D02*
X1219119D01*
G01Y178265D02*
X1225319D01*
G01X1219119Y167065D02*
Y170265D01*
G01X1225319Y167065D02*
X1219119D01*
G01Y170265D02*
X1225319D01*
G01X1216940Y170313D02*
Y167113D01*
G01X1210740Y170313D02*
X1216940D01*
G01X1210740Y167113D02*
Y170313D01*
G01X1216940Y167113D02*
X1210740D01*
G01X1214748Y188756D02*
Y186803D01*
G01X1212795Y188756D02*
X1214748D01*
G01X1219119Y182265D02*
X1225319D01*
G01X1219119Y183065D02*
Y186265D01*
G01X1225319Y183065D02*
X1219119D01*
G01Y186265D02*
X1225319D01*
G01X1219119Y187065D02*
Y190265D01*
G01X1225319Y187065D02*
X1219119D01*
G01Y190265D02*
X1225319D01*
G01X1219119Y194265D02*
X1225319D01*
G01X1219119Y191065D02*
Y194265D01*
G01X1225319Y191065D02*
X1219119D01*
G01X1211795Y195020D02*
Y198220D01*
G01X1217995Y195020D02*
X1211795D01*
G01X1217995Y198220D02*
Y195020D01*
G01X1219119Y195065D02*
Y198265D01*
G01X1225319Y195065D02*
X1219119D01*
G01X1219214Y202464D02*
X1225414D01*
Y199264D01*
X1219214D01*
Y202464D01*
G01X1211795Y198220D02*
X1217995D01*
G01X1219119Y198265D02*
X1225319D01*
G01X1219214Y207264D02*
Y210464D01*
G01X1225414Y207264D02*
X1219214D01*
G01Y210464D02*
X1225414D01*
G01X1219214Y206464D02*
X1225414D01*
G01X1219214Y203264D02*
Y206464D01*
G01X1225414Y203264D02*
X1219214D01*
G01Y214464D02*
X1225414D01*
Y211264D01*
X1219214D01*
Y214464D01*
G01X1205395Y232621D02*
Y226621D01*
G01X1219214Y215264D02*
Y218464D01*
G01X1225414Y215264D02*
X1219214D01*
G01Y218464D02*
X1225414D01*
G01X1219214Y220264D02*
Y223464D01*
G01X1225414Y220264D02*
X1219214D01*
G01Y223464D02*
X1225414D01*
G01X1219211Y227319D02*
X1225411D01*
Y224119D01*
X1219211D01*
Y227319D01*
G01X1216930Y234813D02*
Y250325D01*
G01X1205263Y264210D02*
Y258010D01*
G01X1211974Y264635D02*
X1227486D01*
G01X1211974Y295727D02*
Y264635D01*
G01X1210342Y273701D02*
X1207142D01*
G01X1210342Y279901D02*
Y273701D01*
G01X1207142D02*
Y279901D01*
G01D02*
X1210342D01*
G01X1209000Y282633D02*
X1205900D01*
Y283553D01*
X1206055Y283860D01*
X1206417Y284090D01*
X1206830Y284167D01*
X1207243Y284090D01*
X1207553Y283898D01*
X1207708Y283553D01*
Y282633D01*
G01X1205900Y285657D02*
X1208122D01*
X1208587Y285810D01*
X1208897Y286117D01*
X1209000Y286500D01*
X1208897Y286883D01*
X1208587Y287190D01*
X1208122Y287343D01*
X1205900D01*
G01X1209000Y289600D02*
X1205900D01*
X1206520Y289140D01*
G01X1209000D02*
Y290060D01*
G01Y292700D02*
X1205900D01*
X1206520Y292240D01*
G01X1209000D02*
Y293160D01*
G01Y296260D02*
X1205900D01*
X1208122Y294842D01*
Y296758D01*
G01X1215550Y310800D02*
X1215243Y310852D01*
X1214975Y311058D01*
X1214745Y311368D01*
X1214592Y311730D01*
X1214515Y312143D01*
Y312557D01*
X1214592Y312970D01*
X1214745Y313332D01*
X1214975Y313642D01*
X1215243Y313848D01*
X1215550Y313900D01*
X1215857Y313848D01*
X1216125Y313642D01*
X1216355Y313332D01*
X1216508Y312970D01*
X1216585Y312557D01*
Y312143D01*
X1216508Y311730D01*
X1216355Y311368D01*
X1216125Y311058D01*
X1215857Y310852D01*
X1215550Y310800D01*
G01X1215857Y311627D02*
X1216317Y310800D01*
G01X1217922Y312092D02*
X1218190Y312453D01*
X1218420Y312660D01*
X1218727Y312763D01*
X1218995Y312660D01*
X1219187Y312453D01*
X1219340Y312143D01*
X1219378Y311782D01*
X1219340Y311472D01*
X1219187Y311162D01*
X1218957Y310903D01*
X1218688Y310800D01*
X1218382Y310903D01*
X1218113Y311213D01*
X1217960Y311678D01*
X1217922Y312195D01*
X1217998Y312867D01*
X1218113Y313228D01*
X1218305Y313590D01*
X1218573Y313848D01*
X1218842Y313900D01*
X1219110Y313797D01*
X1219302Y313538D01*
G01X1227486Y295727D02*
X1211974D01*
G01X1220077Y323621D02*
X1217746Y321290D01*
G01X1223186Y323621D02*
X1220077D01*
G01X1212306Y314959D02*
X1223186D01*
G01X1212306Y323621D02*
Y314959D01*
G01X1215415Y323621D02*
X1212306D01*
G01X1217746Y321290D02*
X1215415Y323621D01*
G01X1220316Y327342D02*
X1217116D01*
G01X1220316Y333542D02*
Y327342D01*
G01X1217116D02*
Y333542D01*
G01X1205788Y319473D02*
Y316273D01*
G01X1215158Y340646D02*
Y349110D01*
G01X1228420Y340646D02*
X1215158D01*
G01X1217116Y333542D02*
X1220316D01*
G01X1217107Y353300D02*
Y351078D01*
X1217260Y350613D01*
X1217567Y350303D01*
X1217950Y350200D01*
X1218333Y350303D01*
X1218640Y350613D01*
X1218793Y351078D01*
Y353300D01*
G01X1220207Y350820D02*
X1220437Y350458D01*
X1220743Y350252D01*
X1221088Y350200D01*
X1221395Y350252D01*
X1221702Y350510D01*
X1221893Y350820D01*
X1221932Y351130D01*
X1221855Y351492D01*
X1221587Y351750D01*
X1221318Y351853D01*
X1220973D01*
G01X1221318D02*
X1221548Y352008D01*
X1221740Y352267D01*
X1221817Y352577D01*
X1221740Y352887D01*
X1221548Y353145D01*
X1221203Y353300D01*
X1220858Y353248D01*
X1220513Y353042D01*
G01X1223307Y350665D02*
X1223537Y350407D01*
X1223805Y350252D01*
X1224150Y350200D01*
X1224495Y350303D01*
X1224763Y350510D01*
X1224955Y350872D01*
X1224993Y351285D01*
X1224917Y351698D01*
X1224725Y351957D01*
X1224457Y352163D01*
X1224188Y352215D01*
X1223920Y352163D01*
X1223575Y351957D01*
X1223690Y353300D01*
X1224725D01*
G01X1220289Y349110D02*
X1221789Y347339D01*
G01X1215158Y349110D02*
X1220289D01*
G01X1215305Y366063D02*
Y467925D01*
G01Y470189D02*
Y474925D01*
G01Y484428D02*
Y488909D01*
G01Y477324D02*
Y481824D01*
G01Y491595D02*
Y511832D01*
G01Y521427D02*
Y526164D01*
G01Y514354D02*
Y519080D01*
G01Y535565D02*
Y561873D01*
G01Y528512D02*
Y533125D01*
G01Y564498D02*
Y568894D01*
G01Y585748D02*
Y589992D01*
G01Y578695D02*
Y583103D01*
G01Y571662D02*
Y575968D01*
G01Y599937D02*
Y604181D01*
G01Y592945D02*
Y597230D01*
G01Y639449D02*
Y613993D01*
G01Y607072D02*
Y611439D01*
G01X1216299Y1436969D02*
Y1677520D01*
G01X1226529Y1451871D02*
X1219029D01*
Y1454111D01*
X1219404Y1454858D01*
X1220279Y1455418D01*
X1221279Y1455605D01*
X1222279Y1455418D01*
X1223029Y1454951D01*
X1223404Y1454111D01*
Y1451871D01*
G01X1226529Y1459371D02*
X1219029D01*
Y1461705D01*
X1219404Y1462451D01*
X1219904Y1462918D01*
X1220904Y1463105D01*
X1221904Y1462918D01*
X1222529Y1462358D01*
X1222904Y1461705D01*
Y1459371D01*
G01Y1461705D02*
X1226529Y1463105D01*
G01Y1470605D02*
Y1466871D01*
X1219029D01*
Y1470605D01*
G01X1222654Y1469111D02*
Y1466871D01*
G01X1225529Y1474278D02*
X1226154Y1475025D01*
X1226529Y1475865D01*
Y1476611D01*
X1226154Y1477358D01*
X1225529Y1477918D01*
X1224654Y1478198D01*
X1223779Y1478011D01*
X1223029Y1477545D01*
X1222529Y1476705D01*
X1222279Y1475585D01*
X1221779Y1474931D01*
X1220904Y1474651D01*
X1220029Y1474838D01*
X1219404Y1475305D01*
X1219029Y1475958D01*
Y1476611D01*
X1219279Y1477265D01*
X1219904Y1477825D01*
G01X1225529Y1481778D02*
X1226154Y1482525D01*
X1226529Y1483365D01*
Y1484111D01*
X1226154Y1484858D01*
X1225529Y1485418D01*
X1224654Y1485698D01*
X1223779Y1485511D01*
X1223029Y1485045D01*
X1222529Y1484205D01*
X1222279Y1483085D01*
X1221779Y1482431D01*
X1220904Y1482151D01*
X1220029Y1482338D01*
X1219404Y1482805D01*
X1219029Y1483458D01*
Y1484111D01*
X1219279Y1484765D01*
X1219904Y1485325D01*
G01X1224029Y1490025D02*
Y1492451D01*
G01X1226529Y1496965D02*
X1219029D01*
Y1500511D01*
G01X1222654Y1499205D02*
Y1496965D01*
G01X1219029Y1505118D02*
Y1507358D01*
G01Y1506238D02*
X1226529D01*
G01Y1505118D02*
Y1507358D01*
G01X1219029Y1513738D02*
X1226529D01*
G01X1219029Y1511591D02*
Y1515885D01*
G01X1255655Y1702076D02*
X1221079Y1715189D01*
G01D02*
X1255655Y1728302D01*
G01X1255648Y1760264D02*
X1221072Y1773377D01*
G01D02*
X1255648Y1786490D01*
G01X1254155Y1789796D02*
X1219579Y1802909D01*
G01D02*
X1254155Y1816022D01*
G01X1226536Y-79278D02*
Y-62678D01*
X1236136D01*
Y-79278D01*
X1226536D01*
G01X1231892Y-40228D02*
Y-23628D01*
X1241492D01*
Y-40228D01*
X1231892D01*
G01X1225907Y-21200D02*
Y-18100D01*
X1226673D01*
X1226980Y-18255D01*
X1227210Y-18462D01*
X1227402Y-18772D01*
X1227555Y-19133D01*
X1227593Y-19650D01*
X1227555Y-20167D01*
X1227402Y-20528D01*
X1227210Y-20838D01*
X1226980Y-21045D01*
X1226673Y-21200D01*
X1225907D01*
G01X1230617D02*
X1229083D01*
Y-18100D01*
X1230617D01*
G01X1230003Y-19598D02*
X1229083D01*
G01X1232950Y-21200D02*
Y-18100D01*
X1232490Y-18720D01*
G01Y-21200D02*
X1233410D01*
G01X1235207Y-20580D02*
X1235437Y-20942D01*
X1235743Y-21148D01*
X1236088Y-21200D01*
X1236395Y-21148D01*
X1236702Y-20890D01*
X1236893Y-20580D01*
X1236932Y-20270D01*
X1236855Y-19908D01*
X1236587Y-19650D01*
X1236318Y-19547D01*
X1235973D01*
G01X1236318D02*
X1236548Y-19392D01*
X1236740Y-19133D01*
X1236817Y-18823D01*
X1236740Y-18513D01*
X1236548Y-18255D01*
X1236203Y-18100D01*
X1235858Y-18152D01*
X1235513Y-18358D01*
G01X1239150Y-18100D02*
Y-21200D01*
G01X1238268Y-18100D02*
X1240032D01*
G01X1241100Y-22233D02*
X1243400D01*
G01X1245350Y-21200D02*
Y-18100D01*
X1244890Y-18720D01*
G01Y-21200D02*
X1245810D01*
G01X1231300Y68307D02*
X1233522D01*
X1233987Y68460D01*
X1234297Y68767D01*
X1234400Y69150D01*
X1234297Y69533D01*
X1233987Y69840D01*
X1233522Y69993D01*
X1231300D01*
G01X1234400Y72250D02*
X1231300D01*
X1231920Y71790D01*
G01X1234400D02*
Y72710D01*
G01X1233780Y74507D02*
X1234142Y74737D01*
X1234348Y75043D01*
X1234400Y75388D01*
X1234348Y75695D01*
X1234090Y76002D01*
X1233780Y76193D01*
X1233470Y76232D01*
X1233108Y76155D01*
X1232850Y75887D01*
X1232747Y75618D01*
Y75273D01*
G01Y75618D02*
X1232592Y75848D01*
X1232333Y76040D01*
X1232023Y76117D01*
X1231713Y76040D01*
X1231455Y75848D01*
X1231300Y75503D01*
X1231352Y75158D01*
X1231558Y74813D01*
G01X1233108Y77722D02*
X1232747Y77990D01*
X1232540Y78220D01*
X1232437Y78527D01*
X1232540Y78795D01*
X1232747Y78987D01*
X1233057Y79140D01*
X1233418Y79178D01*
X1233728Y79140D01*
X1234038Y78987D01*
X1234297Y78757D01*
X1234400Y78488D01*
X1234297Y78182D01*
X1233987Y77913D01*
X1233522Y77760D01*
X1233005Y77722D01*
X1232333Y77798D01*
X1231972Y77913D01*
X1231610Y78105D01*
X1231352Y78373D01*
X1231300Y78642D01*
X1231403Y78910D01*
X1231662Y79102D01*
G01X1229765Y79047D02*
Y67523D01*
G01X1224458Y59613D02*
Y56413D01*
G01X1228617Y87204D02*
X1225417D01*
G01X1228617Y93404D02*
Y87204D01*
G01X1225417Y93404D02*
X1228617D01*
G01X1225417Y87204D02*
Y93404D01*
G01X1232524Y87299D02*
X1229324D01*
G01X1232524Y93499D02*
Y87299D01*
G01X1229324Y93499D02*
X1232524D01*
G01X1229324Y87299D02*
Y93499D01*
G01X1224668Y87276D02*
X1221468D01*
G01X1224668Y93476D02*
Y87276D01*
G01X1221468Y93476D02*
X1224668D01*
G01X1221468Y87276D02*
Y93476D01*
G01X1221900Y98707D02*
X1224122D01*
X1224587Y98860D01*
X1224897Y99167D01*
X1225000Y99550D01*
X1224897Y99933D01*
X1224587Y100240D01*
X1224122Y100393D01*
X1221900D01*
G01X1225000Y103110D02*
X1221900D01*
X1224122Y101692D01*
Y103608D01*
G01X1225000Y105750D02*
X1221900D01*
X1222520Y105290D01*
G01X1225000D02*
Y106210D01*
G01X1221900Y108850D02*
X1222003Y108543D01*
X1222262Y108313D01*
X1222572Y108160D01*
X1222985Y108045D01*
X1223450Y108007D01*
X1223915Y108045D01*
X1224328Y108160D01*
X1224638Y108313D01*
X1224897Y108543D01*
X1225000Y108850D01*
X1224897Y109157D01*
X1224638Y109387D01*
X1224328Y109540D01*
X1223915Y109655D01*
X1223450Y109693D01*
X1222985Y109655D01*
X1222572Y109540D01*
X1222262Y109387D01*
X1222003Y109157D01*
X1221900Y108850D01*
G01X1236879Y109424D02*
X1240079D01*
G01X1236879Y103224D02*
Y109424D01*
G01X1240079Y103224D02*
X1236879D01*
G01X1221959Y111951D02*
Y118151D01*
G01X1225159Y111951D02*
X1221959D01*
G01X1225159Y118151D02*
Y111951D01*
G01X1232879Y109424D02*
X1236079D01*
G01X1232879Y103224D02*
Y109424D01*
G01X1236079Y103224D02*
X1232879D01*
G01X1236079Y109424D02*
Y103224D01*
G01X1228879Y109424D02*
X1232079D01*
G01X1228879Y103224D02*
Y109424D01*
G01X1232079Y103224D02*
X1228879D01*
G01X1232079Y109424D02*
Y103224D01*
G01X1227333Y111734D02*
Y123508D01*
G01X1237095Y111734D02*
X1227333D01*
G01X1237095Y123508D02*
Y111734D01*
G01X1238104Y126223D02*
X1234904D01*
G01Y132423D02*
X1238104D01*
G01X1234904Y126223D02*
Y132423D01*
G01X1228104Y126223D02*
X1224904D01*
G01X1228104Y132423D02*
Y126223D01*
G01X1224904Y132423D02*
X1228104D01*
G01X1224904Y126223D02*
Y132423D01*
G01X1221959Y118151D02*
X1225159D01*
G01X1230904Y132423D02*
X1234104D01*
G01X1230904Y126223D02*
Y132423D01*
G01X1234104Y126223D02*
X1230904D01*
G01X1234104Y132423D02*
Y126223D01*
G01X1227333Y123508D02*
X1237095D01*
G01X1227293Y146229D02*
X1224093D01*
G01X1227293Y152429D02*
Y146229D01*
G01X1224093D02*
Y152429D01*
G01X1225783Y144395D02*
Y135095D01*
G01X1236383Y144395D02*
X1225783D01*
G01X1236383Y134995D02*
Y144395D01*
G01X1225783Y134995D02*
X1236383D01*
G01X1224093Y152429D02*
X1227293D01*
G01X1224093Y159540D02*
X1227293D01*
G01X1224093Y153340D02*
Y159540D01*
G01X1227293Y153340D02*
X1224093D01*
G01X1227293Y159540D02*
Y153340D01*
G01X1234006Y149950D02*
Y165304D01*
G01X1246684Y149950D02*
X1234006D01*
G01X1234203Y165304D02*
X1246684D01*
G01X1230783Y179400D02*
Y182500D01*
X1231703D01*
X1232010Y182345D01*
X1232240Y181983D01*
X1232317Y181570D01*
X1232240Y181157D01*
X1232048Y180847D01*
X1231703Y180692D01*
X1230783D01*
G01X1233807Y179400D02*
Y182500D01*
X1234573D01*
X1234880Y182345D01*
X1235110Y182138D01*
X1235302Y181828D01*
X1235455Y181467D01*
X1235493Y180950D01*
X1235455Y180433D01*
X1235302Y180072D01*
X1235110Y179762D01*
X1234880Y179555D01*
X1234573Y179400D01*
X1233807D01*
G01X1237673D02*
X1237750Y180072D01*
X1237865Y180640D01*
X1238018Y181157D01*
X1238210Y181725D01*
X1238517Y182500D01*
X1236983D01*
G01X1240007Y179865D02*
X1240237Y179607D01*
X1240505Y179452D01*
X1240850Y179400D01*
X1241195Y179503D01*
X1241463Y179710D01*
X1241655Y180072D01*
X1241693Y180485D01*
X1241617Y180898D01*
X1241425Y181157D01*
X1241157Y181363D01*
X1240888Y181415D01*
X1240620Y181363D01*
X1240275Y181157D01*
X1240390Y182500D01*
X1241425D01*
G01X1225319Y182265D02*
Y179065D01*
G01Y174265D02*
Y171065D01*
G01Y178265D02*
Y175065D01*
G01Y170265D02*
Y167065D01*
G01X1226887Y189435D02*
X1229127D01*
G01X1227914Y191060D02*
Y187810D01*
G01X1230528Y195583D02*
X1260087D01*
G01X1230528Y184087D02*
Y195583D01*
G01X1260087Y184087D02*
X1230528D01*
G01X1249504Y197645D02*
X1237504D01*
G01D02*
Y203645D01*
G01X1225319Y186265D02*
Y183065D01*
G01Y190265D02*
Y187065D01*
G01Y194265D02*
Y191065D01*
G01Y198265D02*
Y195065D01*
G01X1237504Y203645D02*
X1249504D01*
G01X1230681Y204506D02*
Y216506D01*
G01X1236681Y204506D02*
X1230681D01*
G01X1236681Y216506D02*
Y204506D01*
G01X1237481Y208306D02*
Y214506D01*
G01X1240681Y208306D02*
X1237481D01*
G01X1225414Y210464D02*
Y207264D01*
G01Y206464D02*
Y203264D01*
G01X1230681Y216506D02*
X1236681D01*
G01X1237481Y214506D02*
X1240681D01*
G01X1225414Y218464D02*
Y215264D01*
G01Y223464D02*
Y220264D01*
G01X1233449Y243678D02*
X1239649D01*
G01X1233449Y240478D02*
Y243678D01*
G01X1239649Y240478D02*
X1233449D01*
G01X1229479Y246771D02*
Y249971D01*
G01X1235679Y246771D02*
X1229479D01*
G01X1235679Y249971D02*
Y246771D01*
G01X1229479Y249971D02*
X1235679D01*
G01Y253971D02*
Y250771D01*
G01X1229479Y253971D02*
X1235679D01*
G01X1229479Y250771D02*
Y253971D01*
G01X1235679Y250771D02*
X1229479D01*
G01X1231800Y264583D02*
X1228700D01*
Y265503D01*
X1228855Y265810D01*
X1229217Y266040D01*
X1229630Y266117D01*
X1230043Y266040D01*
X1230353Y265848D01*
X1230508Y265503D01*
Y264583D01*
G01X1231800Y267607D02*
X1228700D01*
Y268373D01*
X1228855Y268680D01*
X1229062Y268910D01*
X1229372Y269102D01*
X1229733Y269255D01*
X1230250Y269293D01*
X1230767Y269255D01*
X1231128Y269102D01*
X1231438Y268910D01*
X1231645Y268680D01*
X1231800Y268373D01*
Y267607D01*
G01Y271550D02*
X1228700D01*
X1229320Y271090D01*
G01X1231800D02*
Y272010D01*
G01X1228700Y274650D02*
X1228803Y274343D01*
X1229062Y274113D01*
X1229372Y273960D01*
X1229785Y273845D01*
X1230250Y273807D01*
X1230715Y273845D01*
X1231128Y273960D01*
X1231438Y274113D01*
X1231697Y274343D01*
X1231800Y274650D01*
X1231697Y274957D01*
X1231438Y275187D01*
X1231128Y275340D01*
X1230715Y275455D01*
X1230250Y275493D01*
X1229785Y275455D01*
X1229372Y275340D01*
X1229062Y275187D01*
X1228803Y274957D01*
X1228700Y274650D01*
G01X1231438Y277098D02*
X1231697Y277367D01*
X1231800Y277673D01*
X1231697Y277980D01*
X1231387Y278248D01*
X1230922Y278440D01*
X1230457Y278517D01*
X1229888D01*
X1229423Y278440D01*
X1229010Y278248D01*
X1228803Y278018D01*
X1228700Y277750D01*
X1228803Y277443D01*
X1229010Y277213D01*
X1229320Y277060D01*
X1229733Y276983D01*
X1230095Y277060D01*
X1230457Y277252D01*
X1230663Y277482D01*
X1230715Y277750D01*
X1230612Y278057D01*
X1230353Y278287D01*
X1229888Y278517D01*
G01X1227486Y264635D02*
Y295727D01*
G01X1236530Y308252D02*
X1242730D01*
G01X1236530Y305052D02*
Y308252D01*
G01X1242730Y305052D02*
X1236530D01*
G01X1228036Y310215D02*
X1224836D01*
G01X1228036Y316415D02*
Y310215D01*
G01X1224836D02*
Y316415D01*
G01X1231100Y309749D02*
Y324749D01*
G01X1244100Y309749D02*
X1231100D01*
G01X1223186Y314959D02*
Y323621D01*
G01X1228124Y326084D02*
X1221524D01*
G01X1229624Y328584D02*
X1228124Y326084D01*
G01X1231124D02*
X1229624Y328584D01*
G01X1237724Y326084D02*
X1231124D01*
G01X1221524D02*
Y339084D01*
G01X1224836Y316415D02*
X1228036D01*
G01X1224836Y323415D02*
X1228036D01*
G01X1224836Y317215D02*
Y323415D01*
G01X1228036Y317215D02*
X1224836D01*
G01X1228036Y323415D02*
Y317215D01*
G01X1231100Y324749D02*
X1244100D01*
G01X1228420Y349110D02*
Y340646D01*
G01X1221524Y339084D02*
X1237724D01*
G01X1229989Y340794D02*
Y346994D01*
G01X1233189Y340794D02*
X1229989D01*
G01X1233189Y346994D02*
Y340794D01*
G01X1233989D02*
Y346994D01*
G01X1237189Y340794D02*
X1233989D01*
G01X1237189Y346994D02*
Y340794D01*
G01X1223289Y349110D02*
X1228420D01*
G01X1221789Y347339D02*
X1223289Y349110D01*
G01X1229981Y349250D02*
Y352450D01*
G01X1236181Y349250D02*
X1229981D01*
G01X1236181Y352450D02*
Y349250D01*
G01X1229981Y352450D02*
X1236181D01*
G01X1229989Y346994D02*
X1233189D01*
G01X1233989D02*
X1237189D01*
G01X1234722Y429437D02*
Y417437D01*
G01X1228722D02*
Y429437D01*
G01X1234722Y417437D02*
X1228722D01*
G01Y429437D02*
X1234722D01*
G01X1228722Y436931D02*
Y448931D01*
G01X1234722Y436931D02*
X1228722D01*
G01X1234722Y448931D02*
Y436931D01*
G01X1228722Y448931D02*
X1234722D01*
G01X1228158Y540312D02*
Y543512D01*
G01X1234358Y540312D02*
X1228158D01*
G01X1234358Y543512D02*
Y540312D01*
G01X1228158Y543512D02*
X1234358D01*
G01X1235858Y554812D02*
X1239058D01*
G01X1235858Y548612D02*
Y554812D01*
G01X1239058Y548612D02*
X1235858D01*
G01X1234358Y547512D02*
Y544312D01*
G01X1228158Y547512D02*
X1234358D01*
G01X1228158Y544312D02*
Y547512D01*
G01X1234358Y544312D02*
X1228158D01*
G01Y621312D02*
Y624512D01*
G01X1234358Y621312D02*
X1228158D01*
G01X1234358Y624512D02*
Y621312D01*
G01X1228158Y624512D02*
X1234358D01*
G01Y628512D02*
Y625312D01*
G01X1228158Y628512D02*
X1234358D01*
G01X1228158Y625312D02*
Y628512D01*
G01X1234358Y625312D02*
X1228158D01*
G01X1229883Y866100D02*
Y863000D01*
X1231417D01*
G01X1234517D02*
X1232983D01*
Y866100D01*
X1234517D01*
G01X1233903Y864602D02*
X1232983D01*
G01X1236007Y863000D02*
Y866100D01*
X1236773D01*
X1237080Y865945D01*
X1237310Y865738D01*
X1237502Y865428D01*
X1237655Y865067D01*
X1237693Y864550D01*
X1237655Y864033D01*
X1237502Y863672D01*
X1237310Y863362D01*
X1237080Y863155D01*
X1236773Y863000D01*
X1236007D01*
G01X1238800Y861967D02*
X1241100D01*
G01X1242207Y863465D02*
X1242437Y863207D01*
X1242705Y863052D01*
X1243050Y863000D01*
X1243395Y863103D01*
X1243663Y863310D01*
X1243855Y863672D01*
X1243893Y864085D01*
X1243817Y864498D01*
X1243625Y864757D01*
X1243357Y864963D01*
X1243088Y865015D01*
X1242820Y864963D01*
X1242475Y864757D01*
X1242590Y866100D01*
X1243625D01*
G01X1229883Y860600D02*
Y857500D01*
X1231417D01*
G01X1234517D02*
X1232983D01*
Y860600D01*
X1234517D01*
G01X1233903Y859102D02*
X1232983D01*
G01X1236007Y857500D02*
Y860600D01*
X1236773D01*
X1237080Y860445D01*
X1237310Y860238D01*
X1237502Y859928D01*
X1237655Y859567D01*
X1237693Y859050D01*
X1237655Y858533D01*
X1237502Y858172D01*
X1237310Y857862D01*
X1237080Y857655D01*
X1236773Y857500D01*
X1236007D01*
G01X1238800Y856467D02*
X1241100D01*
G01X1242322Y858792D02*
X1242590Y859153D01*
X1242820Y859360D01*
X1243127Y859463D01*
X1243395Y859360D01*
X1243587Y859153D01*
X1243740Y858843D01*
X1243778Y858482D01*
X1243740Y858172D01*
X1243587Y857862D01*
X1243357Y857603D01*
X1243088Y857500D01*
X1242782Y857603D01*
X1242513Y857913D01*
X1242360Y858378D01*
X1242322Y858895D01*
X1242398Y859567D01*
X1242513Y859928D01*
X1242705Y860290D01*
X1242973Y860548D01*
X1243242Y860600D01*
X1243510Y860497D01*
X1243702Y860238D01*
G01X1229883Y855600D02*
Y852500D01*
X1231417D01*
G01X1234517D02*
X1232983D01*
Y855600D01*
X1234517D01*
G01X1233903Y854102D02*
X1232983D01*
G01X1236007Y852500D02*
Y855600D01*
X1236773D01*
X1237080Y855445D01*
X1237310Y855238D01*
X1237502Y854928D01*
X1237655Y854567D01*
X1237693Y854050D01*
X1237655Y853533D01*
X1237502Y853172D01*
X1237310Y852862D01*
X1237080Y852655D01*
X1236773Y852500D01*
X1236007D01*
G01X1238800Y851467D02*
X1241100D01*
G01X1242973Y852500D02*
X1243050Y853172D01*
X1243165Y853740D01*
X1243318Y854257D01*
X1243510Y854825D01*
X1243817Y855600D01*
X1242283D01*
G01X1229883Y882100D02*
Y879000D01*
X1231417D01*
G01X1234517D02*
X1232983D01*
Y882100D01*
X1234517D01*
G01X1233903Y880602D02*
X1232983D01*
G01X1236007Y879000D02*
Y882100D01*
X1236773D01*
X1237080Y881945D01*
X1237310Y881738D01*
X1237502Y881428D01*
X1237655Y881067D01*
X1237693Y880550D01*
X1237655Y880033D01*
X1237502Y879672D01*
X1237310Y879362D01*
X1237080Y879155D01*
X1236773Y879000D01*
X1236007D01*
G01X1238800Y877967D02*
X1241100D01*
G01X1242322Y881583D02*
X1242552Y881893D01*
X1242820Y882048D01*
X1243127Y882100D01*
X1243510Y881997D01*
X1243778Y881738D01*
X1243855Y881428D01*
X1243817Y881118D01*
X1243663Y880860D01*
X1242897Y880343D01*
X1242552Y879982D01*
X1242322Y879465D01*
X1242245Y879000D01*
X1243855D01*
G01X1229883Y876600D02*
Y873500D01*
X1231417D01*
G01X1234517D02*
X1232983D01*
Y876600D01*
X1234517D01*
G01X1233903Y875102D02*
X1232983D01*
G01X1236007Y873500D02*
Y876600D01*
X1236773D01*
X1237080Y876445D01*
X1237310Y876238D01*
X1237502Y875928D01*
X1237655Y875567D01*
X1237693Y875050D01*
X1237655Y874533D01*
X1237502Y874172D01*
X1237310Y873862D01*
X1237080Y873655D01*
X1236773Y873500D01*
X1236007D01*
G01X1238800Y872467D02*
X1241100D01*
G01X1242207Y874120D02*
X1242437Y873758D01*
X1242743Y873552D01*
X1243088Y873500D01*
X1243395Y873552D01*
X1243702Y873810D01*
X1243893Y874120D01*
X1243932Y874430D01*
X1243855Y874792D01*
X1243587Y875050D01*
X1243318Y875153D01*
X1242973D01*
G01X1243318D02*
X1243548Y875308D01*
X1243740Y875567D01*
X1243817Y875877D01*
X1243740Y876187D01*
X1243548Y876445D01*
X1243203Y876600D01*
X1242858Y876548D01*
X1242513Y876342D01*
G01X1229883Y871100D02*
Y868000D01*
X1231417D01*
G01X1234517D02*
X1232983D01*
Y871100D01*
X1234517D01*
G01X1233903Y869602D02*
X1232983D01*
G01X1236007Y868000D02*
Y871100D01*
X1236773D01*
X1237080Y870945D01*
X1237310Y870738D01*
X1237502Y870428D01*
X1237655Y870067D01*
X1237693Y869550D01*
X1237655Y869033D01*
X1237502Y868672D01*
X1237310Y868362D01*
X1237080Y868155D01*
X1236773Y868000D01*
X1236007D01*
G01X1238800Y866967D02*
X1241100D01*
G01X1243510Y868000D02*
Y871100D01*
X1242092Y868878D01*
X1244008D01*
G01X1229883Y892100D02*
Y889000D01*
X1231417D01*
G01X1234517D02*
X1232983D01*
Y892100D01*
X1234517D01*
G01X1233903Y890602D02*
X1232983D01*
G01X1236007Y889000D02*
Y892100D01*
X1236773D01*
X1237080Y891945D01*
X1237310Y891738D01*
X1237502Y891428D01*
X1237655Y891067D01*
X1237693Y890550D01*
X1237655Y890033D01*
X1237502Y889672D01*
X1237310Y889362D01*
X1237080Y889155D01*
X1236773Y889000D01*
X1236007D01*
G01X1238800Y887967D02*
X1241100D01*
G01X1243050Y892100D02*
X1242743Y891997D01*
X1242513Y891738D01*
X1242360Y891428D01*
X1242245Y891015D01*
X1242207Y890550D01*
X1242245Y890085D01*
X1242360Y889672D01*
X1242513Y889362D01*
X1242743Y889103D01*
X1243050Y889000D01*
X1243357Y889103D01*
X1243587Y889362D01*
X1243740Y889672D01*
X1243855Y890085D01*
X1243893Y890550D01*
X1243855Y891015D01*
X1243740Y891428D01*
X1243587Y891738D01*
X1243357Y891997D01*
X1243050Y892100D01*
G01X1229883Y887100D02*
Y884000D01*
X1231417D01*
G01X1234517D02*
X1232983D01*
Y887100D01*
X1234517D01*
G01X1233903Y885602D02*
X1232983D01*
G01X1236007Y884000D02*
Y887100D01*
X1236773D01*
X1237080Y886945D01*
X1237310Y886738D01*
X1237502Y886428D01*
X1237655Y886067D01*
X1237693Y885550D01*
X1237655Y885033D01*
X1237502Y884672D01*
X1237310Y884362D01*
X1237080Y884155D01*
X1236773Y884000D01*
X1236007D01*
G01X1238800Y882967D02*
X1241100D01*
G01X1243050Y884000D02*
Y887100D01*
X1242590Y886480D01*
G01Y884000D02*
X1243510D01*
G01X1235738Y1069150D02*
G03X1298621Y1066535I31387J-2615D01*
G01Y1263386D02*
G03X1235685Y1261510I-31496J0D01*
G01X1228110Y1689331D02*
Y1425158D01*
G01X1237282Y1602478D02*
X1238082Y1602978D01*
X1238615Y1603578D01*
X1238882Y1604278D01*
X1238615Y1605078D01*
X1238082Y1605678D01*
X1237282Y1606278D01*
X1236215Y1606478D01*
X1230882D01*
G01X1238882Y1612278D02*
X1237149Y1612478D01*
X1235682Y1612778D01*
X1234349Y1613178D01*
X1232882Y1613678D01*
X1230882Y1614478D01*
Y1610478D01*
G01X1255156Y58432D02*
X1255466Y58624D01*
X1255673Y58854D01*
X1255776Y59122D01*
X1255673Y59429D01*
X1255466Y59659D01*
X1255156Y59889D01*
X1254743Y59966D01*
X1252676D01*
G01X1255776Y62759D02*
X1252676D01*
X1254898Y61341D01*
Y63257D01*
G01X1255776Y65399D02*
X1252676D01*
X1253296Y64939D01*
G01X1255776D02*
Y65859D01*
G01X1248757Y96067D02*
Y99267D01*
G01X1254957Y96067D02*
X1248757D01*
G01Y99267D02*
X1254957D01*
G01X1245496Y122172D02*
Y110172D01*
G01X1239496D02*
Y122172D01*
G01X1245496Y110172D02*
X1239496D01*
G01X1240079Y109424D02*
Y103224D01*
G01X1250773Y108095D02*
Y104895D01*
G01X1244573Y108095D02*
X1250773D01*
G01X1244573Y104895D02*
Y108095D01*
G01X1250773Y104895D02*
X1244573D01*
G01X1251630Y108086D02*
X1254830D01*
G01X1251630Y101886D02*
Y108086D01*
G01X1254830Y101886D02*
X1251630D01*
G01X1244573Y100895D02*
Y104095D01*
G01X1250773Y100895D02*
X1244573D01*
G01X1250773Y104095D02*
Y100895D01*
G01X1244573Y104095D02*
X1250773D01*
G01X1239496Y122172D02*
X1245496D01*
G01X1238104Y132423D02*
Y126223D01*
G01X1242158Y126228D02*
X1238958D01*
G01X1242158Y132428D02*
Y126228D01*
G01X1238958Y132428D02*
X1242158D01*
G01X1238958Y126228D02*
Y132428D01*
G01X1242337Y141337D02*
X1239137D01*
G01X1242337Y147537D02*
Y141337D01*
G01X1239137Y147537D02*
X1242337D01*
G01X1239137Y141337D02*
Y147537D01*
G01X1239002Y133238D02*
Y136438D01*
G01X1245202Y133238D02*
X1239002D01*
G01X1245202Y136438D02*
Y133238D01*
G01X1239002Y136438D02*
X1245202D01*
G01X1245548Y148437D02*
X1248748D01*
G01X1245548Y142237D02*
Y148437D01*
G01X1248748Y142237D02*
X1245548D01*
G01X1248748Y148437D02*
Y142237D01*
G01X1239002Y137238D02*
Y140438D01*
G01X1245202Y137238D02*
X1239002D01*
G01X1245202Y140438D02*
Y137238D01*
G01X1239002Y140438D02*
X1245202D01*
G01X1248100Y153307D02*
X1250322D01*
X1250787Y153460D01*
X1251097Y153767D01*
X1251200Y154150D01*
X1251097Y154533D01*
X1250787Y154840D01*
X1250322Y154993D01*
X1248100D01*
G01X1250580Y156407D02*
X1250942Y156637D01*
X1251148Y156943D01*
X1251200Y157288D01*
X1251148Y157595D01*
X1250890Y157902D01*
X1250580Y158093D01*
X1250270Y158132D01*
X1249908Y158055D01*
X1249650Y157787D01*
X1249547Y157518D01*
Y157173D01*
G01Y157518D02*
X1249392Y157748D01*
X1249133Y157940D01*
X1248823Y158017D01*
X1248513Y157940D01*
X1248255Y157748D01*
X1248100Y157403D01*
X1248152Y157058D01*
X1248358Y156713D01*
G01X1251200Y160273D02*
X1250528Y160350D01*
X1249960Y160465D01*
X1249443Y160618D01*
X1248875Y160810D01*
X1248100Y161117D01*
Y159583D01*
G01X1251200Y163373D02*
X1250528Y163450D01*
X1249960Y163565D01*
X1249443Y163718D01*
X1248875Y163910D01*
X1248100Y164217D01*
Y162683D01*
G01X1246684Y165304D02*
Y149950D01*
G01X1249504Y203645D02*
Y197645D01*
G01X1240681Y214506D02*
Y208306D01*
G01X1247457Y208464D02*
Y205264D01*
G01X1241257Y208464D02*
X1247457D01*
G01X1241257Y205264D02*
Y208464D01*
G01X1247457Y205264D02*
X1241257D01*
G01X1242287Y226801D02*
X1254491D01*
Y211497D01*
X1242287D01*
Y226801D01*
G01X1237847Y245521D02*
Y254969D01*
G01X1248683Y245521D02*
X1237847D01*
G01X1248683Y254969D02*
Y245521D01*
G01X1241423Y231334D02*
X1238223D01*
G01X1241423Y237534D02*
Y231334D01*
G01X1238223Y237534D02*
X1241423D01*
G01X1238223Y231334D02*
Y237534D01*
G01X1246950Y231446D02*
X1243750D01*
G01X1246950Y237646D02*
Y231446D01*
G01X1243750Y237646D02*
X1246950D01*
G01X1243750Y231446D02*
Y237646D01*
G01X1239649Y243678D02*
Y240478D01*
G01X1250825Y231434D02*
X1247625D01*
G01X1250825Y237634D02*
Y231434D01*
G01X1247625Y237634D02*
X1250825D01*
G01X1247625Y231434D02*
Y237634D01*
G01X1251860Y237659D02*
X1255060D01*
G01X1251860Y231459D02*
Y237659D01*
G01X1255060Y231459D02*
X1251860D01*
G01X1250486Y240081D02*
Y243281D01*
G01X1256686Y240081D02*
X1250486D01*
G01Y243281D02*
X1256686D01*
G01X1246628Y243678D02*
Y240478D01*
G01X1240428Y243678D02*
X1246628D01*
G01X1240428Y240478D02*
Y243678D01*
G01X1246628Y240478D02*
X1240428D01*
G01X1243182Y256331D02*
X1242875Y256383D01*
X1242607Y256589D01*
X1242377Y256899D01*
X1242224Y257261D01*
X1242147Y257674D01*
Y258088D01*
X1242224Y258501D01*
X1242377Y258863D01*
X1242607Y259173D01*
X1242875Y259379D01*
X1243182Y259431D01*
X1243489Y259379D01*
X1243757Y259173D01*
X1243987Y258863D01*
X1244140Y258501D01*
X1244217Y258088D01*
Y257674D01*
X1244140Y257261D01*
X1243987Y256899D01*
X1243757Y256589D01*
X1243489Y256383D01*
X1243182Y256331D01*
G01X1243489Y257158D02*
X1243949Y256331D01*
G01X1245554Y258914D02*
X1245784Y259224D01*
X1246052Y259379D01*
X1246359Y259431D01*
X1246742Y259328D01*
X1247010Y259069D01*
X1247087Y258759D01*
X1247049Y258449D01*
X1246895Y258191D01*
X1246129Y257674D01*
X1245784Y257313D01*
X1245554Y256796D01*
X1245477Y256331D01*
X1247087D01*
G01X1249382Y259431D02*
X1249075Y259328D01*
X1248845Y259069D01*
X1248692Y258759D01*
X1248577Y258346D01*
X1248539Y257881D01*
X1248577Y257416D01*
X1248692Y257003D01*
X1248845Y256693D01*
X1249075Y256434D01*
X1249382Y256331D01*
X1249689Y256434D01*
X1249919Y256693D01*
X1250072Y257003D01*
X1250187Y257416D01*
X1250225Y257881D01*
X1250187Y258346D01*
X1250072Y258759D01*
X1249919Y259069D01*
X1249689Y259328D01*
X1249382Y259431D01*
G01X1252405Y256331D02*
X1252482Y257003D01*
X1252597Y257571D01*
X1252750Y258088D01*
X1252942Y258656D01*
X1253249Y259431D01*
X1251715D01*
G01X1245265Y254969D02*
X1248683D01*
G01X1243265Y253245D02*
X1245265Y254969D01*
G01X1241265D02*
X1243265Y253245D01*
G01X1237847Y254969D02*
X1241265D01*
G01X1250090Y252199D02*
X1256290D01*
G01X1250090Y248999D02*
Y252199D01*
G01X1256290Y248999D02*
X1250090D01*
G01X1242730Y308252D02*
Y305052D01*
G01X1245300Y311057D02*
X1247522D01*
X1247987Y311210D01*
X1248297Y311517D01*
X1248400Y311900D01*
X1248297Y312283D01*
X1247987Y312590D01*
X1247522Y312743D01*
X1245300D01*
G01X1247780Y314157D02*
X1248142Y314387D01*
X1248348Y314693D01*
X1248400Y315038D01*
X1248348Y315345D01*
X1248090Y315652D01*
X1247780Y315843D01*
X1247470Y315882D01*
X1247108Y315805D01*
X1246850Y315537D01*
X1246747Y315268D01*
Y314923D01*
G01Y315268D02*
X1246592Y315498D01*
X1246333Y315690D01*
X1246023Y315767D01*
X1245713Y315690D01*
X1245455Y315498D01*
X1245300Y315153D01*
X1245352Y314808D01*
X1245558Y314463D01*
G01X1248400Y318023D02*
X1247728Y318100D01*
X1247160Y318215D01*
X1246643Y318368D01*
X1246075Y318560D01*
X1245300Y318867D01*
Y317333D01*
G01X1244100Y324749D02*
Y309749D01*
G01X1237724Y339084D02*
Y326084D01*
G01X1239300Y330907D02*
X1241522D01*
X1241987Y331060D01*
X1242297Y331367D01*
X1242400Y331750D01*
X1242297Y332133D01*
X1241987Y332440D01*
X1241522Y332593D01*
X1239300D01*
G01X1241780Y334007D02*
X1242142Y334237D01*
X1242348Y334543D01*
X1242400Y334888D01*
X1242348Y335195D01*
X1242090Y335502D01*
X1241780Y335693D01*
X1241470Y335732D01*
X1241108Y335655D01*
X1240850Y335387D01*
X1240747Y335118D01*
Y334773D01*
G01Y335118D02*
X1240592Y335348D01*
X1240333Y335540D01*
X1240023Y335617D01*
X1239713Y335540D01*
X1239455Y335348D01*
X1239300Y335003D01*
X1239352Y334658D01*
X1239558Y334313D01*
G01X1241108Y337222D02*
X1240747Y337490D01*
X1240540Y337720D01*
X1240437Y338027D01*
X1240540Y338295D01*
X1240747Y338487D01*
X1241057Y338640D01*
X1241418Y338678D01*
X1241728Y338640D01*
X1242038Y338487D01*
X1242297Y338257D01*
X1242400Y337988D01*
X1242297Y337682D01*
X1241987Y337413D01*
X1241522Y337260D01*
X1241005Y337222D01*
X1240333Y337298D01*
X1239972Y337413D01*
X1239610Y337605D01*
X1239352Y337873D01*
X1239300Y338142D01*
X1239403Y338410D01*
X1239662Y338602D01*
G01X1255600Y468183D02*
X1252500D01*
Y469103D01*
X1252655Y469410D01*
X1253017Y469640D01*
X1253430Y469717D01*
X1253843Y469640D01*
X1254153Y469448D01*
X1254308Y469103D01*
Y468183D01*
G01X1255600Y471207D02*
X1252500D01*
Y471973D01*
X1252655Y472280D01*
X1252862Y472510D01*
X1253172Y472702D01*
X1253533Y472855D01*
X1254050Y472893D01*
X1254567Y472855D01*
X1254928Y472702D01*
X1255238Y472510D01*
X1255445Y472280D01*
X1255600Y471973D01*
Y471207D01*
G01X1255135Y474307D02*
X1255393Y474537D01*
X1255548Y474805D01*
X1255600Y475150D01*
X1255497Y475495D01*
X1255290Y475763D01*
X1254928Y475955D01*
X1254515Y475993D01*
X1254102Y475917D01*
X1253843Y475725D01*
X1253637Y475457D01*
X1253585Y475188D01*
X1253637Y474920D01*
X1253843Y474575D01*
X1252500Y474690D01*
Y475725D01*
G01X1255135Y477407D02*
X1255393Y477637D01*
X1255548Y477905D01*
X1255600Y478250D01*
X1255497Y478595D01*
X1255290Y478863D01*
X1254928Y479055D01*
X1254515Y479093D01*
X1254102Y479017D01*
X1253843Y478825D01*
X1253637Y478557D01*
X1253585Y478288D01*
X1253637Y478020D01*
X1253843Y477675D01*
X1252500Y477790D01*
Y478825D01*
G01X1239058Y554812D02*
Y548612D01*
G01X1242857Y546900D02*
Y544678D01*
X1243010Y544213D01*
X1243317Y543903D01*
X1243700Y543800D01*
X1244083Y543903D01*
X1244390Y544213D01*
X1244543Y544678D01*
Y546900D01*
G01X1245957Y544420D02*
X1246187Y544058D01*
X1246493Y543852D01*
X1246838Y543800D01*
X1247145Y543852D01*
X1247452Y544110D01*
X1247643Y544420D01*
X1247682Y544730D01*
X1247605Y545092D01*
X1247337Y545350D01*
X1247068Y545453D01*
X1246723D01*
G01X1247068D02*
X1247298Y545608D01*
X1247490Y545867D01*
X1247567Y546177D01*
X1247490Y546487D01*
X1247298Y546745D01*
X1246953Y546900D01*
X1246608Y546848D01*
X1246263Y546642D01*
G01X1250360Y543800D02*
Y546900D01*
X1248942Y544678D01*
X1250858D01*
G01X1253197Y563389D02*
Y548035D01*
G01X1240519D02*
Y563389D01*
G01X1253000Y548035D02*
X1240519D01*
G01Y563389D02*
X1253197D01*
G01X1246807Y853000D02*
Y856100D01*
X1247573D01*
X1247880Y855945D01*
X1248110Y855738D01*
X1248302Y855428D01*
X1248455Y855067D01*
X1248493Y854550D01*
X1248455Y854033D01*
X1248302Y853672D01*
X1248110Y853362D01*
X1247880Y853155D01*
X1247573Y853000D01*
X1246807D01*
G01X1250022Y855583D02*
X1250252Y855893D01*
X1250520Y856048D01*
X1250827Y856100D01*
X1251210Y855997D01*
X1251478Y855738D01*
X1251555Y855428D01*
X1251517Y855118D01*
X1251363Y854860D01*
X1250597Y854343D01*
X1250252Y853982D01*
X1250022Y853465D01*
X1249945Y853000D01*
X1251555D01*
G01X1253850Y856100D02*
X1253543Y855997D01*
X1253313Y855738D01*
X1253160Y855428D01*
X1253045Y855015D01*
X1253007Y854550D01*
X1253045Y854085D01*
X1253160Y853672D01*
X1253313Y853362D01*
X1253543Y853103D01*
X1253850Y853000D01*
X1254157Y853103D01*
X1254387Y853362D01*
X1254540Y853672D01*
X1254655Y854085D01*
X1254693Y854550D01*
X1254655Y855015D01*
X1254540Y855428D01*
X1254387Y855738D01*
X1254157Y855997D01*
X1253850Y856100D01*
G01X1246807Y863000D02*
Y866100D01*
X1247573D01*
X1247880Y865945D01*
X1248110Y865738D01*
X1248302Y865428D01*
X1248455Y865067D01*
X1248493Y864550D01*
X1248455Y864033D01*
X1248302Y863672D01*
X1248110Y863362D01*
X1247880Y863155D01*
X1247573Y863000D01*
X1246807D01*
G01X1250750D02*
Y866100D01*
X1250290Y865480D01*
G01Y863000D02*
X1251210D01*
G01X1253850D02*
X1254118Y863052D01*
X1254425Y863207D01*
X1254617Y863465D01*
X1254693Y863827D01*
X1254617Y864188D01*
X1254387Y864498D01*
X1254042Y864653D01*
X1253658D01*
X1253428Y864757D01*
X1253237Y865015D01*
X1253160Y865377D01*
X1253275Y865738D01*
X1253543Y865997D01*
X1253850Y866100D01*
X1254157Y865997D01*
X1254425Y865738D01*
X1254540Y865377D01*
X1254463Y865015D01*
X1254272Y864757D01*
X1254042Y864653D01*
X1253658D01*
X1253313Y864498D01*
X1253083Y864188D01*
X1253007Y863827D01*
X1253083Y863465D01*
X1253275Y863207D01*
X1253582Y863052D01*
X1253850Y863000D01*
G01X1246807Y858000D02*
Y861100D01*
X1247573D01*
X1247880Y860945D01*
X1248110Y860738D01*
X1248302Y860428D01*
X1248455Y860067D01*
X1248493Y859550D01*
X1248455Y859033D01*
X1248302Y858672D01*
X1248110Y858362D01*
X1247880Y858155D01*
X1247573Y858000D01*
X1246807D01*
G01X1250750D02*
Y861100D01*
X1250290Y860480D01*
G01Y858000D02*
X1251210D01*
G01X1253198Y858362D02*
X1253467Y858103D01*
X1253773Y858000D01*
X1254080Y858103D01*
X1254348Y858413D01*
X1254540Y858878D01*
X1254617Y859343D01*
Y859912D01*
X1254540Y860377D01*
X1254348Y860790D01*
X1254118Y860997D01*
X1253850Y861100D01*
X1253543Y860997D01*
X1253313Y860790D01*
X1253160Y860480D01*
X1253083Y860067D01*
X1253160Y859705D01*
X1253352Y859343D01*
X1253582Y859137D01*
X1253850Y859085D01*
X1254157Y859188D01*
X1254387Y859447D01*
X1254617Y859912D01*
G01X1246807Y873500D02*
Y876600D01*
X1247573D01*
X1247880Y876445D01*
X1248110Y876238D01*
X1248302Y875928D01*
X1248455Y875567D01*
X1248493Y875050D01*
X1248455Y874533D01*
X1248302Y874172D01*
X1248110Y873862D01*
X1247880Y873655D01*
X1247573Y873500D01*
X1246807D01*
G01X1250750D02*
Y876600D01*
X1250290Y875980D01*
G01Y873500D02*
X1251210D01*
G01X1253122Y874792D02*
X1253390Y875153D01*
X1253620Y875360D01*
X1253927Y875463D01*
X1254195Y875360D01*
X1254387Y875153D01*
X1254540Y874843D01*
X1254578Y874482D01*
X1254540Y874172D01*
X1254387Y873862D01*
X1254157Y873603D01*
X1253888Y873500D01*
X1253582Y873603D01*
X1253313Y873913D01*
X1253160Y874378D01*
X1253122Y874895D01*
X1253198Y875567D01*
X1253313Y875928D01*
X1253505Y876290D01*
X1253773Y876548D01*
X1254042Y876600D01*
X1254310Y876497D01*
X1254502Y876238D01*
G01X1246807Y878500D02*
Y881600D01*
X1247573D01*
X1247880Y881445D01*
X1248110Y881238D01*
X1248302Y880928D01*
X1248455Y880567D01*
X1248493Y880050D01*
X1248455Y879533D01*
X1248302Y879172D01*
X1248110Y878862D01*
X1247880Y878655D01*
X1247573Y878500D01*
X1246807D01*
G01X1250750D02*
Y881600D01*
X1250290Y880980D01*
G01Y878500D02*
X1251210D01*
G01X1253007Y878965D02*
X1253237Y878707D01*
X1253505Y878552D01*
X1253850Y878500D01*
X1254195Y878603D01*
X1254463Y878810D01*
X1254655Y879172D01*
X1254693Y879585D01*
X1254617Y879998D01*
X1254425Y880257D01*
X1254157Y880463D01*
X1253888Y880515D01*
X1253620Y880463D01*
X1253275Y880257D01*
X1253390Y881600D01*
X1254425D01*
G01X1246807Y868500D02*
Y871600D01*
X1247573D01*
X1247880Y871445D01*
X1248110Y871238D01*
X1248302Y870928D01*
X1248455Y870567D01*
X1248493Y870050D01*
X1248455Y869533D01*
X1248302Y869172D01*
X1248110Y868862D01*
X1247880Y868655D01*
X1247573Y868500D01*
X1246807D01*
G01X1250750D02*
Y871600D01*
X1250290Y870980D01*
G01Y868500D02*
X1251210D01*
G01X1253773D02*
X1253850Y869172D01*
X1253965Y869740D01*
X1254118Y870257D01*
X1254310Y870825D01*
X1254617Y871600D01*
X1253083D01*
G01X1246807Y883500D02*
Y886600D01*
X1247573D01*
X1247880Y886445D01*
X1248110Y886238D01*
X1248302Y885928D01*
X1248455Y885567D01*
X1248493Y885050D01*
X1248455Y884533D01*
X1248302Y884172D01*
X1248110Y883862D01*
X1247880Y883655D01*
X1247573Y883500D01*
X1246807D01*
G01X1250750D02*
Y886600D01*
X1250290Y885980D01*
G01Y883500D02*
X1251210D01*
G01X1254310D02*
Y886600D01*
X1252892Y884378D01*
X1254808D01*
G01X1246807Y888500D02*
Y891600D01*
X1247573D01*
X1247880Y891445D01*
X1248110Y891238D01*
X1248302Y890928D01*
X1248455Y890567D01*
X1248493Y890050D01*
X1248455Y889533D01*
X1248302Y889172D01*
X1248110Y888862D01*
X1247880Y888655D01*
X1247573Y888500D01*
X1246807D01*
G01X1250750D02*
Y891600D01*
X1250290Y890980D01*
G01Y888500D02*
X1251210D01*
G01X1253007Y889120D02*
X1253237Y888758D01*
X1253543Y888552D01*
X1253888Y888500D01*
X1254195Y888552D01*
X1254502Y888810D01*
X1254693Y889120D01*
X1254732Y889430D01*
X1254655Y889792D01*
X1254387Y890050D01*
X1254118Y890153D01*
X1253773D01*
G01X1254118D02*
X1254348Y890308D01*
X1254540Y890567D01*
X1254617Y890877D01*
X1254540Y891187D01*
X1254348Y891445D01*
X1254003Y891600D01*
X1253658Y891548D01*
X1253313Y891342D01*
G01X1250390Y909216D02*
X1250083Y909268D01*
X1249815Y909474D01*
X1249585Y909784D01*
X1249432Y910146D01*
X1249355Y910559D01*
Y910973D01*
X1249432Y911386D01*
X1249585Y911748D01*
X1249815Y912058D01*
X1250083Y912264D01*
X1250390Y912316D01*
X1250697Y912264D01*
X1250965Y912058D01*
X1251195Y911748D01*
X1251348Y911386D01*
X1251425Y910973D01*
Y910559D01*
X1251348Y910146D01*
X1251195Y909784D01*
X1250965Y909474D01*
X1250697Y909268D01*
X1250390Y909216D01*
G01X1250697Y910043D02*
X1251157Y909216D01*
G01X1253490D02*
Y912316D01*
X1253030Y911696D01*
G01Y909216D02*
X1253950D01*
G01X1256590D02*
Y912316D01*
X1256130Y911696D01*
G01Y909216D02*
X1257050D01*
G01X1258847Y909836D02*
X1259077Y909474D01*
X1259383Y909268D01*
X1259728Y909216D01*
X1260035Y909268D01*
X1260342Y909526D01*
X1260533Y909836D01*
X1260572Y910146D01*
X1260495Y910508D01*
X1260227Y910766D01*
X1259958Y910869D01*
X1259613D01*
G01X1259958D02*
X1260188Y911024D01*
X1260380Y911283D01*
X1260457Y911593D01*
X1260380Y911903D01*
X1260188Y912161D01*
X1259843Y912316D01*
X1259498Y912264D01*
X1259153Y912058D01*
G01X1249807Y899434D02*
Y902534D01*
X1250573D01*
X1250880Y902379D01*
X1251110Y902172D01*
X1251302Y901862D01*
X1251455Y901501D01*
X1251493Y900984D01*
X1251455Y900467D01*
X1251302Y900106D01*
X1251110Y899796D01*
X1250880Y899589D01*
X1250573Y899434D01*
X1249807D01*
G01X1253022Y902017D02*
X1253252Y902327D01*
X1253520Y902482D01*
X1253827Y902534D01*
X1254210Y902431D01*
X1254478Y902172D01*
X1254555Y901862D01*
X1254517Y901552D01*
X1254363Y901294D01*
X1253597Y900777D01*
X1253252Y900416D01*
X1253022Y899899D01*
X1252945Y899434D01*
X1254555D01*
G01X1256850D02*
Y902534D01*
X1256390Y901914D01*
G01Y899434D02*
X1257310D01*
G01X1242519Y1071456D02*
Y1258464D01*
G01X1298621Y1066535D02*
G03X1244677Y1088627I-31496J0D01*
G01X1252528Y1141804D02*
Y1135604D01*
X1249328D01*
Y1141804D01*
X1252528D01*
G01X1246452Y1156532D02*
X1248674D01*
X1249139Y1156685D01*
X1249449Y1156992D01*
X1249552Y1157375D01*
X1249449Y1157758D01*
X1249139Y1158065D01*
X1248674Y1158218D01*
X1246452D01*
G01X1249552Y1160935D02*
X1246452D01*
X1248674Y1159517D01*
Y1161433D01*
G01X1246969Y1162847D02*
X1246659Y1163077D01*
X1246504Y1163345D01*
X1246452Y1163652D01*
X1246555Y1164035D01*
X1246814Y1164303D01*
X1247124Y1164380D01*
X1247434Y1164342D01*
X1247692Y1164188D01*
X1248209Y1163422D01*
X1248570Y1163077D01*
X1249087Y1162847D01*
X1249552Y1162770D01*
Y1164380D01*
G01Y1166598D02*
X1248880Y1166675D01*
X1248312Y1166790D01*
X1247795Y1166943D01*
X1247227Y1167135D01*
X1246452Y1167442D01*
Y1165908D01*
G01X1250518Y1161425D02*
X1251711Y1160525D01*
X1250518Y1159525D01*
G01Y1161525D02*
Y1164625D01*
X1262920D01*
Y1156425D01*
X1250518D01*
Y1159525D01*
G01X1253402Y1180425D02*
Y1174225D01*
X1250202D01*
Y1180425D01*
X1253402D01*
G01X1250830Y1194021D02*
Y1187821D01*
X1247630D01*
Y1194021D01*
X1250830D01*
G01X1251340Y1193976D02*
X1257540D01*
G01X1251340Y1190776D02*
Y1193976D01*
G01X1257540Y1190776D02*
X1251340D01*
G01X1249702Y1197325D02*
Y1203525D01*
X1252902D01*
Y1197325D01*
X1249702D01*
G01X1245057Y1240914D02*
G03X1298621Y1263386I22068J22472D01*
G01X1240951Y1290650D02*
Y1293750D01*
G01X1242561D02*
Y1290650D01*
G01Y1292200D02*
X1240951D01*
G01X1244204Y1291012D02*
X1244473Y1290753D01*
X1244779Y1290650D01*
X1245086Y1290753D01*
X1245354Y1291063D01*
X1245546Y1291528D01*
X1245623Y1291993D01*
Y1292562D01*
X1245546Y1293027D01*
X1245354Y1293440D01*
X1245124Y1293647D01*
X1244856Y1293750D01*
X1244549Y1293647D01*
X1244319Y1293440D01*
X1244166Y1293130D01*
X1244089Y1292717D01*
X1244166Y1292355D01*
X1244358Y1291993D01*
X1244588Y1291787D01*
X1244856Y1291735D01*
X1245163Y1291838D01*
X1245393Y1292097D01*
X1245623Y1292562D01*
G01X1247956Y1293750D02*
X1247649Y1293647D01*
X1247419Y1293388D01*
X1247266Y1293078D01*
X1247151Y1292665D01*
X1247113Y1292200D01*
X1247151Y1291735D01*
X1247266Y1291322D01*
X1247419Y1291012D01*
X1247649Y1290753D01*
X1247956Y1290650D01*
X1248263Y1290753D01*
X1248493Y1291012D01*
X1248646Y1291322D01*
X1248761Y1291735D01*
X1248799Y1292200D01*
X1248761Y1292665D01*
X1248646Y1293078D01*
X1248493Y1293388D01*
X1248263Y1293647D01*
X1247956Y1293750D01*
G01X1246015Y1532942D02*
X1252215D01*
Y1529742D01*
X1246015D01*
Y1532942D01*
G01X1245177Y1564843D02*
X1272933D01*
G01X1245177Y1690040D02*
Y1564843D01*
G01X1272933Y1647992D02*
X1245177D01*
G01X1272933Y1690040D02*
X1245177D01*
G01X1259900Y57756D02*
Y111596D01*
G01X1260196Y58150D02*
Y111596D01*
G01X1266281Y57756D02*
X1259900D01*
G01X1265876Y58150D02*
X1260196D01*
G01X1254957Y99267D02*
Y96067D01*
G01X1260196Y118848D02*
Y114048D01*
G01X1259900Y118848D02*
Y114048D01*
G01X1254830Y108086D02*
Y101886D01*
G01X1260196Y132607D02*
Y128340D01*
G01X1259900Y132607D02*
Y128340D01*
G01Y125781D02*
Y121219D01*
G01X1260196Y125781D02*
Y121219D01*
G01Y152756D02*
Y135490D01*
G01X1259900Y153150D02*
Y135490D01*
G01Y153150D02*
X1266281D01*
G01X1260196Y152756D02*
X1265876D01*
G01X1263627Y189535D02*
X1261201D01*
G01X1260087Y195583D02*
Y184087D01*
G01X1260487Y214398D02*
X1257387D01*
Y215318D01*
X1257542Y215625D01*
X1257904Y215855D01*
X1258317Y215932D01*
X1258730Y215855D01*
X1259040Y215663D01*
X1259195Y215318D01*
Y214398D01*
G01X1257387Y217422D02*
X1259609D01*
X1260074Y217575D01*
X1260384Y217882D01*
X1260487Y218265D01*
X1260384Y218648D01*
X1260074Y218955D01*
X1259609Y219108D01*
X1257387D01*
G01X1259195Y220637D02*
X1258834Y220905D01*
X1258627Y221135D01*
X1258524Y221442D01*
X1258627Y221710D01*
X1258834Y221902D01*
X1259144Y222055D01*
X1259505Y222093D01*
X1259815Y222055D01*
X1260125Y221902D01*
X1260384Y221672D01*
X1260487Y221403D01*
X1260384Y221097D01*
X1260074Y220828D01*
X1259609Y220675D01*
X1259092Y220637D01*
X1258420Y220713D01*
X1258059Y220828D01*
X1257697Y221020D01*
X1257439Y221288D01*
X1257387Y221557D01*
X1257490Y221825D01*
X1257749Y222017D01*
G01X1260125Y223813D02*
X1260384Y224082D01*
X1260487Y224388D01*
X1260384Y224695D01*
X1260074Y224963D01*
X1259609Y225155D01*
X1259144Y225232D01*
X1258575D01*
X1258110Y225155D01*
X1257697Y224963D01*
X1257490Y224733D01*
X1257387Y224465D01*
X1257490Y224158D01*
X1257697Y223928D01*
X1258007Y223775D01*
X1258420Y223698D01*
X1258782Y223775D01*
X1259144Y223967D01*
X1259350Y224197D01*
X1259402Y224465D01*
X1259299Y224772D01*
X1259040Y225002D01*
X1258575Y225232D01*
G01X1259060Y231459D02*
X1255860D01*
G01X1259060Y237659D02*
Y231459D01*
G01X1255860Y237659D02*
X1259060D01*
G01X1255860Y231459D02*
Y237659D01*
G01X1255060D02*
Y231459D01*
G01X1256686Y243281D02*
Y240081D01*
G01X1256290Y252199D02*
Y248999D01*
G01X1257400Y325400D02*
Y328600D01*
G01X1263600Y325400D02*
X1257400D01*
G01X1263600Y328600D02*
Y325400D01*
G01X1257400Y328600D02*
X1263600D01*
G01X1262600Y337600D02*
Y334400D01*
G01X1256400Y337600D02*
X1262600D01*
G01X1256400Y334400D02*
Y337600D01*
G01X1262600Y334400D02*
X1256400D01*
G01X1269716Y388619D02*
X1267763D01*
G01D02*
Y390572D01*
G01X1255059Y384248D02*
X1258259D01*
G01X1255059Y378048D02*
Y384248D01*
G01X1258259Y378048D02*
X1255059D01*
G01X1258259Y384248D02*
Y378048D01*
G01X1263364Y392408D02*
X1260164D01*
G01X1263364Y398608D02*
Y392408D01*
G01X1260164D02*
Y398608D01*
G01X1267059Y384248D02*
X1270259D01*
G01X1267059Y378048D02*
Y384248D01*
G01X1270259Y378048D02*
X1267059D01*
G01X1259059Y384248D02*
X1262259D01*
G01X1259059Y378048D02*
Y384248D01*
G01X1262259Y378048D02*
X1259059D01*
G01X1262259Y384248D02*
Y378048D01*
G01X1263059Y384248D02*
X1266259D01*
G01X1263059Y378048D02*
Y384248D01*
G01X1266259Y378048D02*
X1263059D01*
G01X1266259Y384248D02*
Y378048D01*
G01X1267763Y400431D02*
X1269716D01*
G01X1267763Y398478D02*
Y400431D01*
G01X1263987Y399509D02*
X1261725Y401771D01*
G01X1268371Y403893D02*
X1263987Y399509D01*
G01X1266109Y406155D02*
X1268371Y403893D01*
G01X1261725Y401771D02*
X1266109Y406155D01*
G01X1260164Y398608D02*
X1263364D01*
G01X1265775Y407402D02*
Y413602D01*
G01X1268975Y407402D02*
X1265775D01*
G01X1268975Y413602D02*
Y407402D01*
G01X1254621Y415040D02*
X1285625D01*
G01X1254621Y429840D02*
Y415040D01*
G01X1265775Y413602D02*
X1268975D01*
G01X1285625Y429840D02*
X1254621D01*
G01X1266298Y451934D02*
Y448734D01*
G01X1260098Y451934D02*
X1266298D01*
G01X1260098Y448734D02*
Y451934D01*
G01X1266298Y448734D02*
X1260098D01*
G01X1266298Y459934D02*
Y456734D01*
G01X1260098D02*
Y459934D01*
G01X1266298Y456734D02*
X1260098D01*
G01Y452734D02*
Y455934D01*
G01X1266298Y452734D02*
X1260098D01*
G01X1266298Y455934D02*
Y452734D01*
G01X1260098Y455934D02*
X1266298D01*
G01X1280787Y451163D02*
X1269013D01*
G01D02*
Y460925D01*
G01X1262202Y464270D02*
Y466696D01*
G01X1268250Y467810D02*
X1256754D01*
G01X1268250Y497369D02*
Y467810D01*
G01X1256754D02*
Y497369D01*
G01X1260098Y459934D02*
X1266298D01*
G01X1254433Y461000D02*
Y464100D01*
X1255353D01*
X1255660Y463945D01*
X1255890Y463583D01*
X1255967Y463170D01*
X1255890Y462757D01*
X1255698Y462447D01*
X1255353Y462292D01*
X1254433D01*
G01X1257457Y464100D02*
Y461878D01*
X1257610Y461413D01*
X1257917Y461103D01*
X1258300Y461000D01*
X1258683Y461103D01*
X1258990Y461413D01*
X1259143Y461878D01*
Y464100D01*
G01X1261400Y461000D02*
Y464100D01*
X1260940Y463480D01*
G01Y461000D02*
X1261860D01*
G01X1263772Y463583D02*
X1264002Y463893D01*
X1264270Y464048D01*
X1264577Y464100D01*
X1264960Y463997D01*
X1265228Y463738D01*
X1265305Y463428D01*
X1265267Y463118D01*
X1265113Y462860D01*
X1264347Y462343D01*
X1264002Y461982D01*
X1263772Y461465D01*
X1263695Y461000D01*
X1265305D01*
G01X1267600Y464100D02*
X1267293Y463997D01*
X1267063Y463738D01*
X1266910Y463428D01*
X1266795Y463015D01*
X1266757Y462550D01*
X1266795Y462085D01*
X1266910Y461672D01*
X1267063Y461362D01*
X1267293Y461103D01*
X1267600Y461000D01*
X1267907Y461103D01*
X1268137Y461362D01*
X1268290Y461672D01*
X1268405Y462085D01*
X1268443Y462550D01*
X1268405Y463015D01*
X1268290Y463428D01*
X1268137Y463738D01*
X1267907Y463997D01*
X1267600Y464100D01*
G01X1269013Y460925D02*
X1280787D01*
G01X1262102Y501010D02*
Y498770D01*
G01X1263727Y499983D02*
X1260477D01*
G01X1256754Y497369D02*
X1268250D01*
G01X1254858Y553612D02*
Y559812D01*
G01X1258058Y553612D02*
X1254858D01*
G01X1258058Y559812D02*
Y553612D01*
G01Y560612D02*
X1254858D01*
G01X1258058Y566812D02*
Y560612D01*
G01X1254858Y566812D02*
X1258058D01*
G01X1254858Y560612D02*
Y566812D01*
G01Y559812D02*
X1258058D01*
G01X1264808Y856387D02*
Y852637D01*
G01X1257668Y856387D02*
X1264808D01*
G01X1257668Y852587D02*
Y856387D01*
G01X1264758Y852587D02*
X1257668D01*
G01X1257168Y856387D02*
X1264358D01*
G01X1257168Y852587D02*
Y856387D01*
G01X1264358Y852587D02*
X1257168D01*
G01X1256668Y856387D02*
X1263758D01*
G01X1256668Y852587D02*
Y856387D01*
G01X1263758Y852587D02*
X1256668D01*
G01X1264808Y866387D02*
Y862637D01*
G01X1257668Y862587D02*
Y866387D01*
G01X1264758Y862587D02*
X1257668D01*
G01X1257168D02*
Y866387D01*
G01X1264358Y862587D02*
X1257168D01*
G01X1256668D02*
Y866387D01*
G01X1263758Y862587D02*
X1256668D01*
G01X1264808Y861387D02*
Y857637D01*
G01X1257668Y861387D02*
X1264808D01*
G01X1257668Y857587D02*
Y861387D01*
G01X1264758Y857587D02*
X1257668D01*
G01X1257168Y861387D02*
X1264358D01*
G01X1257168Y857587D02*
Y861387D01*
G01X1264358Y857587D02*
X1257168D01*
G01X1256668Y861387D02*
X1263758D01*
G01X1256668Y857587D02*
Y861387D01*
G01X1263758Y857587D02*
X1256668D01*
G01X1257668Y866387D02*
X1264808D01*
G01X1257168D02*
X1264358D01*
G01X1256668D02*
X1263758D01*
G01X1264808Y876387D02*
Y872637D01*
G01X1257668Y876387D02*
X1264808D01*
G01X1257668Y872587D02*
Y876387D01*
G01X1264758Y872587D02*
X1257668D01*
G01X1257168Y876387D02*
X1264358D01*
G01X1257168Y872587D02*
Y876387D01*
G01X1264358Y872587D02*
X1257168D01*
G01X1256668Y876387D02*
X1263758D01*
G01X1256668Y872587D02*
Y876387D01*
G01X1263758Y872587D02*
X1256668D01*
G01X1264808Y881387D02*
Y877637D01*
G01X1257668Y877587D02*
Y881387D01*
G01X1264758Y877587D02*
X1257668D01*
G01X1257168D02*
Y881387D01*
G01X1264358Y877587D02*
X1257168D01*
G01X1256668D02*
Y881387D01*
G01X1263758Y877587D02*
X1256668D01*
G01X1264808Y871387D02*
Y867637D01*
G01X1257668Y871387D02*
X1264808D01*
G01X1257668Y867587D02*
Y871387D01*
G01X1264758Y867587D02*
X1257668D01*
G01X1257168Y871387D02*
X1264358D01*
G01X1257168Y867587D02*
Y871387D01*
G01X1264358Y867587D02*
X1257168D01*
G01X1256668Y871387D02*
X1263758D01*
G01X1256668Y867587D02*
Y871387D01*
G01X1263758Y867587D02*
X1256668D01*
G01X1264808Y886387D02*
Y882637D01*
G01X1257668Y886387D02*
X1264808D01*
G01X1257668Y882587D02*
Y886387D01*
G01X1264758Y882587D02*
X1257668D01*
G01X1257168Y886387D02*
X1264358D01*
G01X1257168Y882587D02*
Y886387D01*
G01X1264358Y882587D02*
X1257168D01*
G01X1256668Y886387D02*
X1263758D01*
G01X1256668Y882587D02*
Y886387D01*
G01X1263758Y882587D02*
X1256668D01*
G01X1264808Y891387D02*
Y887637D01*
G01X1257668Y891387D02*
X1264808D01*
G01X1257668Y887587D02*
Y891387D01*
G01X1264758Y887587D02*
X1257668D01*
G01X1257168Y891387D02*
X1264358D01*
G01X1257168Y887587D02*
Y891387D01*
G01X1264358Y887587D02*
X1257168D01*
G01X1256668Y891387D02*
X1263758D01*
G01X1256668Y887587D02*
Y891387D01*
G01X1263758Y887587D02*
X1256668D01*
G01X1257668Y881387D02*
X1264808D01*
G01X1257168D02*
X1264358D01*
G01X1256668D02*
X1263758D01*
G01X1266294Y896466D02*
Y893266D01*
G01X1260094Y896466D02*
X1266294D01*
G01X1260094Y893266D02*
Y896466D01*
G01X1266294Y893266D02*
X1260094D01*
G01X1269335Y910048D02*
X1271335Y908324D01*
G01X1265917Y910048D02*
X1269335D01*
G01X1265917Y900600D02*
Y910048D01*
G01X1276753Y900600D02*
X1265917D01*
G01X1260022Y903117D02*
X1263222D01*
G01X1260022Y896917D02*
Y903117D01*
G01X1263222Y896917D02*
X1260022D01*
G01X1263222Y903117D02*
Y896917D01*
G01X1267190Y913349D02*
Y916549D01*
G01X1273390Y913349D02*
X1267190D01*
G01Y916549D02*
X1273390D01*
G01X1273093Y922393D02*
X1269893D01*
G01Y928593D02*
X1273093D01*
G01X1269893Y922393D02*
Y928593D01*
G01X1267190Y917356D02*
Y920556D01*
G01X1273390Y917356D02*
X1267190D01*
G01Y920556D02*
X1273390D01*
G01X1257868Y1100032D02*
Y1103132D01*
G01X1259478D02*
Y1100032D01*
G01Y1101582D02*
X1257868D01*
G01X1261773Y1100032D02*
X1262041Y1100084D01*
X1262348Y1100239D01*
X1262540Y1100497D01*
X1262616Y1100859D01*
X1262540Y1101220D01*
X1262310Y1101530D01*
X1261965Y1101685D01*
X1261581D01*
X1261351Y1101789D01*
X1261160Y1102047D01*
X1261083Y1102409D01*
X1261198Y1102770D01*
X1261466Y1103029D01*
X1261773Y1103132D01*
X1262080Y1103029D01*
X1262348Y1102770D01*
X1262463Y1102409D01*
X1262386Y1102047D01*
X1262195Y1101789D01*
X1261965Y1101685D01*
X1261581D01*
X1261236Y1101530D01*
X1261006Y1101220D01*
X1260930Y1100859D01*
X1261006Y1100497D01*
X1261198Y1100239D01*
X1261505Y1100084D01*
X1261773Y1100032D01*
G01X1264145Y1101324D02*
X1264413Y1101685D01*
X1264643Y1101892D01*
X1264950Y1101995D01*
X1265218Y1101892D01*
X1265410Y1101685D01*
X1265563Y1101375D01*
X1265601Y1101014D01*
X1265563Y1100704D01*
X1265410Y1100394D01*
X1265180Y1100135D01*
X1264911Y1100032D01*
X1264605Y1100135D01*
X1264336Y1100445D01*
X1264183Y1100910D01*
X1264145Y1101427D01*
X1264221Y1102099D01*
X1264336Y1102460D01*
X1264528Y1102822D01*
X1264796Y1103080D01*
X1265065Y1103132D01*
X1265333Y1103029D01*
X1265525Y1102770D01*
G01X1265521Y1135604D02*
X1262321D01*
G01X1265521Y1141804D02*
Y1135604D01*
G01X1262321D02*
Y1141804D01*
G01X1269521Y1135604D02*
X1266321D01*
G01X1269521Y1141804D02*
Y1135604D01*
G01X1266321D02*
Y1141804D01*
G01X1258321Y1135604D02*
Y1141804D01*
G01X1261521Y1135604D02*
X1258321D01*
G01X1261521Y1141804D02*
Y1135604D01*
G01X1257521D02*
X1254321D01*
G01X1257521Y1141804D02*
Y1135604D01*
G01X1254321D02*
Y1141804D01*
G01X1264919Y1149643D02*
Y1161167D01*
G01X1277123Y1149643D02*
X1264919D01*
G01X1262321Y1141804D02*
X1265521D01*
G01X1266321D02*
X1269521D01*
G01X1258321D02*
X1261521D01*
G01X1254321D02*
X1257521D01*
G01X1262698Y1144471D02*
X1256498D01*
Y1147671D01*
X1262698D01*
Y1144471D01*
G01X1264919Y1161167D02*
X1277123D01*
G01X1263429Y1169520D02*
Y1172720D01*
G01X1269629Y1169520D02*
X1263429D01*
G01X1269629Y1172720D02*
Y1169520D01*
G01X1262987Y1179765D02*
X1266187D01*
G01X1262987Y1173565D02*
Y1179765D01*
G01X1266187Y1173565D02*
X1262987D01*
G01X1266187Y1179765D02*
Y1173565D01*
G01X1263429Y1172720D02*
X1269629D01*
G01X1266987Y1179765D02*
X1270187D01*
G01X1266987Y1173565D02*
Y1179765D01*
G01X1270187Y1173565D02*
X1266987D01*
G01X1267015Y1186730D02*
X1270215D01*
G01X1267015Y1180530D02*
Y1186730D01*
G01X1270215Y1180530D02*
X1267015D01*
G01X1263015Y1186730D02*
X1266215D01*
G01X1263015Y1180530D02*
Y1186730D01*
G01X1266215Y1180530D02*
X1263015D01*
G01X1266215Y1186730D02*
Y1180530D01*
G01X1254028Y1180445D02*
Y1186645D01*
X1257228D01*
Y1180445D01*
X1254028D01*
G01X1258044Y1180375D02*
Y1186575D01*
X1261244D01*
Y1180375D01*
X1258044D01*
G01X1266175Y1201918D02*
X1262975D01*
G01X1266175Y1208118D02*
Y1201918D01*
G01X1262975D02*
Y1208118D01*
G01X1270175Y1201918D02*
X1266975D01*
G01D02*
Y1208118D01*
G01X1266173Y1193894D02*
X1262973D01*
G01X1266173Y1200094D02*
Y1193894D01*
G01X1262973Y1200094D02*
X1266173D01*
G01X1262973Y1193894D02*
Y1200094D01*
G01X1270173Y1193894D02*
X1266973D01*
G01Y1200094D02*
X1270173D01*
G01X1266973Y1193894D02*
Y1200094D01*
G01X1257540Y1193976D02*
Y1190776D01*
G01X1262135Y1201923D02*
X1258935D01*
G01X1262135Y1208123D02*
Y1201923D01*
G01X1258935D02*
Y1208123D01*
G01X1259171Y1192220D02*
Y1198420D01*
X1262371D01*
Y1192220D01*
X1259171D01*
G01X1257085Y1203525D02*
Y1197325D01*
X1253885D01*
Y1203525D01*
X1257085D01*
G01X1262975Y1208118D02*
X1266175D01*
G01X1266975D02*
X1270175D01*
G01X1265905Y1221417D02*
X1263643Y1219155D01*
G01X1261521Y1225801D02*
X1265905Y1221417D01*
G01X1263643Y1219155D02*
X1259259Y1223539D01*
G01X1263076Y1218590D02*
X1260814Y1216328D01*
G01X1258692Y1222974D02*
X1263076Y1218590D01*
G01X1256430Y1220712D02*
X1258692Y1222974D01*
G01X1260814Y1216328D02*
X1256430Y1220712D01*
G01X1268219Y1220023D02*
X1272603Y1215639D01*
G01X1265957Y1217761D02*
X1268219Y1220023D01*
G01X1270341Y1213377D02*
X1265957Y1217761D01*
G01X1268786Y1220590D02*
X1271048Y1222852D01*
G01X1273170Y1216206D02*
X1268786Y1220590D01*
G01X1269775Y1212811D02*
X1267513Y1210549D01*
G01X1265391Y1217195D02*
X1269775Y1212811D01*
G01X1263129Y1214933D02*
X1265391Y1217195D01*
G01X1267513Y1210549D02*
X1263129Y1214933D01*
G01X1258935Y1208123D02*
X1262135D01*
G01X1259259Y1223539D02*
X1261521Y1225801D01*
G01X1268734Y1224246D02*
X1266472Y1221984D01*
G01X1264350Y1228630D02*
X1268734Y1224246D01*
G01X1262088Y1226368D02*
X1264350Y1228630D01*
G01X1266472Y1221984D02*
X1262088Y1226368D01*
G01X1271563Y1227075D02*
X1269301Y1224813D01*
G01X1267179Y1231459D02*
X1271563Y1227075D01*
G01X1264917Y1229197D02*
X1267179Y1231459D01*
G01X1269301Y1224813D02*
X1264917Y1229197D01*
G01X1261785Y1521858D02*
X1255585D01*
Y1525058D01*
X1261785D01*
Y1521858D01*
G01X1261746Y1532934D02*
Y1529734D01*
G01X1255546D02*
Y1532934D01*
G01X1261746Y1529734D02*
X1255546D01*
G01X1261746Y1528934D02*
Y1525734D01*
G01X1255546Y1528934D02*
X1261746D01*
G01X1255546Y1525734D02*
Y1528934D01*
G01X1261746Y1525734D02*
X1255546D01*
G01X1255533Y1521059D02*
X1261733D01*
Y1517859D01*
X1255533D01*
Y1521059D01*
G01X1261785Y1541958D02*
X1255585D01*
Y1545158D01*
X1261785D01*
Y1541958D01*
G01X1255546Y1532934D02*
X1261746D01*
G01Y1540934D02*
Y1537734D01*
G01X1255546Y1540934D02*
X1261746D01*
G01X1255546Y1537734D02*
Y1540934D01*
G01X1261746Y1537734D02*
X1255546D01*
G01X1261770Y1533785D02*
X1255570D01*
Y1536985D01*
X1261770D01*
Y1533785D01*
G01X1261977Y1559592D02*
X1262169Y1559282D01*
X1262399Y1559075D01*
X1262667Y1558972D01*
X1262974Y1559075D01*
X1263204Y1559282D01*
X1263434Y1559592D01*
X1263511Y1560005D01*
Y1562072D01*
G01X1265116Y1560264D02*
X1265384Y1560625D01*
X1265614Y1560832D01*
X1265921Y1560935D01*
X1266189Y1560832D01*
X1266381Y1560625D01*
X1266534Y1560315D01*
X1266572Y1559954D01*
X1266534Y1559644D01*
X1266381Y1559334D01*
X1266151Y1559075D01*
X1265882Y1558972D01*
X1265576Y1559075D01*
X1265307Y1559385D01*
X1265154Y1559850D01*
X1265116Y1560367D01*
X1265192Y1561039D01*
X1265307Y1561400D01*
X1265499Y1561762D01*
X1265767Y1562020D01*
X1266036Y1562072D01*
X1266304Y1561969D01*
X1266496Y1561710D01*
G01X1268944Y1558972D02*
Y1562072D01*
X1268484Y1561452D01*
G01Y1558972D02*
X1269404D01*
G01X1255655Y1728302D02*
Y1702076D01*
G01X1259834Y1720872D02*
X1260144Y1721064D01*
X1260351Y1721294D01*
X1260454Y1721562D01*
X1260351Y1721869D01*
X1260144Y1722099D01*
X1259834Y1722329D01*
X1259421Y1722406D01*
X1257354D01*
G01X1259989Y1723896D02*
X1260247Y1724126D01*
X1260402Y1724394D01*
X1260454Y1724739D01*
X1260351Y1725084D01*
X1260144Y1725352D01*
X1259782Y1725544D01*
X1259369Y1725582D01*
X1258956Y1725506D01*
X1258697Y1725314D01*
X1258491Y1725046D01*
X1258439Y1724777D01*
X1258491Y1724509D01*
X1258697Y1724164D01*
X1257354Y1724279D01*
Y1725314D01*
G01X1259834Y1726996D02*
X1260196Y1727226D01*
X1260402Y1727532D01*
X1260454Y1727877D01*
X1260402Y1728184D01*
X1260144Y1728491D01*
X1259834Y1728682D01*
X1259524Y1728721D01*
X1259162Y1728644D01*
X1258904Y1728376D01*
X1258801Y1728107D01*
Y1727762D01*
G01Y1728107D02*
X1258646Y1728337D01*
X1258387Y1728529D01*
X1258077Y1728606D01*
X1257767Y1728529D01*
X1257509Y1728337D01*
X1257354Y1727992D01*
X1257406Y1727647D01*
X1257612Y1727302D01*
G01X1255648Y1786490D02*
Y1760264D01*
G01X1259827Y1779060D02*
X1260137Y1779252D01*
X1260344Y1779482D01*
X1260447Y1779750D01*
X1260344Y1780057D01*
X1260137Y1780287D01*
X1259827Y1780517D01*
X1259414Y1780594D01*
X1257347D01*
G01X1259982Y1782084D02*
X1260240Y1782314D01*
X1260395Y1782582D01*
X1260447Y1782927D01*
X1260344Y1783272D01*
X1260137Y1783540D01*
X1259775Y1783732D01*
X1259362Y1783770D01*
X1258949Y1783694D01*
X1258690Y1783502D01*
X1258484Y1783234D01*
X1258432Y1782965D01*
X1258484Y1782697D01*
X1258690Y1782352D01*
X1257347Y1782467D01*
Y1783502D01*
G01X1260447Y1786027D02*
X1257347D01*
X1257967Y1785567D01*
G01X1260447D02*
Y1786487D01*
G01X1254155Y1816022D02*
Y1789796D01*
G01X1258334Y1808592D02*
X1258644Y1808784D01*
X1258851Y1809014D01*
X1258954Y1809282D01*
X1258851Y1809589D01*
X1258644Y1809819D01*
X1258334Y1810049D01*
X1257921Y1810126D01*
X1255854D01*
G01X1258489Y1811616D02*
X1258747Y1811846D01*
X1258902Y1812114D01*
X1258954Y1812459D01*
X1258851Y1812804D01*
X1258644Y1813072D01*
X1258282Y1813264D01*
X1257869Y1813302D01*
X1257456Y1813226D01*
X1257197Y1813034D01*
X1256991Y1812766D01*
X1256939Y1812497D01*
X1256991Y1812229D01*
X1257197Y1811884D01*
X1255854Y1811999D01*
Y1813034D01*
G01Y1815559D02*
X1255957Y1815252D01*
X1256216Y1815022D01*
X1256526Y1814869D01*
X1256939Y1814754D01*
X1257404Y1814716D01*
X1257869Y1814754D01*
X1258282Y1814869D01*
X1258592Y1815022D01*
X1258851Y1815252D01*
X1258954Y1815559D01*
X1258851Y1815866D01*
X1258592Y1816096D01*
X1258282Y1816249D01*
X1257869Y1816364D01*
X1257404Y1816402D01*
X1256939Y1816364D01*
X1256526Y1816249D01*
X1256216Y1816096D01*
X1255957Y1815866D01*
X1255854Y1815559D01*
G01X1277863Y-21689D02*
Y-18589D01*
X1278629D01*
X1278936Y-18744D01*
X1279166Y-18951D01*
X1279358Y-19261D01*
X1279511Y-19622D01*
X1279549Y-20139D01*
X1279511Y-20656D01*
X1279358Y-21017D01*
X1279166Y-21327D01*
X1278936Y-21534D01*
X1278629Y-21689D01*
X1277863D01*
G01X1282573D02*
X1281039D01*
Y-18589D01*
X1282573D01*
G01X1281959Y-20087D02*
X1281039D01*
G01X1284906Y-21689D02*
Y-18589D01*
X1284446Y-19209D01*
G01Y-21689D02*
X1285366D01*
G01X1288466D02*
Y-18589D01*
X1287048Y-20811D01*
X1288964D01*
G01X1291106Y-18589D02*
Y-21689D01*
G01X1290224Y-18589D02*
X1291988D01*
G01X1293056Y-22722D02*
X1295356D01*
G01X1296578Y-19106D02*
X1296808Y-18796D01*
X1297076Y-18641D01*
X1297383Y-18589D01*
X1297766Y-18692D01*
X1298034Y-18951D01*
X1298111Y-19261D01*
X1298073Y-19571D01*
X1297919Y-19829D01*
X1297153Y-20346D01*
X1296808Y-20707D01*
X1296578Y-21224D01*
X1296501Y-21689D01*
X1298111D01*
G01X1284704Y57756D02*
Y104452D01*
G01X1284408Y58150D02*
Y104452D01*
G01X1284704Y57756D02*
X1278323D01*
G01X1284408Y58150D02*
X1278728D01*
G01X1284704Y111507D02*
Y107060D01*
G01X1284408Y111507D02*
Y107060D01*
G01Y118680D02*
Y114087D01*
G01X1284704Y118680D02*
Y114087D01*
G01X1284408Y132859D02*
Y128325D01*
G01X1284704Y132859D02*
Y128325D01*
G01Y125844D02*
Y121329D01*
G01X1284408Y125844D02*
Y121329D01*
G01Y152756D02*
Y135578D01*
G01X1284704Y153150D02*
Y135578D01*
G01X1273354Y156615D02*
X1274101Y155990D01*
X1274941Y155615D01*
X1275687D01*
X1276434Y155990D01*
X1276994Y156615D01*
X1277274Y157490D01*
X1277087Y158365D01*
X1276621Y159115D01*
X1275781Y159615D01*
X1274661Y159865D01*
X1274007Y160365D01*
X1273727Y161240D01*
X1273914Y162115D01*
X1274381Y162740D01*
X1275034Y163115D01*
X1275687D01*
X1276341Y162865D01*
X1276901Y162240D01*
G01X1280854Y156615D02*
X1281601Y155990D01*
X1282441Y155615D01*
X1283187D01*
X1283934Y155990D01*
X1284494Y156615D01*
X1284774Y157490D01*
X1284587Y158365D01*
X1284121Y159115D01*
X1283281Y159615D01*
X1282161Y159865D01*
X1281507Y160365D01*
X1281227Y161240D01*
X1281414Y162115D01*
X1281881Y162740D01*
X1282534Y163115D01*
X1283187D01*
X1283841Y162865D01*
X1284401Y162240D01*
G01X1288261Y155615D02*
Y163115D01*
X1290127D01*
X1290874Y162740D01*
X1291434Y162240D01*
X1291901Y161490D01*
X1292274Y160615D01*
X1292367Y159365D01*
X1292274Y158115D01*
X1291901Y157240D01*
X1291434Y156490D01*
X1290874Y155990D01*
X1290127Y155615D01*
X1288261D01*
G01X1297814D02*
Y163115D01*
X1296694Y161615D01*
G01Y155615D02*
X1298934D01*
G01X1305314D02*
Y163115D01*
X1304194Y161615D01*
G01Y155615D02*
X1306434D01*
G01X1276804Y164436D02*
X1291604D01*
G01X1276804Y195440D02*
Y164436D01*
G01X1278323Y153150D02*
X1284704D01*
G01X1278728Y152756D02*
X1284408D01*
G01X1291604Y195440D02*
X1276804D01*
G01X1274200Y204783D02*
X1271100D01*
Y205703D01*
X1271255Y206010D01*
X1271617Y206240D01*
X1272030Y206317D01*
X1272443Y206240D01*
X1272753Y206048D01*
X1272908Y205703D01*
Y204783D01*
G01X1274200Y207807D02*
X1271100D01*
Y208573D01*
X1271255Y208880D01*
X1271462Y209110D01*
X1271772Y209302D01*
X1272133Y209455D01*
X1272650Y209493D01*
X1273167Y209455D01*
X1273528Y209302D01*
X1273838Y209110D01*
X1274045Y208880D01*
X1274200Y208573D01*
Y207807D01*
G01Y211750D02*
X1271100D01*
X1271720Y211290D01*
G01X1274200D02*
Y212210D01*
G01Y214850D02*
X1271100D01*
X1271720Y214390D01*
G01X1274200D02*
Y215310D01*
G01X1273735Y217107D02*
X1273993Y217337D01*
X1274148Y217605D01*
X1274200Y217950D01*
X1274097Y218295D01*
X1273890Y218563D01*
X1273528Y218755D01*
X1273115Y218793D01*
X1272702Y218717D01*
X1272443Y218525D01*
X1272237Y218257D01*
X1272185Y217988D01*
X1272237Y217720D01*
X1272443Y217375D01*
X1271100Y217490D01*
Y218525D01*
G01X1280807Y199912D02*
Y202338D01*
G01X1286855Y203452D02*
X1275359D01*
G01D02*
Y233011D01*
G01X1280707Y236652D02*
Y234412D01*
G01X1282332Y235625D02*
X1279082D01*
G01X1275359Y233011D02*
X1286855D01*
G01X1280576Y259204D02*
Y261630D01*
G01X1286624Y262744D02*
X1275128D01*
G01D02*
Y292303D01*
G01X1274000Y263583D02*
X1270900D01*
Y264503D01*
X1271055Y264810D01*
X1271417Y265040D01*
X1271830Y265117D01*
X1272243Y265040D01*
X1272553Y264848D01*
X1272708Y264503D01*
Y263583D01*
G01X1274000Y266607D02*
X1270900D01*
Y267373D01*
X1271055Y267680D01*
X1271262Y267910D01*
X1271572Y268102D01*
X1271933Y268255D01*
X1272450Y268293D01*
X1272967Y268255D01*
X1273328Y268102D01*
X1273638Y267910D01*
X1273845Y267680D01*
X1274000Y267373D01*
Y266607D01*
G01X1273535Y269707D02*
X1273793Y269937D01*
X1273948Y270205D01*
X1274000Y270550D01*
X1273897Y270895D01*
X1273690Y271163D01*
X1273328Y271355D01*
X1272915Y271393D01*
X1272502Y271317D01*
X1272243Y271125D01*
X1272037Y270857D01*
X1271985Y270588D01*
X1272037Y270320D01*
X1272243Y269975D01*
X1270900Y270090D01*
Y271125D01*
G01Y273650D02*
X1271003Y273343D01*
X1271262Y273113D01*
X1271572Y272960D01*
X1271985Y272845D01*
X1272450Y272807D01*
X1272915Y272845D01*
X1273328Y272960D01*
X1273638Y273113D01*
X1273897Y273343D01*
X1274000Y273650D01*
X1273897Y273957D01*
X1273638Y274187D01*
X1273328Y274340D01*
X1272915Y274455D01*
X1272450Y274493D01*
X1271985Y274455D01*
X1271572Y274340D01*
X1271262Y274187D01*
X1271003Y273957D01*
X1270900Y273650D01*
G01X1280931Y297843D02*
Y295603D01*
G01X1282556Y296816D02*
X1279306D01*
G01X1275128Y292303D02*
X1286624D01*
G01X1272107Y324500D02*
Y322278D01*
X1272260Y321813D01*
X1272567Y321503D01*
X1272950Y321400D01*
X1273333Y321503D01*
X1273640Y321813D01*
X1273793Y322278D01*
Y324500D01*
G01X1276510Y321400D02*
Y324500D01*
X1275092Y322278D01*
X1277008D01*
G01X1278422Y323983D02*
X1278652Y324293D01*
X1278920Y324448D01*
X1279227Y324500D01*
X1279610Y324397D01*
X1279878Y324138D01*
X1279955Y323828D01*
X1279917Y323518D01*
X1279763Y323260D01*
X1278997Y322743D01*
X1278652Y322382D01*
X1278422Y321865D01*
X1278345Y321400D01*
X1279955D01*
G01X1282250Y324500D02*
X1281943Y324397D01*
X1281713Y324138D01*
X1281560Y323828D01*
X1281445Y323415D01*
X1281407Y322950D01*
X1281445Y322485D01*
X1281560Y322072D01*
X1281713Y321762D01*
X1281943Y321503D01*
X1282250Y321400D01*
X1282557Y321503D01*
X1282787Y321762D01*
X1282940Y322072D01*
X1283055Y322485D01*
X1283093Y322950D01*
X1283055Y323415D01*
X1282940Y323828D01*
X1282787Y324138D01*
X1282557Y324397D01*
X1282250Y324500D01*
G01X1282619Y338037D02*
Y325833D01*
G01X1271095D02*
Y338037D01*
G01X1273857Y325833D02*
X1271095D01*
G01X1276857Y328935D02*
X1273857Y325833D01*
G01X1279959D02*
X1276857Y328935D01*
G01X1282619Y325833D02*
X1279959D01*
G01X1271095Y338037D02*
X1282619D01*
G01X1277260Y347310D02*
Y341110D01*
X1274060D01*
Y347310D01*
X1277260D01*
G01X1281255Y347251D02*
Y341051D01*
X1278055D01*
Y347251D01*
X1281255D01*
G01X1289037Y377279D02*
Y371079D01*
X1285837D01*
Y377279D01*
X1289037D01*
G01X1281300Y392257D02*
X1283522D01*
X1283987Y392410D01*
X1284297Y392717D01*
X1284400Y393100D01*
X1284297Y393483D01*
X1283987Y393790D01*
X1283522Y393943D01*
X1281300D01*
G01X1284400Y396200D02*
X1284348Y396468D01*
X1284193Y396775D01*
X1283935Y396967D01*
X1283573Y397043D01*
X1283212Y396967D01*
X1282902Y396737D01*
X1282747Y396392D01*
Y396008D01*
X1282643Y395778D01*
X1282385Y395587D01*
X1282023Y395510D01*
X1281662Y395625D01*
X1281403Y395893D01*
X1281300Y396200D01*
X1281403Y396507D01*
X1281662Y396775D01*
X1282023Y396890D01*
X1282385Y396813D01*
X1282643Y396622D01*
X1282747Y396392D01*
Y396008D01*
X1282902Y395663D01*
X1283212Y395433D01*
X1283573Y395357D01*
X1283935Y395433D01*
X1284193Y395625D01*
X1284348Y395932D01*
X1284400Y396200D01*
G01Y399760D02*
X1281300D01*
X1283522Y398342D01*
Y400258D01*
G01X1279575Y388619D02*
X1277622D01*
G01X1279575Y390572D02*
Y388619D01*
G01X1282259Y378048D02*
X1279059D01*
G01X1282259Y384248D02*
Y378048D01*
G01X1279059Y384248D02*
X1282259D01*
G01X1279059Y378048D02*
Y384248D01*
G01X1286259Y378048D02*
X1283059D01*
G01X1286259Y384248D02*
Y378048D01*
G01X1283059Y384248D02*
X1286259D01*
G01X1283059Y378048D02*
Y384248D01*
G01X1275059D02*
X1278259D01*
G01X1275059Y378048D02*
Y384248D01*
G01X1278259Y378048D02*
X1275059D01*
G01X1278259Y384248D02*
Y378048D01*
G01X1270259Y384248D02*
Y378048D01*
G01X1271059Y384248D02*
X1274259D01*
G01X1271059Y378048D02*
Y384248D01*
G01X1274259Y378048D02*
X1271059D01*
G01X1274259Y384248D02*
Y378048D01*
G01X1279575Y400431D02*
Y398478D01*
G01X1277622Y400431D02*
X1279575D01*
G01X1286141Y411675D02*
X1288567D01*
G01X1284360Y401941D02*
X1281160D01*
G01X1284360Y408141D02*
Y401941D01*
G01X1281160Y408141D02*
X1284360D01*
G01X1281160Y401941D02*
Y408141D01*
G01X1274049Y404932D02*
Y408132D01*
G01X1280249Y404932D02*
X1274049D01*
G01X1280249Y408132D02*
Y404932D01*
G01X1274049Y408132D02*
X1280249D01*
G01X1285625Y415040D02*
Y429840D01*
G01X1273215Y431902D02*
Y443902D01*
G01X1279215Y431902D02*
X1273215D01*
G01X1279215Y443902D02*
Y431902D01*
G01X1283092Y438502D02*
Y450502D01*
G01X1289092Y438502D02*
X1283092D01*
G01X1273215Y443902D02*
X1279215D01*
G01X1283092Y450502D02*
X1289092D01*
G01X1274393Y445757D02*
Y448957D01*
G01X1280593Y445757D02*
X1274393D01*
G01X1280593Y448957D02*
Y445757D01*
G01X1274393Y448957D02*
X1280593D01*
G01X1283097Y456709D02*
Y459909D01*
G01X1289297Y456709D02*
X1283097D01*
G01Y452709D02*
Y455909D01*
G01X1289297Y452709D02*
X1283097D01*
G01Y455909D02*
X1289297D01*
G01X1280787Y460925D02*
Y451163D01*
G01X1270349Y469326D02*
X1282349D01*
G01X1270349Y463326D02*
Y469326D01*
G01X1282349Y463326D02*
X1270349D01*
G01X1282349Y469326D02*
Y463326D01*
G01X1283097Y460709D02*
Y463909D01*
G01X1289297Y460709D02*
X1283097D01*
G01Y463909D02*
X1289297D01*
G01X1283097Y459909D02*
X1289297D01*
G01X1285662Y465500D02*
Y468600D01*
X1286582D01*
X1286889Y468445D01*
X1287119Y468083D01*
X1287196Y467670D01*
X1287119Y467257D01*
X1286927Y466947D01*
X1286582Y466792D01*
X1285662D01*
G01X1288686Y468600D02*
Y466378D01*
X1288839Y465913D01*
X1289146Y465603D01*
X1289529Y465500D01*
X1289912Y465603D01*
X1290219Y465913D01*
X1290372Y466378D01*
Y468600D01*
G01X1293089Y465500D02*
Y468600D01*
X1291671Y466378D01*
X1293587D01*
G01X1295077Y465862D02*
X1295346Y465603D01*
X1295652Y465500D01*
X1295959Y465603D01*
X1296227Y465913D01*
X1296419Y466378D01*
X1296496Y466843D01*
Y467412D01*
X1296419Y467877D01*
X1296227Y468290D01*
X1295997Y468497D01*
X1295729Y468600D01*
X1295422Y468497D01*
X1295192Y468290D01*
X1295039Y467980D01*
X1294962Y467567D01*
X1295039Y467205D01*
X1295231Y466843D01*
X1295461Y466637D01*
X1295729Y466585D01*
X1296036Y466688D01*
X1296266Y466947D01*
X1296496Y467412D01*
G01X1296909Y483629D02*
Y471425D01*
X1281605D01*
Y483629D01*
X1296909D01*
G01X1270106Y478517D02*
Y490517D01*
G01X1276106Y478517D02*
X1270106D01*
G01X1276106Y490517D02*
Y478517D01*
G01X1280973Y490416D02*
X1287173D01*
G01X1280973Y487216D02*
Y490416D01*
G01X1287173Y487216D02*
X1280973D01*
G01X1280099Y480358D02*
X1276899D01*
G01X1280099Y486558D02*
Y480358D01*
G01X1276899Y486558D02*
X1280099D01*
G01X1276899Y480358D02*
Y486558D01*
G01X1277173Y497216D02*
X1289173D01*
G01X1277173Y491216D02*
Y497216D01*
G01X1289173Y491216D02*
X1277173D01*
G01X1270106Y490517D02*
X1276106D01*
G01X1280414Y770176D02*
X1286614D01*
G01X1280414Y766976D02*
Y770176D01*
G01X1286614Y766976D02*
X1280414D01*
G01Y774976D02*
Y778176D01*
G01X1286614Y774976D02*
X1280414D01*
G01Y778176D02*
X1286614D01*
G01X1280414Y770976D02*
Y774176D01*
G01X1286614Y770976D02*
X1280414D01*
G01Y774176D02*
X1286614D01*
G01X1280414Y782176D02*
X1286614D01*
G01X1280414Y778976D02*
Y782176D01*
G01X1286614Y778976D02*
X1280414D01*
G01Y782976D02*
Y786176D01*
G01X1286614Y782976D02*
X1280414D01*
G01Y786176D02*
X1286614D01*
G01X1286550Y811400D02*
X1286243Y811452D01*
X1285975Y811658D01*
X1285745Y811968D01*
X1285592Y812330D01*
X1285515Y812743D01*
Y813157D01*
X1285592Y813570D01*
X1285745Y813932D01*
X1285975Y814242D01*
X1286243Y814448D01*
X1286550Y814500D01*
X1286857Y814448D01*
X1287125Y814242D01*
X1287355Y813932D01*
X1287508Y813570D01*
X1287585Y813157D01*
Y812743D01*
X1287508Y812330D01*
X1287355Y811968D01*
X1287125Y811658D01*
X1286857Y811452D01*
X1286550Y811400D01*
G01X1288845Y811813D02*
X1289152Y811555D01*
X1289497Y811400D01*
X1289803D01*
X1290110Y811555D01*
X1290340Y811813D01*
X1290455Y812175D01*
X1290378Y812537D01*
X1290187Y812847D01*
X1289842Y813053D01*
X1289382Y813157D01*
X1289113Y813363D01*
X1288998Y813725D01*
X1289075Y814087D01*
X1289267Y814345D01*
X1289535Y814500D01*
X1289803D01*
X1290072Y814397D01*
X1290302Y814138D01*
G01X1293593Y814242D02*
X1293363Y814397D01*
X1293095Y814500D01*
X1292788D01*
X1292443Y814345D01*
X1292175Y814087D01*
X1291983Y813777D01*
X1291830Y813260D01*
X1291792Y812795D01*
X1291868Y812330D01*
X1291983Y812020D01*
X1292213Y811710D01*
X1292482Y811503D01*
X1292750Y811400D01*
X1293018D01*
X1293287Y811503D01*
X1293517Y811658D01*
X1293708Y811865D01*
G01X1295850Y811400D02*
Y814500D01*
X1295390Y813880D01*
G01Y811400D02*
X1296310D01*
G01X1278271Y846545D02*
X1272071D01*
Y849745D01*
X1278271D01*
Y846545D01*
G01X1278367Y866087D02*
Y862887D01*
G01X1272167D02*
Y866087D01*
G01X1278367Y862887D02*
X1272167D01*
G01X1278367Y861087D02*
Y857887D01*
G01X1272167Y861087D02*
X1278367D01*
G01X1272167Y857887D02*
Y861087D01*
G01X1278367Y857887D02*
X1272167D01*
G01X1278355Y853629D02*
Y850429D01*
G01X1272155Y853629D02*
X1278355D01*
G01X1272155Y850429D02*
Y853629D01*
G01X1278355Y850429D02*
X1272155D01*
G01X1272167Y866087D02*
X1278367D01*
G01Y876087D02*
Y872887D01*
G01X1272167Y876087D02*
X1278367D01*
G01X1272167Y872887D02*
Y876087D01*
G01X1278367Y872887D02*
X1272167D01*
G01X1278367Y871087D02*
Y867887D01*
G01X1272167Y871087D02*
X1278367D01*
G01X1272167Y867887D02*
Y871087D01*
G01X1278367Y867887D02*
X1272167D01*
G01X1278367Y881087D02*
Y877887D01*
G01X1272167D02*
Y881087D01*
G01X1278367Y877887D02*
X1272167D01*
G01X1270564Y893746D02*
Y897546D01*
G01X1277654Y893746D02*
X1270564D01*
G01X1271064D02*
Y897546D01*
G01X1278254Y893746D02*
X1271064D01*
G01X1278704Y897546D02*
Y893796D01*
G01X1271564Y893746D02*
Y897546D01*
G01X1278654Y893746D02*
X1271564D01*
G01X1272167Y881087D02*
X1278367D01*
G01X1286255Y893400D02*
X1283055D01*
G01X1286255Y899600D02*
Y893400D01*
G01X1283055D02*
Y899600D01*
G01X1278367Y891087D02*
Y887887D01*
G01X1272167Y891087D02*
X1278367D01*
G01X1272167Y887887D02*
Y891087D01*
G01X1278367Y887887D02*
X1272167D01*
G01X1278367Y886087D02*
Y882887D01*
G01X1272167Y886087D02*
X1278367D01*
G01X1272167Y882887D02*
Y886087D01*
G01X1278367Y882887D02*
X1272167D01*
G01X1284268Y907500D02*
X1286039Y909000D01*
G01X1284268Y902369D02*
Y907500D01*
G01X1292732Y902369D02*
X1284268D01*
G01Y910500D02*
Y915631D01*
G01X1286039Y909000D02*
X1284268Y910500D01*
G01X1273335Y910048D02*
X1276753D01*
G01X1271335Y908324D02*
X1273335Y910048D01*
G01X1276753D02*
Y900600D01*
G01X1270564Y897546D02*
X1277654D01*
G01X1271064D02*
X1278254D01*
G01X1271564D02*
X1278704D01*
G01X1276400Y912400D02*
Y915600D01*
G01X1282600Y912400D02*
X1276400D01*
G01X1282600Y915600D02*
Y912400D01*
G01X1283055Y899600D02*
X1286255D01*
G01X1278442Y906748D02*
X1281642D01*
G01X1278442Y900548D02*
Y906748D01*
G01X1281642Y900548D02*
X1278442D01*
G01X1281642Y906748D02*
Y900548D01*
G01X1284268Y915631D02*
X1292732D01*
G01X1276400Y915600D02*
X1282600D01*
G01X1282400Y921100D02*
X1288600D01*
G01X1282400Y917900D02*
Y921100D01*
G01X1288600Y917900D02*
X1282400D01*
G01X1277093Y922393D02*
X1273893D01*
G01X1277093Y928593D02*
Y922393D01*
G01X1273893Y928593D02*
X1277093D01*
G01X1273893Y922393D02*
Y928593D01*
G01X1281093Y922393D02*
X1277893D01*
G01X1281093Y928593D02*
Y922393D01*
G01X1277893Y928593D02*
X1281093D01*
G01X1277893Y922393D02*
Y928593D01*
G01X1285093Y922393D02*
X1281893D01*
G01X1285093Y928593D02*
Y922393D01*
G01X1281893Y928593D02*
X1285093D01*
G01X1281893Y922393D02*
Y928593D01*
G01X1273390Y916549D02*
Y913349D01*
G01X1273093Y928593D02*
Y922393D01*
G01X1273390Y920556D02*
Y917356D01*
G01X1286200Y938100D02*
X1286148Y937793D01*
X1285942Y937525D01*
X1285632Y937295D01*
X1285270Y937142D01*
X1284857Y937065D01*
X1284443D01*
X1284030Y937142D01*
X1283668Y937295D01*
X1283358Y937525D01*
X1283152Y937793D01*
X1283100Y938100D01*
X1283152Y938407D01*
X1283358Y938675D01*
X1283668Y938905D01*
X1284030Y939058D01*
X1284443Y939135D01*
X1284857D01*
X1285270Y939058D01*
X1285632Y938905D01*
X1285942Y938675D01*
X1286148Y938407D01*
X1286200Y938100D01*
G01X1285373Y938407D02*
X1286200Y938867D01*
G01Y941200D02*
X1283100D01*
X1283720Y940740D01*
G01X1286200D02*
Y941660D01*
G01X1285838Y943648D02*
X1286097Y943917D01*
X1286200Y944223D01*
X1286097Y944530D01*
X1285787Y944798D01*
X1285322Y944990D01*
X1284857Y945067D01*
X1284288D01*
X1283823Y944990D01*
X1283410Y944798D01*
X1283203Y944568D01*
X1283100Y944300D01*
X1283203Y943993D01*
X1283410Y943763D01*
X1283720Y943610D01*
X1284133Y943533D01*
X1284495Y943610D01*
X1284857Y943802D01*
X1285063Y944032D01*
X1285115Y944300D01*
X1285012Y944607D01*
X1284753Y944837D01*
X1284288Y945067D01*
G01X1284976Y935198D02*
Y931998D01*
G01X1278776Y935198D02*
X1284976D01*
G01X1278776Y931998D02*
Y935198D01*
G01X1284976Y931998D02*
X1278776D01*
G01X1277521Y1135604D02*
X1274321D01*
G01X1277521Y1141804D02*
Y1135604D01*
G01X1274321D02*
Y1141804D01*
G01X1278321Y1135604D02*
Y1141804D01*
G01X1281521Y1135604D02*
X1278321D01*
G01X1281521Y1141804D02*
Y1135604D01*
G01X1273521D02*
X1270321D01*
G01X1273521Y1141804D02*
Y1135604D01*
G01X1270321D02*
Y1141804D01*
G01X1277123Y1152405D02*
Y1149643D01*
G01X1274021Y1155405D02*
X1277123Y1152405D01*
G01Y1158507D02*
X1274021Y1155405D01*
G01X1281930Y1145412D02*
X1278730D01*
G01X1281930Y1151612D02*
Y1145412D01*
G01X1278730Y1151612D02*
X1281930D01*
G01X1278730Y1145412D02*
Y1151612D01*
G01X1274321Y1141804D02*
X1277521D01*
G01X1278321D02*
X1281521D01*
G01X1270321D02*
X1273521D01*
G01X1277123Y1161167D02*
Y1158507D01*
G01X1281906Y1163692D02*
X1278706D01*
G01X1281906Y1169892D02*
Y1163692D01*
G01X1278706Y1169892D02*
X1281906D01*
G01X1278706Y1163692D02*
Y1169892D01*
G01X1276628Y1172720D02*
Y1169520D01*
G01X1270428D02*
Y1172720D01*
G01X1276628Y1169520D02*
X1270428D01*
G01X1276312Y1179813D02*
X1279512D01*
G01X1276312Y1173613D02*
Y1179813D01*
G01X1279512Y1173613D02*
X1276312D01*
G01X1279512Y1179813D02*
Y1173613D01*
G01X1272312Y1179813D02*
X1275512D01*
G01X1272312Y1173613D02*
Y1179813D01*
G01X1275512Y1173613D02*
X1272312D01*
G01X1275512Y1179813D02*
Y1173613D01*
G01X1272334Y1186726D02*
X1275534D01*
G01X1272334Y1180526D02*
Y1186726D01*
G01X1275534Y1180526D02*
X1272334D01*
G01X1275534Y1186726D02*
Y1180526D01*
G01X1276302Y1186763D02*
X1279502D01*
G01X1276302Y1180563D02*
Y1186763D01*
G01X1279502Y1180563D02*
X1276302D01*
G01X1279502Y1186763D02*
Y1180563D01*
G01X1270428Y1172720D02*
X1276628D01*
G01X1270187Y1179765D02*
Y1173565D01*
G01X1270215Y1186730D02*
Y1180530D01*
G01X1278175Y1201918D02*
X1274975D01*
G01X1278175Y1208118D02*
Y1201918D01*
G01X1274975D02*
Y1208118D01*
G01X1282173Y1193894D02*
X1278973D01*
G01X1282173Y1200094D02*
Y1193894D01*
G01X1278973Y1200094D02*
X1282173D01*
G01X1278973Y1193894D02*
Y1200094D01*
G01X1278173Y1193894D02*
X1274973D01*
G01X1278173Y1200094D02*
Y1193894D01*
G01X1274973Y1200094D02*
X1278173D01*
G01X1274973Y1193894D02*
Y1200094D01*
G01X1282175Y1201918D02*
X1278975D01*
G01X1282175Y1208118D02*
Y1201918D01*
G01X1278975D02*
Y1208118D01*
G01X1270175D02*
Y1201918D01*
G01X1274175D02*
X1270975D01*
G01X1274175Y1208118D02*
Y1201918D01*
G01X1270975D02*
Y1208118D01*
G01X1270173Y1200094D02*
Y1193894D01*
G01X1274173D02*
X1270973D01*
G01X1274173Y1200094D02*
Y1193894D01*
G01X1270973Y1200094D02*
X1274173D01*
G01X1270973Y1193894D02*
Y1200094D01*
G01X1274975Y1208118D02*
X1278175D01*
G01X1278975D02*
X1282175D01*
G01X1270975D02*
X1274175D01*
G01X1272603Y1215639D02*
X1270341Y1213377D01*
G01X1275432Y1218468D02*
X1273170Y1216206D01*
G01X1271048Y1222852D02*
X1275432Y1218468D01*
G01X1275999Y1219035D02*
X1271615Y1223419D01*
G01X1278261Y1221297D02*
X1275999Y1219035D01*
G01X1273877Y1225681D02*
X1278261Y1221297D01*
G01X1281089Y1224125D02*
X1278827Y1221863D01*
G01X1276705Y1228509D02*
X1281089Y1224125D01*
G01X1274443Y1226247D02*
X1276705Y1228509D01*
G01X1278827Y1221863D02*
X1274443Y1226247D01*
G01X1271615Y1223419D02*
X1273877Y1225681D01*
G01X1272933Y1564843D02*
Y1690040D01*
G01X1283951Y1598668D02*
X1284751Y1599168D01*
X1285284Y1599768D01*
X1285551Y1600468D01*
X1285284Y1601268D01*
X1284751Y1601868D01*
X1283951Y1602468D01*
X1282884Y1602668D01*
X1277551D01*
G01X1285551Y1608668D02*
X1277551D01*
X1279151Y1607468D01*
G01X1285551D02*
Y1609868D01*
G01X1283951Y1614468D02*
X1284884Y1615068D01*
X1285418Y1615868D01*
X1285551Y1616768D01*
X1285418Y1617568D01*
X1284751Y1618368D01*
X1283951Y1618868D01*
X1283151Y1618968D01*
X1282218Y1618768D01*
X1281551Y1618068D01*
X1281284Y1617368D01*
Y1616468D01*
G01Y1617368D02*
X1280884Y1617968D01*
X1280218Y1618468D01*
X1279418Y1618668D01*
X1278618Y1618468D01*
X1277951Y1617968D01*
X1277551Y1617068D01*
X1277684Y1616168D01*
X1278218Y1615268D01*
G01X1296556Y-23656D02*
Y-40256D01*
X1286956D01*
Y-23656D01*
X1296556D01*
G01X1301885Y29093D02*
X1298685D01*
G01X1301885Y35293D02*
Y29093D01*
G01X1298685Y35293D02*
X1301885D01*
G01X1298685Y29093D02*
Y35293D01*
G01X1300629Y82540D02*
Y85740D01*
G01X1306829Y82540D02*
X1300629D01*
G01Y74540D02*
Y77740D01*
G01X1306829Y74540D02*
X1300629D01*
G01Y77740D02*
X1306829D01*
G01X1300629Y78540D02*
Y81740D01*
G01X1306829Y78540D02*
X1300629D01*
G01Y81740D02*
X1306829D01*
G01X1300629Y85740D02*
X1306829D01*
G01X1290236Y97026D02*
Y103226D01*
G01X1293436Y97026D02*
X1290236D01*
G01X1293436Y103226D02*
Y97026D01*
G01X1300240Y86929D02*
X1297040D01*
G01X1300240Y93129D02*
Y86929D01*
G01X1297040Y93129D02*
X1300240D01*
G01X1297040Y86929D02*
Y93129D01*
G01X1296240Y86929D02*
X1293040D01*
G01X1296240Y93129D02*
Y86929D01*
G01X1293040Y93129D02*
X1296240D01*
G01X1293040Y86929D02*
Y93129D01*
G01X1304249Y86929D02*
X1301049D01*
G01Y93129D02*
X1304249D01*
G01X1301049Y86929D02*
Y93129D01*
G01X1292240Y86929D02*
X1289040D01*
G01X1292240Y93129D02*
Y86929D01*
G01X1289040Y93129D02*
X1292240D01*
G01X1289040Y86929D02*
Y93129D01*
G01X1296319Y96673D02*
Y102873D01*
G01X1299519Y96673D02*
X1296319D01*
G01X1299519Y102873D02*
Y96673D01*
G01X1300319D02*
Y102873D01*
G01X1303519Y96673D02*
X1300319D01*
G01X1290236Y103226D02*
X1293436D01*
G01X1296319Y102873D02*
X1299519D01*
G01X1300319D02*
X1303519D01*
G01X1291604Y164436D02*
Y195440D01*
G01X1300570Y171473D02*
X1297370D01*
G01X1300570Y177673D02*
Y171473D01*
G01X1297370Y177673D02*
X1300570D01*
G01X1297370Y171473D02*
Y177673D01*
G01X1297393Y170297D02*
X1303593D01*
G01X1297393Y167097D02*
Y170297D01*
G01X1303593Y167097D02*
X1297393D01*
G01X1296570Y171473D02*
X1293370D01*
G01X1296570Y177673D02*
Y171473D01*
G01X1293370Y177673D02*
X1296570D01*
G01X1293370Y171473D02*
Y177673D01*
G01X1300797Y182730D02*
X1297597D01*
G01X1300797Y188930D02*
Y182730D01*
G01X1297597Y188930D02*
X1300797D01*
G01X1297597Y182730D02*
Y188930D01*
G01X1297588Y193541D02*
X1303788D01*
G01X1297588Y190341D02*
Y193541D01*
G01X1303788Y190341D02*
X1297588D01*
G01X1288917Y213035D02*
Y225035D01*
G01X1294917Y213035D02*
X1288917D01*
G01X1294917Y225035D02*
Y213035D01*
G01X1286855Y233011D02*
Y203452D01*
G01X1288917Y225035D02*
X1294917D01*
G01X1295757Y226621D02*
Y232621D01*
G01X1307757Y226621D02*
X1295757D01*
G01X1299736Y215082D02*
X1296536D01*
G01X1299736Y221282D02*
Y215082D01*
G01X1296536Y221282D02*
X1299736D01*
G01X1296536Y215082D02*
Y221282D01*
G01X1299557Y225921D02*
X1305757D01*
G01X1299557Y222721D02*
Y225921D01*
G01X1305757Y222721D02*
X1299557D01*
G01X1295757Y232621D02*
X1307757D01*
G01X1288200Y250325D02*
Y234813D01*
G01D02*
X1319292D01*
G01X1286624Y292303D02*
Y262744D01*
G01X1288379Y251936D02*
Y255036D01*
X1289299D01*
X1289606Y254881D01*
X1289836Y254519D01*
X1289913Y254106D01*
X1289836Y253693D01*
X1289644Y253383D01*
X1289299Y253228D01*
X1288379D01*
G01X1291403Y251936D02*
Y255036D01*
X1292169D01*
X1292476Y254881D01*
X1292706Y254674D01*
X1292898Y254364D01*
X1293051Y254003D01*
X1293089Y253486D01*
X1293051Y252969D01*
X1292898Y252608D01*
X1292706Y252298D01*
X1292476Y252091D01*
X1292169Y251936D01*
X1291403D01*
G01X1295806D02*
Y255036D01*
X1294388Y252814D01*
X1296304D01*
G01X1297794Y252298D02*
X1298063Y252039D01*
X1298369Y251936D01*
X1298676Y252039D01*
X1298944Y252349D01*
X1299136Y252814D01*
X1299213Y253279D01*
Y253848D01*
X1299136Y254313D01*
X1298944Y254726D01*
X1298714Y254933D01*
X1298446Y255036D01*
X1298139Y254933D01*
X1297909Y254726D01*
X1297756Y254416D01*
X1297679Y254003D01*
X1297756Y253641D01*
X1297948Y253279D01*
X1298178Y253073D01*
X1298446Y253021D01*
X1298753Y253124D01*
X1298983Y253383D01*
X1299213Y253848D01*
G01X1319292Y250325D02*
X1288200D01*
G01X1296425Y258010D02*
Y264210D01*
G01X1299625Y258010D02*
X1296425D01*
G01X1299625Y264210D02*
Y258010D01*
G01X1303625D02*
X1300425D01*
G01D02*
Y264210D01*
G01X1288495Y271655D02*
Y283655D01*
G01X1294495Y271655D02*
X1288495D01*
G01X1294495Y283655D02*
Y271655D01*
G01X1296425Y264210D02*
X1299625D01*
G01X1300425D02*
X1303625D01*
G01X1297384Y267653D02*
Y279427D01*
G01X1307146Y267653D02*
X1297384D01*
G01X1288495Y283655D02*
X1294495D01*
G01X1298678Y283383D02*
X1295478D01*
G01X1298678Y289583D02*
Y283383D01*
G01X1295478Y289583D02*
X1298678D01*
G01X1295478Y283383D02*
Y289583D01*
G01X1302678Y283383D02*
X1299478D01*
G01Y289583D02*
X1302678D01*
G01X1299478Y283383D02*
Y289583D01*
G01X1297384Y279427D02*
X1307146D01*
G01X1293100Y319900D02*
X1289900D01*
G01X1293100Y326100D02*
Y319900D01*
G01X1289900Y326100D02*
X1293100D01*
G01X1289900Y319900D02*
Y326100D01*
G01X1300100Y328100D02*
Y324900D01*
G01X1293900D02*
Y328100D01*
G01X1300100Y324900D02*
X1293900D01*
G01Y328100D02*
X1300100D01*
G01Y338600D02*
Y335400D01*
G01X1293900Y338600D02*
X1300100D01*
G01X1293900Y335400D02*
Y338600D01*
G01X1300100Y335400D02*
X1293900D01*
G01X1300100Y331600D02*
Y328400D01*
G01X1293900Y331600D02*
X1300100D01*
G01X1293900Y328400D02*
Y331600D01*
G01X1300100Y328400D02*
X1293900D01*
G01X1300100Y335100D02*
Y331900D01*
G01X1293900Y335100D02*
X1300100D01*
G01X1293900Y331900D02*
Y335100D01*
G01X1300100Y331900D02*
X1293900D01*
G01X1301113Y353754D02*
X1311313D01*
G01X1301113Y349154D02*
Y353754D01*
G01X1311313Y349154D02*
X1301113D01*
G01Y354654D02*
Y359254D01*
G01X1311313Y354654D02*
X1301113D01*
G01Y359254D02*
X1311313D01*
G01X1301810Y371954D02*
Y378154D01*
G01X1305010Y371954D02*
X1301810D01*
G01X1293010Y372155D02*
X1289810D01*
G01X1293010Y378355D02*
Y372155D01*
G01X1289810D02*
Y378355D01*
G01X1293810Y371954D02*
Y378154D01*
G01X1297010Y371954D02*
X1293810D01*
G01X1297010Y378154D02*
Y371954D01*
G01X1301010Y378154D02*
Y371954D01*
X1297810D01*
Y378154D01*
X1301010D01*
G01X1301810D02*
X1305010D01*
G01X1289810Y378355D02*
X1293010D01*
G01X1293810Y378154D02*
X1297010D01*
G01X1290696Y385018D02*
X1287596D01*
Y385938D01*
X1287751Y386245D01*
X1288113Y386475D01*
X1288526Y386552D01*
X1288939Y386475D01*
X1289249Y386283D01*
X1289404Y385938D01*
Y385018D01*
G01X1287596Y388042D02*
X1289818D01*
X1290283Y388195D01*
X1290593Y388502D01*
X1290696Y388885D01*
X1290593Y389268D01*
X1290283Y389575D01*
X1289818Y389728D01*
X1287596D01*
G01X1288113Y391257D02*
X1287803Y391487D01*
X1287648Y391755D01*
X1287596Y392062D01*
X1287699Y392445D01*
X1287958Y392713D01*
X1288268Y392790D01*
X1288578Y392752D01*
X1288836Y392598D01*
X1289353Y391832D01*
X1289714Y391487D01*
X1290231Y391257D01*
X1290696Y391180D01*
Y392790D01*
G01X1290231Y394242D02*
X1290489Y394472D01*
X1290644Y394740D01*
X1290696Y395085D01*
X1290593Y395430D01*
X1290386Y395698D01*
X1290024Y395890D01*
X1289611Y395928D01*
X1289198Y395852D01*
X1288939Y395660D01*
X1288733Y395392D01*
X1288681Y395123D01*
X1288733Y394855D01*
X1288939Y394510D01*
X1287596Y394625D01*
Y395660D01*
G01X1304657Y381986D02*
X1292453D01*
Y397290D01*
X1304657D01*
Y381986D01*
G01X1297440Y405142D02*
Y411142D01*
G01X1309440Y405142D02*
X1297440D01*
G01X1299487Y400323D02*
Y403523D01*
G01X1305687Y400323D02*
X1299487D01*
G01Y403523D02*
X1305687D01*
G01X1297440Y411142D02*
X1309440D01*
G01X1288183Y426000D02*
Y429100D01*
X1289103D01*
X1289410Y428945D01*
X1289640Y428583D01*
X1289717Y428170D01*
X1289640Y427757D01*
X1289448Y427447D01*
X1289103Y427292D01*
X1288183D01*
G01X1291207Y426000D02*
Y429100D01*
X1291973D01*
X1292280Y428945D01*
X1292510Y428738D01*
X1292702Y428428D01*
X1292855Y428067D01*
X1292893Y427550D01*
X1292855Y427033D01*
X1292702Y426672D01*
X1292510Y426362D01*
X1292280Y426155D01*
X1291973Y426000D01*
X1291207D01*
G01X1295150D02*
Y429100D01*
X1294690Y428480D01*
G01Y426000D02*
X1295610D01*
G01X1298250D02*
Y429100D01*
X1297790Y428480D01*
G01Y426000D02*
X1298710D01*
G01X1287857Y413204D02*
Y424700D01*
G01X1317416Y413204D02*
X1287857D01*
G01Y424700D02*
X1317416D01*
G01X1304448Y425620D02*
Y428046D01*
G01X1291092Y438502D02*
Y450502D01*
G01X1297092Y438502D02*
X1291092D01*
G01X1297092Y450502D02*
Y438502D01*
G01X1289092Y450502D02*
Y438502D01*
G01X1310496Y429160D02*
X1299000D01*
G01D02*
Y458719D01*
G01X1291092Y450502D02*
X1297092D01*
G01X1289297Y459909D02*
Y456709D01*
G01Y455909D02*
Y452709D01*
G01X1304348Y462360D02*
Y460120D01*
G01X1305973Y461333D02*
X1302723D01*
G01X1299000Y458719D02*
X1310496D01*
G01X1300741Y464809D02*
Y468009D01*
G01X1306941Y464809D02*
X1300741D01*
G01Y468009D02*
X1306941D01*
G01X1289297Y463909D02*
Y460709D01*
G01X1300741Y471982D02*
X1306941D01*
G01X1300741Y468782D02*
Y471982D01*
G01X1306941Y468782D02*
X1300741D01*
G01Y472782D02*
Y475982D01*
G01X1306941Y472782D02*
X1300741D01*
G01Y485782D02*
Y488982D01*
G01X1306941Y485782D02*
X1300741D01*
G01Y488982D02*
X1306941D01*
G01X1287173Y490416D02*
Y487216D01*
G01X1300741Y480782D02*
Y483982D01*
G01X1306941Y480782D02*
X1300741D01*
G01Y483982D02*
X1306941D01*
G01X1300741Y475982D02*
X1306941D01*
G01X1300741Y479982D02*
X1306941D01*
Y476782D01*
X1300741D01*
Y479982D01*
G01X1289173Y497216D02*
Y491216D01*
G01X1301504Y746927D02*
X1318020D01*
G01X1301504Y778029D02*
Y746927D01*
G01X1286614Y770176D02*
Y766976D01*
G01Y778176D02*
Y774976D01*
G01Y774176D02*
Y770976D01*
G01Y782176D02*
Y778976D01*
G01X1304211Y778029D02*
X1301504D01*
G01X1293966Y794721D02*
Y797921D01*
G01X1300166Y794721D02*
X1293966D01*
G01X1300166Y797921D02*
Y794721D01*
G01X1293966Y797921D02*
X1300166D01*
G01X1286614Y786176D02*
Y782976D01*
G01X1308365Y800203D02*
X1295767D01*
G01Y810439D02*
X1308365D01*
G01X1295767Y800203D02*
Y810439D01*
G01X1290966Y808921D02*
X1294166D01*
G01X1290966Y802721D02*
Y808921D01*
G01X1294166Y802721D02*
X1290966D01*
G01X1294166Y808921D02*
Y802721D01*
G01X1297309Y813992D02*
Y820192D01*
G01X1300509Y813992D02*
X1297309D01*
G01X1300509Y820192D02*
Y813992D01*
G01X1297309Y820192D02*
X1300509D01*
G01X1286400Y825900D02*
Y829100D01*
G01X1292600Y825900D02*
X1286400D01*
G01X1292600Y829100D02*
Y825900D01*
G01X1286400Y829100D02*
X1292600D01*
G01X1286400Y829900D02*
Y833100D01*
G01X1292600Y829900D02*
X1286400D01*
G01X1292600Y833100D02*
Y829900D01*
G01X1286400Y821900D02*
Y825100D01*
G01X1292600Y821900D02*
X1286400D01*
G01X1292600Y825100D02*
Y821900D01*
G01X1286400Y825100D02*
X1292600D01*
G01Y821100D02*
Y817900D01*
G01X1286400Y821100D02*
X1292600D01*
G01X1286400Y817900D02*
Y821100D01*
G01X1292600Y817900D02*
X1286400D01*
G01Y833100D02*
X1292600D01*
G01Y841100D02*
Y837900D01*
G01X1286400Y841100D02*
X1292600D01*
G01X1286400Y837900D02*
Y841100D01*
G01X1292600Y837900D02*
X1286400D01*
G01X1292600Y845100D02*
Y841900D01*
G01X1286400Y845100D02*
X1292600D01*
G01X1286400Y841900D02*
Y845100D01*
G01X1292600Y841900D02*
X1286400D01*
G01X1292600Y849100D02*
Y845900D01*
G01X1286400D02*
Y849100D01*
G01X1292600Y845900D02*
X1286400D01*
G01Y833900D02*
Y837100D01*
G01X1292600Y833900D02*
X1286400D01*
G01X1292600Y837100D02*
Y833900D01*
G01X1286400Y837100D02*
X1292600D01*
G01Y853100D02*
Y849900D01*
G01X1286400Y853100D02*
X1292600D01*
G01X1286400Y849900D02*
Y853100D01*
G01X1292600Y849900D02*
X1286400D01*
G01X1292600Y865100D02*
Y861900D01*
G01X1286400D02*
Y865100D01*
G01X1292600Y861900D02*
X1286400D01*
G01Y857900D02*
Y861100D01*
G01X1292600Y857900D02*
X1286400D01*
G01X1292600Y861100D02*
Y857900D01*
G01X1286400Y861100D02*
X1292600D01*
G01X1286400Y853900D02*
Y857100D01*
G01X1292600Y853900D02*
X1286400D01*
G01X1292600Y857100D02*
Y853900D01*
G01X1286400Y857100D02*
X1292600D01*
G01X1286400Y849100D02*
X1292600D01*
G01X1286400Y865100D02*
X1292600D01*
G01Y868600D02*
Y865400D01*
G01X1286400Y868600D02*
X1292600D01*
G01X1286400Y865400D02*
Y868600D01*
G01X1292600Y865400D02*
X1286400D01*
G01X1286395Y880183D02*
Y883383D01*
G01X1292595Y880183D02*
X1286395D01*
G01X1292595Y883383D02*
Y880183D01*
G01X1286395Y876183D02*
Y879383D01*
G01X1292595Y876183D02*
X1286395D01*
G01X1292595Y879383D02*
Y876183D01*
G01X1286395Y879383D02*
X1292595D01*
G01X1293600Y893400D02*
X1290400D01*
G01X1293600Y899600D02*
Y893400D01*
G01X1290400D02*
Y899600D01*
G01X1286395Y883383D02*
X1292595D01*
G01Y887383D02*
Y884183D01*
G01X1286395Y887383D02*
X1292595D01*
G01X1286395Y884183D02*
Y887383D01*
G01X1292595Y884183D02*
X1286395D01*
G01X1286555Y893400D02*
Y899600D01*
G01X1289755Y893400D02*
X1286555D01*
G01X1289755Y899600D02*
Y893400D01*
G01X1286395Y888167D02*
Y891367D01*
G01X1292595Y888167D02*
X1286395D01*
G01X1292595Y891367D02*
Y888167D01*
G01X1286395Y891367D02*
X1292595D01*
G01X1295500Y902907D02*
X1297722D01*
X1298187Y903060D01*
X1298497Y903367D01*
X1298600Y903750D01*
X1298497Y904133D01*
X1298187Y904440D01*
X1297722Y904593D01*
X1295500D01*
G01X1297980Y906007D02*
X1298342Y906237D01*
X1298548Y906543D01*
X1298600Y906888D01*
X1298548Y907195D01*
X1298290Y907502D01*
X1297980Y907693D01*
X1297670Y907732D01*
X1297308Y907655D01*
X1297050Y907387D01*
X1296947Y907118D01*
Y906773D01*
G01Y907118D02*
X1296792Y907348D01*
X1296533Y907540D01*
X1296223Y907617D01*
X1295913Y907540D01*
X1295655Y907348D01*
X1295500Y907003D01*
X1295552Y906658D01*
X1295758Y906313D01*
G01X1297980Y909107D02*
X1298342Y909337D01*
X1298548Y909643D01*
X1298600Y909988D01*
X1298548Y910295D01*
X1298290Y910602D01*
X1297980Y910793D01*
X1297670Y910832D01*
X1297308Y910755D01*
X1297050Y910487D01*
X1296947Y910218D01*
Y909873D01*
G01Y910218D02*
X1296792Y910448D01*
X1296533Y910640D01*
X1296223Y910717D01*
X1295913Y910640D01*
X1295655Y910448D01*
X1295500Y910103D01*
X1295552Y909758D01*
X1295758Y909413D01*
G01X1297308Y912322D02*
X1296947Y912590D01*
X1296740Y912820D01*
X1296637Y913127D01*
X1296740Y913395D01*
X1296947Y913587D01*
X1297257Y913740D01*
X1297618Y913778D01*
X1297928Y913740D01*
X1298238Y913587D01*
X1298497Y913357D01*
X1298600Y913088D01*
X1298497Y912782D01*
X1298187Y912513D01*
X1297722Y912360D01*
X1297205Y912322D01*
X1296533Y912398D01*
X1296172Y912513D01*
X1295810Y912705D01*
X1295552Y912973D01*
X1295500Y913242D01*
X1295603Y913510D01*
X1295862Y913702D01*
G01X1292732Y915631D02*
Y902369D01*
G01X1290400Y899600D02*
X1293600D01*
G01X1286555D02*
X1289755D01*
G01X1300400Y924600D02*
X1303600D01*
G01X1300400Y918400D02*
Y924600D01*
G01X1303600Y918400D02*
X1300400D01*
G01X1296400Y924600D02*
X1299600D01*
G01X1296400Y918400D02*
Y924600D01*
G01X1299600Y918400D02*
X1296400D01*
G01X1299600Y924600D02*
Y918400D01*
G01X1289400Y917900D02*
Y921100D01*
G01X1295600Y917900D02*
X1289400D01*
G01X1295600Y921100D02*
Y917900D01*
G01X1289400Y921100D02*
X1295600D01*
G01X1288600D02*
Y917900D01*
G01X1287776Y936500D02*
Y939918D01*
G01X1289500Y934500D02*
X1287776Y936500D01*
G01Y932500D02*
X1289500Y934500D01*
G01X1287776Y929082D02*
Y932500D01*
G01X1297224Y929082D02*
X1287776D01*
G01X1297224Y939918D02*
Y929082D01*
G01X1287776Y939918D02*
X1297224D01*
G01X1299400Y944100D02*
X1305600D01*
G01X1299400Y940900D02*
Y944100D01*
G01X1305600Y940900D02*
X1299400D01*
G01X1299282Y935664D02*
X1302482D01*
G01X1299282Y929464D02*
Y935664D01*
G01X1302482Y929464D02*
X1299282D01*
G01X1302482Y935664D02*
Y929464D01*
G01X1291100Y942400D02*
X1287900D01*
G01X1291100Y948600D02*
Y942400D01*
G01X1287900D02*
Y948600D01*
G01X1295300Y946107D02*
X1297522D01*
X1297987Y946260D01*
X1298297Y946567D01*
X1298400Y946950D01*
X1298297Y947333D01*
X1297987Y947640D01*
X1297522Y947793D01*
X1295300D01*
G01X1298400Y950050D02*
X1295300D01*
X1295920Y949590D01*
G01X1298400D02*
Y950510D01*
G01Y953610D02*
X1295300D01*
X1297522Y952192D01*
Y954108D01*
G01X1297780Y955407D02*
X1298142Y955637D01*
X1298348Y955943D01*
X1298400Y956288D01*
X1298348Y956595D01*
X1298090Y956902D01*
X1297780Y957093D01*
X1297470Y957132D01*
X1297108Y957055D01*
X1296850Y956787D01*
X1296747Y956518D01*
Y956173D01*
G01Y956518D02*
X1296592Y956748D01*
X1296333Y956940D01*
X1296023Y957017D01*
X1295713Y956940D01*
X1295455Y956748D01*
X1295300Y956403D01*
X1295352Y956058D01*
X1295558Y955713D01*
G01X1299507Y945361D02*
Y958961D01*
G01D02*
X1308307D01*
G01Y945361D02*
X1299507D01*
G01X1287900Y948600D02*
X1291100D01*
G01X1298900Y968600D02*
X1302100D01*
G01X1298900Y962400D02*
Y968600D01*
G01X1302100Y962400D02*
X1298900D01*
G01X1302100Y968600D02*
Y962400D01*
G01X1298100D02*
X1294900D01*
G01X1298100Y968600D02*
Y962400D01*
G01X1294900Y968600D02*
X1298100D01*
G01X1294900Y962400D02*
Y968600D01*
G01X1288071Y984634D02*
Y996584D01*
G01X1298071Y984634D02*
X1288071D01*
G01X1298071Y986584D02*
Y984634D01*
G01Y1006584D02*
Y992684D01*
G01X1288071Y1002684D02*
Y1014634D01*
G01X1287854Y1016821D02*
X1288046Y1016511D01*
X1288276Y1016304D01*
X1288544Y1016201D01*
X1288851Y1016304D01*
X1289081Y1016511D01*
X1289311Y1016821D01*
X1289388Y1017234D01*
Y1019301D01*
G01X1290878Y1016666D02*
X1291108Y1016408D01*
X1291376Y1016253D01*
X1291721Y1016201D01*
X1292066Y1016304D01*
X1292334Y1016511D01*
X1292526Y1016873D01*
X1292564Y1017286D01*
X1292488Y1017699D01*
X1292296Y1017958D01*
X1292028Y1018164D01*
X1291759Y1018216D01*
X1291491Y1018164D01*
X1291146Y1017958D01*
X1291261Y1019301D01*
X1292296D01*
G01X1294093Y1017493D02*
X1294361Y1017854D01*
X1294591Y1018061D01*
X1294898Y1018164D01*
X1295166Y1018061D01*
X1295358Y1017854D01*
X1295511Y1017544D01*
X1295549Y1017183D01*
X1295511Y1016873D01*
X1295358Y1016563D01*
X1295128Y1016304D01*
X1294859Y1016201D01*
X1294553Y1016304D01*
X1294284Y1016614D01*
X1294131Y1017079D01*
X1294093Y1017596D01*
X1294169Y1018268D01*
X1294284Y1018629D01*
X1294476Y1018991D01*
X1294744Y1019249D01*
X1295013Y1019301D01*
X1295281Y1019198D01*
X1295473Y1018939D01*
G01X1298071Y1014634D02*
Y1012684D01*
G01X1288071Y1014634D02*
X1298071D01*
G01X1299738Y1121677D02*
Y1124777D01*
G01X1301348D02*
Y1121677D01*
G01Y1123227D02*
X1299738D01*
G01X1303643Y1121677D02*
Y1124777D01*
X1303183Y1124157D01*
G01Y1121677D02*
X1304103D01*
G01X1307203D02*
Y1124777D01*
X1305785Y1122555D01*
X1307701D01*
G01X1309843Y1124777D02*
X1309536Y1124674D01*
X1309306Y1124415D01*
X1309153Y1124105D01*
X1309038Y1123692D01*
X1309000Y1123227D01*
X1309038Y1122762D01*
X1309153Y1122349D01*
X1309306Y1122039D01*
X1309536Y1121780D01*
X1309843Y1121677D01*
X1310150Y1121780D01*
X1310380Y1122039D01*
X1310533Y1122349D01*
X1310648Y1122762D01*
X1310686Y1123227D01*
X1310648Y1123692D01*
X1310533Y1124105D01*
X1310380Y1124415D01*
X1310150Y1124674D01*
X1309843Y1124777D01*
G01X1288434Y1151945D02*
X1290656D01*
X1291121Y1152098D01*
X1291431Y1152405D01*
X1291534Y1152788D01*
X1291431Y1153171D01*
X1291121Y1153478D01*
X1290656Y1153631D01*
X1288434D01*
G01X1290914Y1155045D02*
X1291276Y1155275D01*
X1291482Y1155581D01*
X1291534Y1155926D01*
X1291482Y1156233D01*
X1291224Y1156540D01*
X1290914Y1156731D01*
X1290604Y1156770D01*
X1290242Y1156693D01*
X1289984Y1156425D01*
X1289881Y1156156D01*
Y1155811D01*
G01Y1156156D02*
X1289726Y1156386D01*
X1289467Y1156578D01*
X1289157Y1156655D01*
X1288847Y1156578D01*
X1288589Y1156386D01*
X1288434Y1156041D01*
X1288486Y1155696D01*
X1288692Y1155351D01*
G01X1291534Y1158988D02*
X1288434D01*
X1289054Y1158528D01*
G01X1291534D02*
Y1159448D01*
G01X1291069Y1161245D02*
X1291327Y1161475D01*
X1291482Y1161743D01*
X1291534Y1162088D01*
X1291431Y1162433D01*
X1291224Y1162701D01*
X1290862Y1162893D01*
X1290449Y1162931D01*
X1290036Y1162855D01*
X1289777Y1162663D01*
X1289571Y1162395D01*
X1289519Y1162126D01*
X1289571Y1161858D01*
X1289777Y1161513D01*
X1288434Y1161628D01*
Y1162663D01*
G01X1305693Y1422407D02*
X1305133Y1422782D01*
X1304480Y1423032D01*
X1303733D01*
X1302893Y1422657D01*
X1302240Y1422032D01*
X1301773Y1421282D01*
X1301400Y1420032D01*
X1301307Y1418907D01*
X1301493Y1417782D01*
X1301773Y1417032D01*
X1302333Y1416282D01*
X1302987Y1415782D01*
X1303640Y1415532D01*
X1304293D01*
X1304947Y1415782D01*
X1305507Y1416157D01*
X1305973Y1416657D01*
G01X1309273Y1415532D02*
Y1423032D01*
X1311513D01*
X1312260Y1422657D01*
X1312820Y1421782D01*
X1313007Y1420782D01*
X1312820Y1419782D01*
X1312353Y1419032D01*
X1311513Y1418657D01*
X1309273D01*
G01X1316587Y1423032D02*
Y1417657D01*
X1316960Y1416532D01*
X1317707Y1415782D01*
X1318640Y1415532D01*
X1319573Y1415782D01*
X1320320Y1416532D01*
X1320693Y1417657D01*
Y1423032D01*
G01X1323340Y1413032D02*
X1328940D01*
G01X1335693Y1422407D02*
X1335133Y1422782D01*
X1334480Y1423032D01*
X1333733D01*
X1332893Y1422657D01*
X1332240Y1422032D01*
X1331773Y1421282D01*
X1331400Y1420032D01*
X1331307Y1418907D01*
X1331493Y1417782D01*
X1331773Y1417032D01*
X1332333Y1416282D01*
X1332987Y1415782D01*
X1333640Y1415532D01*
X1334293D01*
X1334947Y1415782D01*
X1335507Y1416157D01*
X1335973Y1416657D01*
G01X1288347Y1425158D02*
Y1689331D01*
G01X1401339Y1425158D02*
X1288347D01*
G01X1300158Y1677520D02*
Y1436969D01*
G01D02*
X1389528D01*
G01X1300158Y1647993D02*
X1389528D01*
G01X1288347Y1689331D02*
X1401339D01*
G01X1389528Y1677520D02*
X1300158D01*
G01X1317863Y-60739D02*
Y-57639D01*
X1318629D01*
X1318936Y-57794D01*
X1319166Y-58001D01*
X1319358Y-58311D01*
X1319511Y-58672D01*
X1319549Y-59189D01*
X1319511Y-59706D01*
X1319358Y-60067D01*
X1319166Y-60377D01*
X1318936Y-60584D01*
X1318629Y-60739D01*
X1317863D01*
G01X1322573D02*
X1321039D01*
Y-57639D01*
X1322573D01*
G01X1321959Y-59137D02*
X1321039D01*
G01X1324906Y-57639D02*
X1324599Y-57742D01*
X1324369Y-58001D01*
X1324216Y-58311D01*
X1324101Y-58724D01*
X1324063Y-59189D01*
X1324101Y-59654D01*
X1324216Y-60067D01*
X1324369Y-60377D01*
X1324599Y-60636D01*
X1324906Y-60739D01*
X1325213Y-60636D01*
X1325443Y-60377D01*
X1325596Y-60067D01*
X1325711Y-59654D01*
X1325749Y-59189D01*
X1325711Y-58724D01*
X1325596Y-58311D01*
X1325443Y-58001D01*
X1325213Y-57742D01*
X1324906Y-57639D01*
G01X1328466Y-60739D02*
Y-57639D01*
X1327048Y-59861D01*
X1328964D01*
G01X1330378Y-60739D02*
Y-57639D01*
X1331834D01*
G01X1331298Y-59137D02*
X1330378D01*
G01X1333056Y-61772D02*
X1335356D01*
G01X1336578Y-58156D02*
X1336808Y-57846D01*
X1337076Y-57691D01*
X1337383Y-57639D01*
X1337766Y-57742D01*
X1338034Y-58001D01*
X1338111Y-58311D01*
X1338073Y-58621D01*
X1337919Y-58879D01*
X1337153Y-59396D01*
X1336808Y-59757D01*
X1336578Y-60274D01*
X1336501Y-60739D01*
X1338111D01*
G01X1310507Y21900D02*
Y19678D01*
X1310660Y19213D01*
X1310967Y18903D01*
X1311350Y18800D01*
X1311733Y18903D01*
X1312040Y19213D01*
X1312193Y19678D01*
Y21900D01*
G01X1314450Y18800D02*
Y21900D01*
X1313990Y21280D01*
G01Y18800D02*
X1314910D01*
G01X1316707Y19420D02*
X1316937Y19058D01*
X1317243Y18852D01*
X1317588Y18800D01*
X1317895Y18852D01*
X1318202Y19110D01*
X1318393Y19420D01*
X1318432Y19730D01*
X1318355Y20092D01*
X1318087Y20350D01*
X1317818Y20453D01*
X1317473D01*
G01X1317818D02*
X1318048Y20608D01*
X1318240Y20867D01*
X1318317Y21177D01*
X1318240Y21487D01*
X1318048Y21745D01*
X1317703Y21900D01*
X1317358Y21848D01*
X1317013Y21642D01*
G01X1320573Y18800D02*
X1320650Y19472D01*
X1320765Y20040D01*
X1320918Y20557D01*
X1321110Y21125D01*
X1321417Y21900D01*
X1319883D01*
G01X1309795Y23786D02*
Y35990D01*
G01X1321319Y23786D02*
X1309795D01*
G01X1315557Y32888D02*
X1318557Y35990D01*
G01X1312455D02*
X1315557Y32888D01*
G01X1318557Y35990D02*
X1321319D01*
G01X1309795D02*
X1312455D01*
G01X1313259Y44573D02*
X1316459D01*
G01X1313259Y38373D02*
Y44573D01*
G01X1316459Y38373D02*
X1313259D01*
G01X1316459Y44573D02*
Y38373D01*
G01X1317259Y44573D02*
X1320459D01*
G01X1317259Y38373D02*
Y44573D01*
G01X1320459Y38373D02*
X1317259D01*
G01X1312453Y38418D02*
X1309253D01*
G01X1312453Y44618D02*
Y38418D01*
G01X1309253Y44618D02*
X1312453D01*
G01X1309253Y38418D02*
Y44618D01*
G01X1306829Y85740D02*
Y82540D01*
G01Y77740D02*
Y74540D01*
G01Y81740D02*
Y78540D01*
G01X1304249Y93129D02*
Y86929D01*
G01X1305823Y95950D02*
Y102150D01*
G01X1309023Y95950D02*
X1305823D01*
G01X1309023Y102150D02*
Y95950D01*
G01X1303519Y102873D02*
Y96673D01*
G01X1310487Y95913D02*
Y111267D01*
G01X1322968Y95913D02*
X1310487D01*
G01X1305823Y102150D02*
X1309023D01*
G01X1316838Y116088D02*
X1323038D01*
G01X1316838Y112888D02*
Y116088D01*
G01X1323038Y112888D02*
X1316838D01*
G01X1305823Y109762D02*
X1309023D01*
G01X1305823Y103562D02*
Y109762D01*
G01X1309023Y103562D02*
X1305823D01*
G01X1309023Y109762D02*
Y103562D01*
G01X1310487Y111267D02*
X1323165D01*
G01X1305857Y175100D02*
Y172878D01*
X1306010Y172413D01*
X1306317Y172103D01*
X1306700Y172000D01*
X1307083Y172103D01*
X1307390Y172413D01*
X1307543Y172878D01*
Y175100D01*
G01X1309723Y172000D02*
X1309800Y172672D01*
X1309915Y173240D01*
X1310068Y173757D01*
X1310260Y174325D01*
X1310567Y175100D01*
X1309033D01*
G01X1313360Y172000D02*
Y175100D01*
X1311942Y172878D01*
X1313858D01*
G01X1317110Y176944D02*
X1315157D01*
G01X1305298D02*
Y178897D01*
G01X1307251Y176944D02*
X1305298D01*
G01X1317110Y178897D02*
Y176944D01*
G01X1313102Y170313D02*
X1319302D01*
G01X1313102Y167113D02*
Y170313D01*
G01X1319302Y167113D02*
X1313102D01*
G01X1303593Y170297D02*
Y167097D01*
G01X1317110Y188756D02*
Y186803D01*
G01X1315157Y188756D02*
X1317110D01*
G01X1305298D02*
X1307251D01*
G01X1305298Y186803D02*
Y188756D01*
G01X1303788Y193541D02*
Y190341D01*
G01X1314157Y195020D02*
Y198220D01*
G01X1320357Y195020D02*
X1314157D01*
G01Y198220D02*
X1320357D01*
G01X1303071Y201041D02*
Y204141D01*
X1303991D01*
X1304298Y203986D01*
X1304528Y203624D01*
X1304605Y203211D01*
X1304528Y202798D01*
X1304336Y202488D01*
X1303991Y202333D01*
X1303071D01*
G01X1306095Y204141D02*
Y201919D01*
X1306248Y201454D01*
X1306555Y201144D01*
X1306938Y201041D01*
X1307321Y201144D01*
X1307628Y201454D01*
X1307781Y201919D01*
Y204141D01*
G01X1310498Y201041D02*
Y204141D01*
X1309080Y201919D01*
X1310996D01*
G01X1313598Y201041D02*
Y204141D01*
X1312180Y201919D01*
X1314096D01*
G01X1318073Y220252D02*
Y208048D01*
X1302769D01*
Y220252D01*
X1318073D01*
G01X1307757Y232621D02*
Y226621D01*
G01X1305757Y225921D02*
Y222721D01*
G01X1304425Y258010D02*
Y264210D01*
G01X1307625Y258010D02*
X1304425D01*
G01X1307625Y264210D02*
Y258010D01*
G01X1303625Y264210D02*
Y258010D01*
G01X1314336Y264635D02*
X1329848D01*
G01X1314336Y295727D02*
Y264635D01*
G01X1304425Y264210D02*
X1307625D01*
G01X1312704Y273701D02*
X1309504D01*
G01X1312704Y279901D02*
Y273701D01*
G01X1309504D02*
Y279901D01*
G01X1307146Y279427D02*
Y267653D01*
G01X1309504Y279901D02*
X1312704D01*
G01X1302678Y289583D02*
Y283383D01*
G01X1303478D02*
Y289583D01*
X1306678D01*
Y283383D01*
X1303478D01*
G01X1311000Y282433D02*
X1307900D01*
Y283353D01*
X1308055Y283660D01*
X1308417Y283890D01*
X1308830Y283967D01*
X1309243Y283890D01*
X1309553Y283698D01*
X1309708Y283353D01*
Y282433D01*
G01X1307900Y285457D02*
X1310122D01*
X1310587Y285610D01*
X1310897Y285917D01*
X1311000Y286300D01*
X1310897Y286683D01*
X1310587Y286990D01*
X1310122Y287143D01*
X1307900D01*
G01X1311000Y289400D02*
X1307900D01*
X1308520Y288940D01*
G01X1311000D02*
Y289860D01*
G01Y292500D02*
X1307900D01*
X1308520Y292040D01*
G01X1311000D02*
Y292960D01*
G01X1310380Y294757D02*
X1310742Y294987D01*
X1310948Y295293D01*
X1311000Y295638D01*
X1310948Y295945D01*
X1310690Y296252D01*
X1310380Y296443D01*
X1310070Y296482D01*
X1309708Y296405D01*
X1309450Y296137D01*
X1309347Y295868D01*
Y295523D01*
G01Y295868D02*
X1309192Y296098D01*
X1308933Y296290D01*
X1308623Y296367D01*
X1308313Y296290D01*
X1308055Y296098D01*
X1307900Y295753D01*
X1307952Y295408D01*
X1308158Y295063D01*
G01X1329848Y295727D02*
X1314336D01*
G01X1316662Y314253D02*
X1318739D01*
G01X1316662Y320453D02*
X1318729D01*
G01X1316662Y314253D02*
Y320453D01*
G01X1311313Y353754D02*
Y349154D01*
G01Y359254D02*
Y354654D01*
G01X1305010Y378154D02*
Y371954D01*
G01X1306810Y371956D02*
Y378156D01*
G01X1310010Y371956D02*
X1306810D01*
G01X1310010Y378156D02*
Y371956D01*
G01X1314010D02*
X1310810D01*
G01X1314010Y378156D02*
Y371956D01*
G01X1310810D02*
Y378156D01*
G01X1315303Y369841D02*
X1318503D01*
G01X1315303Y363641D02*
Y369841D01*
G01X1318503Y363641D02*
X1315303D01*
G01X1318503Y369841D02*
Y363641D01*
G01X1317026Y401302D02*
Y389302D01*
G01X1311026D02*
Y401302D01*
G01X1317026Y389302D02*
X1311026D01*
G01X1306810Y378156D02*
X1310010D01*
G01X1310326Y391302D02*
X1307126D01*
G01X1310326Y397502D02*
Y391302D01*
G01X1307126D02*
Y397502D01*
G01X1310810Y378156D02*
X1314010D01*
G01X1309440Y411142D02*
Y405142D01*
G01X1311026Y401302D02*
X1317026D01*
G01X1305687Y403523D02*
Y400323D01*
G01X1307126Y397502D02*
X1310326D01*
G01X1320443Y424095D02*
X1318203D01*
G01X1319416Y422470D02*
Y425720D01*
G01X1317416Y424700D02*
Y413204D01*
G01X1314800Y429183D02*
X1311700D01*
Y430103D01*
X1311855Y430410D01*
X1312217Y430640D01*
X1312630Y430717D01*
X1313043Y430640D01*
X1313353Y430448D01*
X1313508Y430103D01*
Y429183D01*
G01X1314800Y432207D02*
X1311700D01*
Y432973D01*
X1311855Y433280D01*
X1312062Y433510D01*
X1312372Y433702D01*
X1312733Y433855D01*
X1313250Y433893D01*
X1313767Y433855D01*
X1314128Y433702D01*
X1314438Y433510D01*
X1314645Y433280D01*
X1314800Y432973D01*
Y432207D01*
G01X1314438Y435498D02*
X1314697Y435767D01*
X1314800Y436073D01*
X1314697Y436380D01*
X1314387Y436648D01*
X1313922Y436840D01*
X1313457Y436917D01*
X1312888D01*
X1312423Y436840D01*
X1312010Y436648D01*
X1311803Y436418D01*
X1311700Y436150D01*
X1311803Y435843D01*
X1312010Y435613D01*
X1312320Y435460D01*
X1312733Y435383D01*
X1313095Y435460D01*
X1313457Y435652D01*
X1313663Y435882D01*
X1313715Y436150D01*
X1313612Y436457D01*
X1313353Y436687D01*
X1312888Y436917D01*
G01X1314335Y438407D02*
X1314593Y438637D01*
X1314748Y438905D01*
X1314800Y439250D01*
X1314697Y439595D01*
X1314490Y439863D01*
X1314128Y440055D01*
X1313715Y440093D01*
X1313302Y440017D01*
X1313043Y439825D01*
X1312837Y439557D01*
X1312785Y439288D01*
X1312837Y439020D01*
X1313043Y438675D01*
X1311700Y438790D01*
Y439825D01*
G01X1310496Y458719D02*
Y429160D01*
G01X1322646Y447001D02*
X1318046D01*
G01Y457201D02*
X1322646D01*
G01X1318046Y447001D02*
Y457201D01*
G01X1316938Y443937D02*
X1313738D01*
G01X1316938Y450137D02*
Y443937D01*
G01X1313738Y450137D02*
X1316938D01*
G01X1313738Y443937D02*
Y450137D01*
G01X1306941Y468009D02*
Y464809D01*
G01Y471982D02*
Y468782D01*
G01X1318574Y469160D02*
Y465960D01*
G01X1312374Y469160D02*
X1318574D01*
G01X1312374Y465960D02*
Y469160D01*
G01X1318574Y465960D02*
X1312374D01*
G01Y469960D02*
Y473160D01*
G01X1318574Y469960D02*
X1312374D01*
G01X1318574Y473160D02*
Y469960D01*
G01X1312374Y473160D02*
X1318574D01*
G01X1306941Y475982D02*
Y472782D01*
G01X1312374Y473960D02*
Y477160D01*
G01X1318574Y473960D02*
X1312374D01*
G01X1318574Y477160D02*
Y473960D01*
G01X1306941Y488982D02*
Y485782D01*
G01Y483982D02*
Y480782D01*
G01X1318574Y481160D02*
Y477960D01*
G01X1312374Y481160D02*
X1318574D01*
G01X1312374Y477960D02*
Y481160D01*
G01X1318574Y477960D02*
X1312374D01*
G01Y477160D02*
X1318574D01*
G01X1318020Y746927D02*
Y778029D01*
G01X1304907Y783100D02*
Y780878D01*
X1305060Y780413D01*
X1305367Y780103D01*
X1305750Y780000D01*
X1306133Y780103D01*
X1306440Y780413D01*
X1306593Y780878D01*
Y783100D01*
G01X1308007Y780620D02*
X1308237Y780258D01*
X1308543Y780052D01*
X1308888Y780000D01*
X1309195Y780052D01*
X1309502Y780310D01*
X1309693Y780620D01*
X1309732Y780930D01*
X1309655Y781292D01*
X1309387Y781550D01*
X1309118Y781653D01*
X1308773D01*
G01X1309118D02*
X1309348Y781808D01*
X1309540Y782067D01*
X1309617Y782377D01*
X1309540Y782687D01*
X1309348Y782945D01*
X1309003Y783100D01*
X1308658Y783048D01*
X1308313Y782842D01*
G01X1311222Y782583D02*
X1311452Y782893D01*
X1311720Y783048D01*
X1312027Y783100D01*
X1312410Y782997D01*
X1312678Y782738D01*
X1312755Y782428D01*
X1312717Y782118D01*
X1312563Y781860D01*
X1311797Y781343D01*
X1311452Y780982D01*
X1311222Y780465D01*
X1311145Y780000D01*
X1312755D01*
G01X1315510D02*
Y783100D01*
X1314092Y780878D01*
X1316008D01*
G01X1315313Y778029D02*
X1309762Y772478D01*
G01X1318020Y778029D02*
X1315313D01*
G01X1309762Y772478D02*
X1304211Y778029D01*
G01X1315400Y795100D02*
X1318600D01*
G01X1315400Y788900D02*
Y795100D01*
G01X1318600Y788900D02*
X1315400D01*
G01X1318600Y795100D02*
Y788900D01*
G01X1311400Y795100D02*
X1314600D01*
G01X1311400Y788900D02*
Y795100D01*
G01X1314600Y788900D02*
X1311400D01*
G01X1314600Y795100D02*
Y788900D01*
G01X1308365Y810439D02*
Y800203D01*
G01X1311400Y811100D02*
X1314600D01*
G01X1311400Y804900D02*
Y811100D01*
G01X1314600Y804900D02*
X1311400D01*
G01X1314600Y811100D02*
Y804900D01*
G01X1315400Y811100D02*
X1318600D01*
G01X1315400Y804900D02*
Y811100D01*
G01X1318600Y804900D02*
X1315400D01*
G01X1318600Y811100D02*
Y804900D01*
G01X1310999Y827114D02*
X1385803D01*
G01X1310999Y901918D02*
Y827114D01*
G01X1307908Y909383D02*
Y907161D01*
X1308061Y906696D01*
X1308368Y906386D01*
X1308751Y906283D01*
X1309134Y906386D01*
X1309441Y906696D01*
X1309594Y907161D01*
Y909383D01*
G01X1311123Y907575D02*
X1311391Y907936D01*
X1311621Y908143D01*
X1311928Y908246D01*
X1312196Y908143D01*
X1312388Y907936D01*
X1312541Y907626D01*
X1312579Y907265D01*
X1312541Y906955D01*
X1312388Y906645D01*
X1312158Y906386D01*
X1311889Y906283D01*
X1311583Y906386D01*
X1311314Y906696D01*
X1311161Y907161D01*
X1311123Y907678D01*
X1311199Y908350D01*
X1311314Y908711D01*
X1311506Y909073D01*
X1311774Y909331D01*
X1312043Y909383D01*
X1312311Y909280D01*
X1312503Y909021D01*
G01X1385803Y901918D02*
X1310999D01*
G01X1316900Y924600D02*
X1320100D01*
G01X1316900Y918400D02*
Y924600D01*
G01X1320100Y918400D02*
X1316900D01*
G01X1316100D02*
X1312900D01*
G01X1316100Y924600D02*
Y918400D01*
G01X1312900Y924600D02*
X1316100D01*
G01X1312900Y918400D02*
Y924600D01*
G01X1303600D02*
Y918400D01*
G01X1313600Y951000D02*
Y945200D01*
G01X1322400D02*
X1313600D01*
G01X1305600Y944100D02*
Y940900D01*
G01X1311552Y935664D02*
X1314752D01*
G01X1311552Y929464D02*
Y935664D01*
G01X1314752Y929464D02*
X1311552D01*
G01X1314752Y935664D02*
Y929464D01*
G01X1318600Y929400D02*
X1315400D01*
G01X1318600Y935600D02*
Y929400D01*
G01X1315400Y935600D02*
X1318600D01*
G01X1315400Y929400D02*
Y935600D01*
G01X1307503Y935664D02*
X1310703D01*
G01X1307503Y929464D02*
Y935664D01*
G01X1310703Y929464D02*
X1307503D01*
G01X1310703Y935664D02*
Y929464D01*
G01X1315400Y942600D02*
X1318600D01*
G01X1315400Y936400D02*
Y942600D01*
G01X1318600Y936400D02*
X1315400D01*
G01X1318600Y942600D02*
Y936400D01*
G01X1303349Y935664D02*
X1306549D01*
G01X1303349Y929464D02*
Y935664D01*
G01X1306549Y929464D02*
X1303349D01*
G01X1306549Y935664D02*
Y929464D01*
G01X1309700Y946507D02*
X1311922D01*
X1312387Y946660D01*
X1312697Y946967D01*
X1312800Y947350D01*
X1312697Y947733D01*
X1312387Y948040D01*
X1311922Y948193D01*
X1309700D01*
G01X1312800Y950450D02*
X1309700D01*
X1310320Y949990D01*
G01X1312800D02*
Y950910D01*
G01Y954010D02*
X1309700D01*
X1311922Y952592D01*
Y954508D01*
G01X1312335Y955807D02*
X1312593Y956037D01*
X1312748Y956305D01*
X1312800Y956650D01*
X1312697Y956995D01*
X1312490Y957263D01*
X1312128Y957455D01*
X1311715Y957493D01*
X1311302Y957417D01*
X1311043Y957225D01*
X1310837Y956957D01*
X1310785Y956688D01*
X1310837Y956420D01*
X1311043Y956075D01*
X1309700Y956190D01*
Y957225D01*
G01X1313600Y958800D02*
Y953000D01*
G01Y958800D02*
X1322400D01*
G01X1315100Y952000D02*
X1313600Y951000D01*
G01Y953000D02*
X1315100Y952000D01*
G01X1308307Y953161D02*
Y958961D01*
G01Y945361D02*
Y951161D01*
G01X1306807Y952161D02*
X1308307Y953161D01*
G01Y951161D02*
X1306807Y952161D01*
G01X1320100Y960400D02*
X1316900D01*
G01D02*
Y966600D01*
G01D02*
X1320100D01*
G01X1312600Y962400D02*
X1309400D01*
G01X1312600Y968600D02*
Y962400D01*
G01X1309400Y968600D02*
X1312600D01*
G01X1309400Y962400D02*
Y968600D01*
G01X1305400D02*
X1308600D01*
G01X1305400Y962400D02*
Y968600D01*
G01X1308600Y962400D02*
X1305400D01*
G01X1308600Y968600D02*
Y962400D01*
G01X1316600D02*
X1313400D01*
G01X1316600Y968600D02*
Y962400D01*
G01X1313400Y968600D02*
X1316600D01*
G01X1313400Y962400D02*
Y968600D01*
G01X1311287Y988049D02*
X1311649Y988279D01*
X1311855Y988585D01*
X1311907Y988930D01*
X1311855Y989237D01*
X1311597Y989544D01*
X1311287Y989735D01*
X1310977Y989774D01*
X1310615Y989697D01*
X1310357Y989429D01*
X1310254Y989160D01*
Y988815D01*
G01Y989160D02*
X1310099Y989390D01*
X1309840Y989582D01*
X1309530Y989659D01*
X1309220Y989582D01*
X1308962Y989390D01*
X1308807Y989045D01*
X1308859Y988700D01*
X1309065Y988355D01*
G01X1319692Y1062632D02*
X1316284D01*
G01D02*
Y1080348D01*
G01X1321864Y1090068D02*
X1309864D01*
G01D02*
Y1096068D01*
G01X1309858Y1082881D02*
Y1088881D01*
X1321858D01*
Y1082881D01*
X1309858D01*
G01X1316284Y1080348D02*
X1319692D01*
G01X1309864Y1096068D02*
X1321864D01*
G01X1318933Y1118297D02*
X1315733D01*
G01D02*
Y1124497D01*
G01D02*
X1318933D01*
G01X1315837Y1153659D02*
Y1159859D01*
G01X1319037Y1153659D02*
X1315837D01*
G01Y1159859D02*
X1319037D01*
G01X1311178Y1189471D02*
Y1201471D01*
G01X1317178Y1189471D02*
X1311178D01*
G01X1317178Y1201471D02*
Y1189471D01*
G01X1311178Y1201471D02*
X1317178D01*
G01X1317123Y1220128D02*
Y1209928D01*
X1312523D01*
Y1220128D01*
X1317123D01*
G01X1309043Y1266904D02*
Y1249202D01*
G01D02*
X1322322D01*
G01X1321993Y1266904D02*
X1309043D01*
G01X1336556Y-62706D02*
Y-79306D01*
X1326956D01*
Y-62706D01*
X1336556D01*
G01X1321319Y35990D02*
Y23786D01*
G01X1329548Y34383D02*
Y37583D01*
G01X1335748Y34383D02*
X1329548D01*
G01X1329476Y24934D02*
Y28134D01*
G01X1335676Y24934D02*
X1329476D01*
G01Y28134D02*
X1335676D01*
G01X1329548Y28883D02*
Y32083D01*
G01X1335748Y28883D02*
X1329548D01*
G01Y32083D02*
X1335748D01*
G01X1329571Y21027D02*
Y24227D01*
G01X1335771Y21027D02*
X1329571D01*
G01Y24227D02*
X1335771D01*
G01X1329548Y37583D02*
X1335748D01*
G01X1320459Y44573D02*
Y38373D01*
G01X1324453Y38418D02*
X1321253D01*
G01X1324453Y44618D02*
Y38418D01*
G01X1321253Y44618D02*
X1324453D01*
G01X1321253Y38418D02*
Y44618D01*
G01X1324700Y98507D02*
X1326922D01*
X1327387Y98660D01*
X1327697Y98967D01*
X1327800Y99350D01*
X1327697Y99733D01*
X1327387Y100040D01*
X1326922Y100193D01*
X1324700D01*
G01X1327800Y102910D02*
X1324700D01*
X1326922Y101492D01*
Y103408D01*
G01X1327800Y105550D02*
X1324700D01*
X1325320Y105090D01*
G01X1327800D02*
Y106010D01*
G01Y108650D02*
X1324700D01*
X1325320Y108190D01*
G01X1327800D02*
Y109110D01*
G01X1323165Y111267D02*
Y95913D01*
G01X1329420Y89099D02*
Y92199D01*
G01X1331030D02*
Y89099D01*
G01Y90649D02*
X1329420D01*
G01X1332482Y89564D02*
X1332712Y89306D01*
X1332980Y89151D01*
X1333325Y89099D01*
X1333670Y89202D01*
X1333938Y89409D01*
X1334130Y89771D01*
X1334168Y90184D01*
X1334092Y90597D01*
X1333900Y90856D01*
X1333632Y91062D01*
X1333363Y91114D01*
X1333095Y91062D01*
X1332750Y90856D01*
X1332865Y92199D01*
X1333900D01*
G01X1336885Y89099D02*
Y92199D01*
X1335467Y89977D01*
X1337383D01*
G01X1323038Y116088D02*
Y112888D01*
G01X1319302Y170313D02*
Y167113D01*
G01X1321481Y167065D02*
Y170265D01*
G01X1327681Y167065D02*
X1321481D01*
G01X1327681Y170265D02*
Y167065D01*
G01X1321481Y170265D02*
X1327681D01*
G01X1321481Y175065D02*
Y178265D01*
G01X1327681Y175065D02*
X1321481D01*
G01X1327681Y178265D02*
Y175065D01*
G01X1321481Y178265D02*
X1327681D01*
G01X1321481Y171065D02*
Y174265D01*
G01X1327681Y171065D02*
X1321481D01*
G01X1327681Y174265D02*
Y171065D01*
G01X1321481Y174265D02*
X1327681D01*
G01X1321481Y179065D02*
Y182265D01*
G01X1327681Y179065D02*
X1321481D01*
G01X1327681Y182265D02*
Y179065D01*
G01X1320357Y198220D02*
Y195020D01*
G01X1321481Y182265D02*
X1327681D01*
G01X1321481Y183065D02*
Y186265D01*
G01X1327681Y183065D02*
X1321481D01*
G01X1327681Y186265D02*
Y183065D01*
G01X1321481Y186265D02*
X1327681D01*
G01Y198265D02*
Y195065D01*
G01X1321481D02*
Y198265D01*
G01X1327681Y195065D02*
X1321481D01*
G01X1327681Y194265D02*
Y191065D01*
G01X1321481Y194265D02*
X1327681D01*
G01X1321481Y191065D02*
Y194265D01*
G01X1327681Y191065D02*
X1321481D01*
G01Y187065D02*
Y190265D01*
G01X1327681Y187065D02*
X1321481D01*
G01X1327681Y190265D02*
Y187065D01*
G01X1321481Y190265D02*
X1327681D01*
G01X1321576Y202464D02*
X1327776D01*
Y199264D01*
X1321576D01*
Y202464D01*
G01X1321481Y198265D02*
X1327681D01*
G01X1321576Y207264D02*
Y210464D01*
G01X1327776Y207264D02*
X1321576D01*
G01X1327776Y210464D02*
Y207264D01*
G01X1321576Y210464D02*
X1327776D01*
G01Y206464D02*
Y203264D01*
G01X1321576Y206464D02*
X1327776D01*
G01X1321576Y203264D02*
Y206464D01*
G01X1327776Y203264D02*
X1321576D01*
G01Y214464D02*
X1327776D01*
Y211264D01*
X1321576D01*
Y214464D01*
G01Y215264D02*
Y218464D01*
G01X1327776Y215264D02*
X1321576D01*
G01X1327776Y218464D02*
Y215264D01*
G01X1321576Y218464D02*
X1327776D01*
G01X1321576Y220264D02*
Y223464D01*
G01X1327776Y220264D02*
X1321576D01*
G01X1327776Y223464D02*
Y220264D01*
G01X1321576Y223464D02*
X1327776D01*
G01X1321573Y227319D02*
X1327773D01*
Y224119D01*
X1321573D01*
Y227319D01*
G01X1319292Y234813D02*
Y250325D01*
G01X1334600Y265383D02*
X1331500D01*
Y266303D01*
X1331655Y266610D01*
X1332017Y266840D01*
X1332430Y266917D01*
X1332843Y266840D01*
X1333153Y266648D01*
X1333308Y266303D01*
Y265383D01*
G01X1334600Y268407D02*
X1331500D01*
Y269173D01*
X1331655Y269480D01*
X1331862Y269710D01*
X1332172Y269902D01*
X1332533Y270055D01*
X1333050Y270093D01*
X1333567Y270055D01*
X1333928Y269902D01*
X1334238Y269710D01*
X1334445Y269480D01*
X1334600Y269173D01*
Y268407D01*
G01Y272350D02*
X1331500D01*
X1332120Y271890D01*
G01X1334600D02*
Y272810D01*
G01X1331500Y275450D02*
X1331603Y275143D01*
X1331862Y274913D01*
X1332172Y274760D01*
X1332585Y274645D01*
X1333050Y274607D01*
X1333515Y274645D01*
X1333928Y274760D01*
X1334238Y274913D01*
X1334497Y275143D01*
X1334600Y275450D01*
X1334497Y275757D01*
X1334238Y275987D01*
X1333928Y276140D01*
X1333515Y276255D01*
X1333050Y276293D01*
X1332585Y276255D01*
X1332172Y276140D01*
X1331862Y275987D01*
X1331603Y275757D01*
X1331500Y275450D01*
G01X1334600Y278550D02*
X1334548Y278818D01*
X1334393Y279125D01*
X1334135Y279317D01*
X1333773Y279393D01*
X1333412Y279317D01*
X1333102Y279087D01*
X1332947Y278742D01*
Y278358D01*
X1332843Y278128D01*
X1332585Y277937D01*
X1332223Y277860D01*
X1331862Y277975D01*
X1331603Y278243D01*
X1331500Y278550D01*
X1331603Y278857D01*
X1331862Y279125D01*
X1332223Y279240D01*
X1332585Y279163D01*
X1332843Y278972D01*
X1332947Y278742D01*
Y278358D01*
X1333102Y278013D01*
X1333412Y277783D01*
X1333773Y277707D01*
X1334135Y277783D01*
X1334393Y277975D01*
X1334548Y278282D01*
X1334600Y278550D01*
G01X1329848Y264635D02*
Y295727D01*
G01X1332410Y314253D02*
X1334615D01*
G01X1331336D02*
X1329386D01*
G01X1324536D02*
X1326727D01*
G01X1327736Y319473D02*
Y315147D01*
G01X1328136Y319473D02*
Y315147D01*
G01X1323462Y314253D02*
X1321438D01*
G01X1319862Y319532D02*
Y315335D01*
G01X1320262Y319532D02*
Y315335D01*
G01X1332410Y320453D02*
X1334516D01*
G01X1331336D02*
X1329128D01*
G01X1324536D02*
X1326627D01*
G01X1323462D02*
X1321229D01*
G01X1331336D02*
Y314253D01*
G01X1332410D02*
Y320453D01*
G01X1323462D02*
Y314253D01*
G01X1324536D02*
Y320453D01*
G01X1319274Y329781D02*
X1321485D01*
G01X1319274Y331992D02*
Y329781D01*
G01Y353403D02*
Y351192D01*
G01X1321485Y353403D02*
X1319274D01*
G01X1332409Y369710D02*
X1334566D01*
G01X1332409Y363510D02*
X1334645D01*
G01X1334730Y373767D02*
Y404859D01*
G01X1319218Y373767D02*
X1334730D01*
G01X1319218Y404859D02*
Y373767D01*
G01X1323407Y369849D02*
X1326607D01*
G01X1323407Y363649D02*
Y369849D01*
G01X1326607Y363649D02*
X1323407D01*
G01X1326607Y369849D02*
Y363649D01*
G01X1332409Y363510D02*
Y369710D01*
G01X1322503Y363641D02*
X1319303D01*
G01X1322503Y369841D02*
Y363641D01*
G01X1319303Y369841D02*
X1322503D01*
G01X1319303Y363641D02*
Y369841D01*
G01X1330664Y363649D02*
X1327464D01*
G01X1330664Y369849D02*
Y363649D01*
G01X1327464Y369849D02*
X1330664D01*
G01X1327464Y363649D02*
Y369849D01*
G01X1321152Y422140D02*
Y406628D01*
G01D02*
X1352244D01*
G01X1334730Y404859D02*
X1319218D01*
G01X1352244Y422140D02*
X1321152D01*
G01X1334406Y427013D02*
Y423813D01*
G01X1328206D02*
Y427013D01*
G01X1334406Y423813D02*
X1328206D01*
G01Y427013D02*
X1334406D01*
G01X1324420Y433937D02*
X1327620D01*
G01X1324420Y427737D02*
Y433937D01*
G01X1327620Y427737D02*
X1324420D01*
G01X1327620Y433937D02*
Y427737D01*
G01X1328796Y427594D02*
X1328546Y427754D01*
X1328421Y427941D01*
X1328379Y428154D01*
X1328462Y428421D01*
X1328671Y428608D01*
X1328921Y428661D01*
X1329171Y428634D01*
X1329379Y428528D01*
X1329796Y427994D01*
X1330087Y427754D01*
X1330504Y427594D01*
X1330879Y427541D01*
Y428661D01*
G01X1328379Y430301D02*
X1328462Y430088D01*
X1328671Y429928D01*
X1328921Y429821D01*
X1329254Y429741D01*
X1329629Y429714D01*
X1330004Y429741D01*
X1330337Y429821D01*
X1330587Y429928D01*
X1330796Y430088D01*
X1330879Y430301D01*
X1330796Y430514D01*
X1330587Y430674D01*
X1330337Y430781D01*
X1330004Y430861D01*
X1329629Y430888D01*
X1329254Y430861D01*
X1328921Y430781D01*
X1328671Y430674D01*
X1328462Y430514D01*
X1328379Y430301D01*
G01X1323800Y431383D02*
X1320700D01*
Y432303D01*
X1320855Y432610D01*
X1321217Y432840D01*
X1321630Y432917D01*
X1322043Y432840D01*
X1322353Y432648D01*
X1322508Y432303D01*
Y431383D01*
G01X1320700Y434407D02*
X1322922D01*
X1323387Y434560D01*
X1323697Y434867D01*
X1323800Y435250D01*
X1323697Y435633D01*
X1323387Y435940D01*
X1322922Y436093D01*
X1320700D01*
G01X1323800Y438350D02*
X1320700D01*
X1321320Y437890D01*
G01X1323800D02*
Y438810D01*
G01X1320700Y441450D02*
X1320803Y441143D01*
X1321062Y440913D01*
X1321372Y440760D01*
X1321785Y440645D01*
X1322250Y440607D01*
X1322715Y440645D01*
X1323128Y440760D01*
X1323438Y440913D01*
X1323697Y441143D01*
X1323800Y441450D01*
X1323697Y441757D01*
X1323438Y441987D01*
X1323128Y442140D01*
X1322715Y442255D01*
X1322250Y442293D01*
X1321785Y442255D01*
X1321372Y442140D01*
X1321062Y441987D01*
X1320803Y441757D01*
X1320700Y441450D01*
G01X1323800Y445010D02*
X1320700D01*
X1322922Y443592D01*
Y445508D01*
G01X1331744Y431227D02*
Y430062D01*
G01D02*
X1334885D01*
G01X1322646Y457201D02*
Y447001D01*
G01X1323546Y457201D02*
X1328146D01*
G01X1323546Y447001D02*
Y457201D01*
G01X1328146Y447001D02*
X1323546D01*
G01X1328146Y457201D02*
Y447001D01*
G01X1330746Y457501D02*
Y460701D01*
G01X1336946Y457501D02*
X1330746D01*
G01Y456901D02*
X1336946D01*
G01X1330746Y453701D02*
Y456901D01*
G01X1336946Y453701D02*
X1330746D01*
G01X1331593Y450913D02*
Y453413D01*
X1331273Y452913D01*
G01Y450913D02*
X1331913D01*
G01X1333793D02*
Y453413D01*
X1333473Y452913D01*
G01Y450913D02*
X1334113D01*
G01X1329300Y443265D02*
X1326800D01*
X1327300Y442945D01*
G01X1329300D02*
Y443585D01*
G01X1327217Y444958D02*
X1326967Y445118D01*
X1326842Y445305D01*
X1326800Y445518D01*
X1326883Y445785D01*
X1327092Y445972D01*
X1327342Y446025D01*
X1327592Y445998D01*
X1327800Y445892D01*
X1328217Y445358D01*
X1328508Y445118D01*
X1328925Y444958D01*
X1329300Y444905D01*
Y446025D01*
G01X1331744Y450140D02*
Y448975D01*
G01X1334878Y450140D02*
X1331744D01*
G01X1321056Y466836D02*
Y476284D01*
G01X1331892Y466836D02*
X1321056D01*
G01X1331892Y476284D02*
Y466836D01*
G01X1330746Y460701D02*
X1336946D01*
G01X1330746Y464701D02*
X1336946D01*
G01X1330746Y461501D02*
Y464701D01*
G01X1336946Y461501D02*
X1330746D01*
G01X1334374Y472960D02*
Y476160D01*
G01X1340574Y472960D02*
X1334374D01*
G01X1321620Y481258D02*
X1321313Y481310D01*
X1321045Y481516D01*
X1320815Y481826D01*
X1320662Y482188D01*
X1320585Y482601D01*
Y483015D01*
X1320662Y483428D01*
X1320815Y483790D01*
X1321045Y484100D01*
X1321313Y484306D01*
X1321620Y484358D01*
X1321927Y484306D01*
X1322195Y484100D01*
X1322425Y483790D01*
X1322578Y483428D01*
X1322655Y483015D01*
Y482601D01*
X1322578Y482188D01*
X1322425Y481826D01*
X1322195Y481516D01*
X1321927Y481310D01*
X1321620Y481258D01*
G01X1321927Y482085D02*
X1322387Y481258D01*
G01X1323992Y483841D02*
X1324222Y484151D01*
X1324490Y484306D01*
X1324797Y484358D01*
X1325180Y484255D01*
X1325448Y483996D01*
X1325525Y483686D01*
X1325487Y483376D01*
X1325333Y483118D01*
X1324567Y482601D01*
X1324222Y482240D01*
X1323992Y481723D01*
X1323915Y481258D01*
X1325525D01*
G01X1327820D02*
Y484358D01*
X1327360Y483738D01*
G01Y481258D02*
X1328280D01*
G01X1330843D02*
X1330920Y481930D01*
X1331035Y482498D01*
X1331188Y483015D01*
X1331380Y483583D01*
X1331687Y484358D01*
X1330153D01*
G01X1328474Y476284D02*
X1331892D01*
G01X1326474Y474560D02*
X1328474Y476284D01*
G01X1324474D02*
X1326474Y474560D01*
G01X1321056Y476284D02*
X1324474D01*
G01X1334374Y476160D02*
X1340574D01*
G01X1334100Y560100D02*
Y556900D01*
G01X1327900Y560100D02*
X1334100D01*
G01X1327900Y556900D02*
Y560100D01*
G01X1334100Y556900D02*
X1327900D01*
G01X1334100Y564100D02*
Y560900D01*
G01X1327900Y564100D02*
X1334100D01*
G01X1327900Y560900D02*
Y564100D01*
G01X1334100Y560900D02*
X1327900D01*
G01X1334100Y568100D02*
Y564900D01*
G01X1327900Y568100D02*
X1334100D01*
G01X1327900Y564900D02*
Y568100D01*
G01X1334100Y564900D02*
X1327900D01*
G01X1326100Y568100D02*
Y564900D01*
G01X1319900Y568100D02*
X1326100D01*
G01X1319900Y564900D02*
Y568100D01*
G01X1326100Y564900D02*
X1319900D01*
G01Y556900D02*
Y560100D01*
G01X1326100Y556900D02*
X1319900D01*
G01X1326100Y560100D02*
Y556900D01*
G01X1319900Y560100D02*
X1326100D01*
G01X1319900Y560900D02*
Y564100D01*
G01X1326100Y560900D02*
X1319900D01*
G01X1326100Y564100D02*
Y560900D01*
G01X1319900Y564100D02*
X1326100D01*
G01X1334100Y576100D02*
Y572900D01*
G01X1327900Y576100D02*
X1334100D01*
G01X1327900Y572900D02*
Y576100D01*
G01X1334100Y572900D02*
X1327900D01*
G01X1334100Y588100D02*
Y584900D01*
G01X1327900D02*
Y588100D01*
G01X1334100Y584900D02*
X1327900D01*
G01X1334100Y580100D02*
Y576900D01*
G01X1327900Y580100D02*
X1334100D01*
G01X1327900Y576900D02*
Y580100D01*
G01X1334100Y576900D02*
X1327900D01*
G01X1334100Y584100D02*
Y580900D01*
G01X1327900Y584100D02*
X1334100D01*
G01X1327900Y580900D02*
Y584100D01*
G01X1334100Y580900D02*
X1327900D01*
G01X1319900Y572900D02*
Y576100D01*
G01X1326100Y572900D02*
X1319900D01*
G01X1326100Y576100D02*
Y572900D01*
G01X1319900Y576100D02*
X1326100D01*
G01Y584100D02*
Y580900D01*
G01X1319900Y584100D02*
X1326100D01*
G01X1319900Y580900D02*
Y584100D01*
G01X1326100Y580900D02*
X1319900D01*
G01X1326100Y588100D02*
Y584900D01*
G01X1319900D02*
Y588100D01*
G01X1326100Y584900D02*
X1319900D01*
G01Y576900D02*
Y580100D01*
G01X1326100Y576900D02*
X1319900D01*
G01X1326100Y580100D02*
Y576900D01*
G01X1319900Y580100D02*
X1326100D01*
G01X1334100Y592100D02*
Y588900D01*
G01X1327900Y592100D02*
X1334100D01*
G01X1327900Y588900D02*
Y592100D01*
G01X1334100Y588900D02*
X1327900D01*
G01Y588100D02*
X1334100D01*
G01X1327900Y592900D02*
Y596100D01*
G01X1334100Y592900D02*
X1327900D01*
G01X1334100Y596100D02*
Y592900D01*
G01X1327900Y596100D02*
X1334100D01*
G01Y606600D02*
Y603400D01*
G01X1327900D02*
Y606600D01*
G01X1334100Y603400D02*
X1327900D01*
G01X1326100Y592100D02*
Y588900D01*
G01X1319900Y592100D02*
X1326100D01*
G01X1319900Y588900D02*
Y592100D01*
G01X1326100Y588900D02*
X1319900D01*
G01Y588100D02*
X1326100D01*
G01X1319900Y592900D02*
Y596100D01*
G01X1326100Y592900D02*
X1319900D01*
G01X1326100Y596100D02*
Y592900D01*
G01X1319900Y596100D02*
X1326100D01*
G01X1319900Y603400D02*
Y606600D01*
G01X1326100Y603400D02*
X1319900D01*
G01X1326100Y606600D02*
Y603400D01*
G01X1327900Y606600D02*
X1334100D01*
G01Y610600D02*
Y607400D01*
G01X1327900Y610600D02*
X1334100D01*
G01X1327900Y607400D02*
Y610600D01*
G01X1334100Y607400D02*
X1327900D01*
G01X1334100Y614600D02*
Y611400D01*
G01X1327900Y614600D02*
X1334100D01*
G01X1327900Y611400D02*
Y614600D01*
G01X1334100Y611400D02*
X1327900D01*
G01X1334100Y622600D02*
Y619400D01*
G01X1327900D02*
Y622600D01*
G01X1334100Y619400D02*
X1327900D01*
G01X1319900Y606600D02*
X1326100D01*
G01Y614600D02*
Y611400D01*
G01X1319900Y614600D02*
X1326100D01*
G01X1319900Y611400D02*
Y614600D01*
G01X1326100Y611400D02*
X1319900D01*
G01Y619400D02*
Y622600D01*
G01X1326100Y619400D02*
X1319900D01*
G01X1326100Y622600D02*
Y619400D01*
G01X1319900Y607400D02*
Y610600D01*
G01X1326100Y607400D02*
X1319900D01*
G01X1326100Y610600D02*
Y607400D01*
G01X1319900Y610600D02*
X1326100D01*
G01X1327900Y622600D02*
X1334100D01*
G01Y638600D02*
Y635400D01*
G01X1327900D02*
Y638600D01*
G01X1334100Y635400D02*
X1327900D01*
G01X1334100Y634600D02*
Y631400D01*
G01X1327900Y634600D02*
X1334100D01*
G01X1327900Y631400D02*
Y634600D01*
G01X1334100Y631400D02*
X1327900D01*
G01X1334100Y626600D02*
Y623400D01*
G01X1327900Y626600D02*
X1334100D01*
G01X1327900Y623400D02*
Y626600D01*
G01X1334100Y623400D02*
X1327900D01*
G01X1334100Y630600D02*
Y627400D01*
G01X1327900Y630600D02*
X1334100D01*
G01X1327900Y627400D02*
Y630600D01*
G01X1334100Y627400D02*
X1327900D01*
G01X1319900Y622600D02*
X1326100D01*
G01Y630600D02*
Y627400D01*
G01X1319900Y630600D02*
X1326100D01*
G01X1319900Y627400D02*
Y630600D01*
G01X1326100Y627400D02*
X1319900D01*
G01X1326100Y634600D02*
Y631400D01*
G01X1319900Y634600D02*
X1326100D01*
G01X1319900Y631400D02*
Y634600D01*
G01X1326100Y631400D02*
X1319900D01*
G01X1326100Y638600D02*
Y635400D01*
G01X1319900D02*
Y638600D01*
G01X1326100Y635400D02*
X1319900D01*
G01Y623400D02*
Y626600D01*
G01X1326100Y623400D02*
X1319900D01*
G01X1326100Y626600D02*
Y623400D01*
G01X1319900Y626600D02*
X1326100D01*
G01X1327900Y638600D02*
X1334100D01*
G01Y655100D02*
Y651900D01*
G01X1327900D02*
Y655100D01*
G01X1334100Y651900D02*
X1327900D01*
G01X1334100Y651100D02*
Y647900D01*
G01X1327900Y651100D02*
X1334100D01*
G01X1327900Y647900D02*
Y651100D01*
G01X1334100Y647900D02*
X1327900D01*
G01Y639400D02*
Y642600D01*
G01X1334100Y639400D02*
X1327900D01*
G01X1334100Y642600D02*
Y639400D01*
G01X1327900Y642600D02*
X1334100D01*
G01X1319900Y638600D02*
X1326100D01*
G01X1319900Y651900D02*
Y655100D01*
G01X1326100Y651900D02*
X1319900D01*
G01X1326100Y655100D02*
Y651900D01*
G01Y646600D02*
Y643400D01*
G01X1319900Y646600D02*
X1326100D01*
G01X1319900Y643400D02*
Y646600D01*
G01X1326100Y643400D02*
X1319900D01*
G01Y639400D02*
Y642600D01*
G01X1326100Y639400D02*
X1319900D01*
G01X1326100Y642600D02*
Y639400D01*
G01X1319900Y642600D02*
X1326100D01*
G01X1319900Y647900D02*
Y651100D01*
G01X1326100Y647900D02*
X1319900D01*
G01X1326100Y651100D02*
Y647900D01*
G01X1319900Y651100D02*
X1326100D01*
G01X1327900Y655100D02*
X1334100D01*
G01Y667100D02*
Y663900D01*
G01X1327900Y667100D02*
X1334100D01*
G01X1327900Y663900D02*
Y667100D01*
G01X1334100Y663900D02*
X1327900D01*
G01X1334100Y659100D02*
Y655900D01*
G01X1327900Y659100D02*
X1334100D01*
G01X1327900Y655900D02*
Y659100D01*
G01X1334100Y655900D02*
X1327900D01*
G01X1319900Y655100D02*
X1326100D01*
G01X1319900Y663900D02*
Y667100D01*
G01X1326100Y663900D02*
X1319900D01*
G01X1326100Y667100D02*
Y663900D01*
G01X1319900Y667100D02*
X1326100D01*
G01Y659100D02*
Y655900D01*
G01X1319900Y659100D02*
X1326100D01*
G01X1319900Y655900D02*
Y659100D01*
G01X1326100Y655900D02*
X1319900D01*
G01Y667900D02*
Y671100D01*
G01X1326100Y667900D02*
X1319900D01*
G01X1326100Y671100D02*
Y667900D01*
G01X1334100Y671100D02*
Y667900D01*
G01X1327900D02*
Y671100D01*
G01X1334100Y667900D02*
X1327900D01*
G01X1319900Y683900D02*
Y687100D01*
G01X1326100Y683900D02*
X1319900D01*
G01X1326100Y687100D02*
Y683900D01*
G01Y679100D02*
Y675900D01*
G01X1319900Y679100D02*
X1326100D01*
G01X1319900Y675900D02*
Y679100D01*
G01X1326100Y675900D02*
X1319900D01*
G01X1326100Y683100D02*
Y679900D01*
G01X1319900Y683100D02*
X1326100D01*
G01X1319900Y679900D02*
Y683100D01*
G01X1326100Y679900D02*
X1319900D01*
G01X1326100Y675100D02*
Y671900D01*
G01X1319900Y675100D02*
X1326100D01*
G01X1319900Y671900D02*
Y675100D01*
G01X1326100Y671900D02*
X1319900D01*
G01Y671100D02*
X1326100D01*
G01X1327900Y683900D02*
Y687100D01*
G01X1334100Y683900D02*
X1327900D01*
G01X1334100Y687100D02*
Y683900D01*
G01Y675100D02*
Y671900D01*
G01X1327900Y675100D02*
X1334100D01*
G01X1327900Y671900D02*
Y675100D01*
G01X1334100Y671900D02*
X1327900D01*
G01X1334100Y683100D02*
Y679900D01*
G01X1327900Y683100D02*
X1334100D01*
G01X1327900Y679900D02*
Y683100D01*
G01X1334100Y679900D02*
X1327900D01*
G01X1334100Y679100D02*
Y675900D01*
G01X1327900Y679100D02*
X1334100D01*
G01X1327900Y675900D02*
Y679100D01*
G01X1334100Y675900D02*
X1327900D01*
G01Y671100D02*
X1334100D01*
G01X1319900Y687100D02*
X1326100D01*
G01X1319900Y698900D02*
Y702100D01*
G01X1326100Y698900D02*
X1319900D01*
G01X1326100Y702100D02*
Y698900D01*
G01X1319900Y694900D02*
Y698100D01*
G01X1326100Y694900D02*
X1319900D01*
G01X1326100Y698100D02*
Y694900D01*
G01X1319900Y698100D02*
X1326100D01*
G01X1327900Y687100D02*
X1334100D01*
G01Y698100D02*
Y694900D01*
G01X1327900Y698100D02*
X1334100D01*
G01X1327900Y694900D02*
Y698100D01*
G01X1334100Y694900D02*
X1327900D01*
G01X1334100Y702100D02*
Y698900D01*
G01X1327900D02*
Y702100D01*
G01X1334100Y698900D02*
X1327900D01*
G01X1319900Y702100D02*
X1326100D01*
G01Y706100D02*
Y702900D01*
G01X1319900Y706100D02*
X1326100D01*
G01X1319900Y702900D02*
Y706100D01*
G01X1326100Y702900D02*
X1319900D01*
G01Y714900D02*
Y718100D01*
G01X1326100Y714900D02*
X1319900D01*
G01X1326100Y718100D02*
Y714900D01*
G01X1319900Y710900D02*
Y714100D01*
G01X1326100Y710900D02*
X1319900D01*
G01X1326100Y714100D02*
Y710900D01*
G01X1319900Y714100D02*
X1326100D01*
G01X1327900Y702100D02*
X1334100D01*
G01Y706100D02*
Y702900D01*
G01X1327900Y706100D02*
X1334100D01*
G01X1327900Y702900D02*
Y706100D01*
G01X1334100Y702900D02*
X1327900D01*
G01X1334100Y714100D02*
Y710900D01*
G01X1327900Y714100D02*
X1334100D01*
G01X1327900Y710900D02*
Y714100D01*
G01X1334100Y710900D02*
X1327900D01*
G01X1334100Y718100D02*
Y714900D01*
G01X1327900D02*
Y718100D01*
G01X1334100Y714900D02*
X1327900D01*
G01X1326100Y722100D02*
Y718900D01*
G01X1319900Y722100D02*
X1326100D01*
G01X1319900Y718900D02*
Y722100D01*
G01X1326100Y718900D02*
X1319900D01*
G01Y718100D02*
X1326100D01*
G01X1319900Y730900D02*
Y734100D01*
G01X1326100Y730900D02*
X1319900D01*
G01X1326100Y734100D02*
Y730900D01*
G01Y730100D02*
Y726900D01*
G01X1319900Y730100D02*
X1326100D01*
G01X1319900Y726900D02*
Y730100D01*
G01X1326100Y726900D02*
X1319900D01*
G01X1326100Y726100D02*
Y722900D01*
G01X1319900Y726100D02*
X1326100D01*
G01X1319900Y722900D02*
Y726100D01*
G01X1326100Y722900D02*
X1319900D01*
G01X1327900Y718100D02*
X1334100D01*
G01Y730100D02*
Y726900D01*
G01X1327900Y730100D02*
X1334100D01*
G01X1327900Y726900D02*
Y730100D01*
G01X1334100Y726900D02*
X1327900D01*
G01X1334100Y726100D02*
Y722900D01*
G01X1327900Y726100D02*
X1334100D01*
G01X1327900Y722900D02*
Y726100D01*
G01X1334100Y722900D02*
X1327900D01*
G01Y730900D02*
Y734100D01*
G01X1334100Y730900D02*
X1327900D01*
G01X1334100Y734100D02*
Y730900D01*
G01Y722100D02*
Y718900D01*
G01X1327900Y722100D02*
X1334100D01*
G01X1327900Y718900D02*
Y722100D01*
G01X1334100Y718900D02*
X1327900D01*
G01X1319900Y734100D02*
X1326100D01*
G01X1326070Y738064D02*
Y734864D01*
G01X1319870Y738064D02*
X1326070D01*
G01X1319870Y734864D02*
Y738064D01*
G01X1326070Y734864D02*
X1319870D01*
G01X1327900Y734100D02*
X1334100D01*
G01X1329184Y777505D02*
X1325984D01*
G01X1329184Y783705D02*
Y777505D01*
G01X1325984D02*
Y783705D01*
G01D02*
X1329184D01*
G01X1331400Y795100D02*
X1334600D01*
G01X1331400Y788900D02*
Y795100D01*
G01X1334600Y788900D02*
X1331400D01*
G01X1334600Y795100D02*
Y788900D01*
G01X1327400Y795100D02*
X1330600D01*
G01X1327400Y788900D02*
Y795100D01*
G01X1330600Y788900D02*
X1327400D01*
G01X1330600Y795100D02*
Y788900D01*
G01X1323400Y795100D02*
X1326600D01*
G01X1323400Y788900D02*
Y795100D01*
G01X1326600Y788900D02*
X1323400D01*
G01X1326600Y795100D02*
Y788900D01*
G01X1319400Y795100D02*
X1322600D01*
G01X1319400Y788900D02*
Y795100D01*
G01X1322600Y788900D02*
X1319400D01*
G01X1322600Y795100D02*
Y788900D01*
G01X1331400Y811100D02*
X1334600D01*
G01X1331400Y804900D02*
Y811100D01*
G01X1334600Y804900D02*
X1331400D01*
G01X1334600Y811100D02*
Y804900D01*
G01X1323400Y811100D02*
X1326600D01*
G01X1323400Y804900D02*
Y811100D01*
G01X1326600Y804900D02*
X1323400D01*
G01X1326600Y811100D02*
Y804900D01*
G01X1327400Y811100D02*
X1330600D01*
G01X1327400Y804900D02*
Y811100D01*
G01X1330600Y804900D02*
X1327400D01*
G01X1330600Y811100D02*
Y804900D01*
G01X1319400Y811100D02*
X1322600D01*
G01X1319400Y804900D02*
Y811100D01*
G01X1322600Y804900D02*
X1319400D01*
G01X1322600Y811100D02*
Y804900D01*
G01X1320100Y924600D02*
Y918400D01*
G01X1320900Y924600D02*
X1324100D01*
G01X1320900Y918400D02*
Y924600D01*
G01X1324100Y918400D02*
X1320900D01*
G01X1324100Y924600D02*
Y918400D01*
G01X1332100D02*
X1328900D01*
G01X1332100Y924600D02*
Y918400D01*
G01X1328900Y924600D02*
X1332100D01*
G01X1328900Y918400D02*
Y924600D01*
G01X1336100Y918400D02*
X1332900D01*
G01Y924600D02*
X1336100D01*
G01X1332900Y918400D02*
Y924600D01*
G01X1324900D02*
X1328100D01*
G01X1324900Y918400D02*
Y924600D01*
G01X1328100Y918400D02*
X1324900D01*
G01X1328100Y924600D02*
Y918400D01*
G01X1325100Y945200D02*
Y958800D01*
G01X1333900Y945200D02*
Y951000D01*
G01Y945200D02*
X1325100D01*
G01X1322400Y958800D02*
Y945200D01*
G01X1337600Y929400D02*
X1334400D01*
G01Y935600D02*
X1337600D01*
G01X1334400Y929400D02*
Y935600D01*
G01X1328100Y929400D02*
X1324900D01*
G01X1328100Y935600D02*
Y929400D01*
G01X1324900Y935600D02*
X1328100D01*
G01X1324900Y929400D02*
Y935600D01*
G01X1334400Y942600D02*
X1337600D01*
G01X1334400Y936400D02*
Y942600D01*
G01X1337600Y936400D02*
X1334400D01*
G01X1324900Y942600D02*
X1328100D01*
G01X1324900Y936400D02*
Y942600D01*
G01X1328100Y936400D02*
X1324900D01*
G01X1328100Y942600D02*
Y936400D01*
G01X1333900Y953000D02*
Y958800D01*
G01X1325100D02*
X1333900D01*
G01X1332400Y952000D02*
X1333900Y953000D01*
G01Y951000D02*
X1332400Y952000D01*
G01X1320100Y966600D02*
Y960400D01*
G01X1325400Y968600D02*
X1328600D01*
G01X1325400Y962400D02*
Y968600D01*
G01X1328600Y962400D02*
X1325400D01*
G01X1328600Y968600D02*
Y962400D01*
G01X1330400Y968600D02*
X1333600D01*
G01X1330400Y962400D02*
Y968600D01*
G01X1333600Y962400D02*
X1330400D01*
G01X1333600Y968600D02*
Y962400D01*
G01X1333456Y1059313D02*
Y1053113D01*
G01D02*
X1330256D01*
G01D02*
Y1059313D01*
G01D02*
X1333456D01*
G01X1334000Y1080348D02*
Y1062632D01*
G01D02*
X1330592D01*
G01X1321864Y1096068D02*
Y1090068D01*
G01X1330592Y1080348D02*
X1334000D01*
G01X1323242Y1107230D02*
X1326442D01*
G01X1323242Y1101030D02*
Y1107230D01*
G01X1326442Y1101030D02*
X1323242D01*
G01X1326442Y1107230D02*
Y1101030D01*
G01X1321764Y1097226D02*
Y1100426D01*
G01X1327964Y1097226D02*
X1321764D01*
G01X1327964Y1100426D02*
Y1097226D01*
G01X1321764Y1100426D02*
X1327964D01*
G01X1327029Y1107230D02*
X1330229D01*
G01X1327029Y1101030D02*
Y1107230D01*
G01X1330229Y1101030D02*
X1327029D01*
G01X1330229Y1107230D02*
Y1101030D01*
G01X1318933Y1124497D02*
Y1118297D01*
G01X1321542Y1109839D02*
Y1112030D01*
G01X1322275Y1109839D02*
X1321542D01*
G01Y1133461D02*
X1322335D01*
G01X1321542Y1130861D02*
Y1133461D01*
G01X1320637Y1136752D02*
Y1174548D01*
G01X1326635Y1136752D02*
X1320637D01*
G01X1319037Y1159859D02*
Y1153659D01*
G01X1338771Y1177627D02*
Y1179867D01*
G01X1337146Y1178654D02*
X1340396D01*
G01X1319176Y1177793D02*
X1336116Y1177790D01*
G01X1319176Y1177193D02*
X1336151Y1177189D01*
G01X1319176Y1176593D02*
X1336159Y1176599D01*
G01X1319176Y1176593D02*
Y1177793D01*
G01X1336108D02*
X1319178D01*
G01D02*
Y1213533D01*
G01X1320637Y1174548D02*
X1326635D01*
G01X1327665Y1215869D02*
Y1218295D01*
G01X1319178Y1213533D02*
X1336108D01*
G01X1333143Y1247418D02*
X1324243D01*
G01X1333143Y1267704D02*
Y1247418D01*
G01X1324243D02*
Y1267704D01*
G01D02*
X1333143D01*
G01X1335748Y37583D02*
Y34383D01*
G01X1335676Y28134D02*
Y24934D01*
G01X1335748Y32083D02*
Y28883D01*
G01X1335771Y24227D02*
Y21027D01*
G01X1349941Y144690D02*
Y154138D01*
G01X1360777Y144690D02*
X1349941D01*
G01X1345543Y139647D02*
Y142847D01*
G01X1351743Y139647D02*
X1345543D01*
G01Y142847D02*
X1351743D01*
G01X1341573Y145940D02*
Y149140D01*
G01X1347773Y145940D02*
X1341573D01*
G01X1347773Y149140D02*
Y145940D01*
G01X1341573Y149140D02*
X1347773D01*
G01X1350550Y155400D02*
X1350243Y155452D01*
X1349975Y155658D01*
X1349745Y155968D01*
X1349592Y156330D01*
X1349515Y156743D01*
Y157157D01*
X1349592Y157570D01*
X1349745Y157932D01*
X1349975Y158242D01*
X1350243Y158448D01*
X1350550Y158500D01*
X1350857Y158448D01*
X1351125Y158242D01*
X1351355Y157932D01*
X1351508Y157570D01*
X1351585Y157157D01*
Y156743D01*
X1351508Y156330D01*
X1351355Y155968D01*
X1351125Y155658D01*
X1350857Y155452D01*
X1350550Y155400D01*
G01X1350857Y156227D02*
X1351317Y155400D01*
G01X1352922Y157983D02*
X1353152Y158293D01*
X1353420Y158448D01*
X1353727Y158500D01*
X1354110Y158397D01*
X1354378Y158138D01*
X1354455Y157828D01*
X1354417Y157518D01*
X1354263Y157260D01*
X1353497Y156743D01*
X1353152Y156382D01*
X1352922Y155865D01*
X1352845Y155400D01*
X1354455D01*
G01X1356022Y157983D02*
X1356252Y158293D01*
X1356520Y158448D01*
X1356827Y158500D01*
X1357210Y158397D01*
X1357478Y158138D01*
X1357555Y157828D01*
X1357517Y157518D01*
X1357363Y157260D01*
X1356597Y156743D01*
X1356252Y156382D01*
X1356022Y155865D01*
X1355945Y155400D01*
X1357555D01*
G01X1359850D02*
X1360118Y155452D01*
X1360425Y155607D01*
X1360617Y155865D01*
X1360693Y156227D01*
X1360617Y156588D01*
X1360387Y156898D01*
X1360042Y157053D01*
X1359658D01*
X1359428Y157157D01*
X1359237Y157415D01*
X1359160Y157777D01*
X1359275Y158138D01*
X1359543Y158397D01*
X1359850Y158500D01*
X1360157Y158397D01*
X1360425Y158138D01*
X1360540Y157777D01*
X1360463Y157415D01*
X1360272Y157157D01*
X1360042Y157053D01*
X1359658D01*
X1359313Y156898D01*
X1359083Y156588D01*
X1359007Y156227D01*
X1359083Y155865D01*
X1359275Y155607D01*
X1359582Y155452D01*
X1359850Y155400D01*
G01X1349941Y154138D02*
X1353359D01*
G01X1347773Y153140D02*
Y149940D01*
G01X1341573Y153140D02*
X1347773D01*
G01X1341573Y149940D02*
Y153140D01*
G01X1347773Y149940D02*
X1341573D01*
G01X1339210Y314253D02*
X1337056D01*
G01X1336010Y319612D02*
Y315098D01*
G01X1335610Y319612D02*
Y315098D01*
G01X1339210Y320453D02*
X1336917D01*
G01X1339210D02*
Y314253D01*
G01X1342896Y329781D02*
Y331992D01*
G01X1340685Y329781D02*
X1342896D01*
G01X1339804Y359673D02*
Y357451D01*
X1339957Y356986D01*
X1340264Y356676D01*
X1340647Y356573D01*
X1341030Y356676D01*
X1341337Y356986D01*
X1341490Y357451D01*
Y359673D01*
G01X1343747Y356573D02*
Y359673D01*
X1343287Y359053D01*
G01Y356573D02*
X1344207D01*
G01X1346847D02*
Y359673D01*
X1346387Y359053D01*
G01Y356573D02*
X1347307D01*
G01X1349219Y357865D02*
X1349487Y358226D01*
X1349717Y358433D01*
X1350024Y358536D01*
X1350292Y358433D01*
X1350484Y358226D01*
X1350637Y357916D01*
X1350675Y357555D01*
X1350637Y357245D01*
X1350484Y356935D01*
X1350254Y356676D01*
X1349985Y356573D01*
X1349679Y356676D01*
X1349410Y356986D01*
X1349257Y357451D01*
X1349219Y357968D01*
X1349295Y358640D01*
X1349410Y359001D01*
X1349602Y359363D01*
X1349870Y359621D01*
X1350139Y359673D01*
X1350407Y359570D01*
X1350599Y359311D01*
G01X1342896Y353403D02*
X1340685D01*
G01X1342896Y351192D02*
Y353403D01*
G01X1339209Y369710D02*
X1337136D01*
G01X1336009Y364481D02*
Y368658D01*
G01X1335609Y364481D02*
Y368658D01*
G01X1339209Y363510D02*
X1337086D01*
G01X1339200Y375583D02*
X1336100D01*
Y376503D01*
X1336255Y376810D01*
X1336617Y377040D01*
X1337030Y377117D01*
X1337443Y377040D01*
X1337753Y376848D01*
X1337908Y376503D01*
Y375583D01*
G01X1339200Y378607D02*
X1336100D01*
Y379373D01*
X1336255Y379680D01*
X1336462Y379910D01*
X1336772Y380102D01*
X1337133Y380255D01*
X1337650Y380293D01*
X1338167Y380255D01*
X1338528Y380102D01*
X1338838Y379910D01*
X1339045Y379680D01*
X1339200Y379373D01*
Y378607D01*
G01X1338838Y381898D02*
X1339097Y382167D01*
X1339200Y382473D01*
X1339097Y382780D01*
X1338787Y383048D01*
X1338322Y383240D01*
X1337857Y383317D01*
X1337288D01*
X1336823Y383240D01*
X1336410Y383048D01*
X1336203Y382818D01*
X1336100Y382550D01*
X1336203Y382243D01*
X1336410Y382013D01*
X1336720Y381860D01*
X1337133Y381783D01*
X1337495Y381860D01*
X1337857Y382052D01*
X1338063Y382282D01*
X1338115Y382550D01*
X1338012Y382857D01*
X1337753Y383087D01*
X1337288Y383317D01*
G01X1337908Y384922D02*
X1337547Y385190D01*
X1337340Y385420D01*
X1337237Y385727D01*
X1337340Y385995D01*
X1337547Y386187D01*
X1337857Y386340D01*
X1338218Y386378D01*
X1338528Y386340D01*
X1338838Y386187D01*
X1339097Y385957D01*
X1339200Y385688D01*
X1339097Y385382D01*
X1338787Y385113D01*
X1338322Y384960D01*
X1337805Y384922D01*
X1337133Y384998D01*
X1336772Y385113D01*
X1336410Y385305D01*
X1336152Y385573D01*
X1336100Y385842D01*
X1336203Y386110D01*
X1336462Y386302D01*
G01X1339209Y369710D02*
Y363510D01*
G01X1340383Y402000D02*
Y405100D01*
X1341303D01*
X1341610Y404945D01*
X1341840Y404583D01*
X1341917Y404170D01*
X1341840Y403757D01*
X1341648Y403447D01*
X1341303Y403292D01*
X1340383D01*
G01X1343407Y402000D02*
Y405100D01*
X1344173D01*
X1344480Y404945D01*
X1344710Y404738D01*
X1344902Y404428D01*
X1345055Y404067D01*
X1345093Y403550D01*
X1345055Y403033D01*
X1344902Y402672D01*
X1344710Y402362D01*
X1344480Y402155D01*
X1344173Y402000D01*
X1343407D01*
G01X1346698Y402362D02*
X1346967Y402103D01*
X1347273Y402000D01*
X1347580Y402103D01*
X1347848Y402413D01*
X1348040Y402878D01*
X1348117Y403343D01*
Y403912D01*
X1348040Y404377D01*
X1347848Y404790D01*
X1347618Y404997D01*
X1347350Y405100D01*
X1347043Y404997D01*
X1346813Y404790D01*
X1346660Y404480D01*
X1346583Y404067D01*
X1346660Y403705D01*
X1346852Y403343D01*
X1347082Y403137D01*
X1347350Y403085D01*
X1347657Y403188D01*
X1347887Y403447D01*
X1348117Y403912D01*
G01X1350373Y402000D02*
X1350450Y402672D01*
X1350565Y403240D01*
X1350718Y403757D01*
X1350910Y404325D01*
X1351217Y405100D01*
X1349683D01*
G01X1337657Y428007D02*
X1337817Y428257D01*
X1338004Y428382D01*
X1338217Y428424D01*
X1338484Y428341D01*
X1338671Y428132D01*
X1338724Y427882D01*
X1338697Y427632D01*
X1338591Y427424D01*
X1338057Y427007D01*
X1337817Y426716D01*
X1337657Y426299D01*
X1337604Y425924D01*
X1338724D01*
G01X1340364D02*
Y428424D01*
X1340044Y427924D01*
G01Y425924D02*
X1340684D01*
G01X1341764Y425091D02*
X1343364D01*
G01X1344257Y428007D02*
X1344417Y428257D01*
X1344604Y428382D01*
X1344817Y428424D01*
X1345084Y428341D01*
X1345271Y428132D01*
X1345324Y427882D01*
X1345297Y427632D01*
X1345191Y427424D01*
X1344657Y427007D01*
X1344417Y426716D01*
X1344257Y426299D01*
X1344204Y425924D01*
X1345324D01*
G01X1346457Y428007D02*
X1346617Y428257D01*
X1346804Y428382D01*
X1347017Y428424D01*
X1347284Y428341D01*
X1347471Y428132D01*
X1347524Y427882D01*
X1347497Y427632D01*
X1347391Y427424D01*
X1346857Y427007D01*
X1346617Y426716D01*
X1346457Y426299D01*
X1346404Y425924D01*
X1347524D01*
G01X1351347Y437439D02*
X1348147D01*
G01D02*
Y443639D01*
G01X1336896Y430062D02*
X1338796D01*
G01X1343948D02*
Y431235D01*
G01X1340807Y430062D02*
X1343948D01*
G01X1336946Y460701D02*
Y457501D01*
G01Y456901D02*
Y453701D01*
G01X1348147Y443639D02*
X1351347D01*
G01X1345446Y454501D02*
X1342246D01*
G01X1345446Y460701D02*
Y454501D01*
G01X1342246D02*
Y460701D01*
G01X1349446Y454501D02*
X1346246D01*
G01X1349446Y460701D02*
Y454501D01*
G01X1346246D02*
Y460701D01*
G01X1338246Y454501D02*
Y460701D01*
G01X1341446Y454501D02*
X1338246D01*
G01X1341446Y460701D02*
Y454501D01*
G01X1346033Y447793D02*
X1346219Y447584D01*
X1346433Y447501D01*
X1346646Y447584D01*
X1346833Y447834D01*
X1346966Y448209D01*
X1347019Y448584D01*
Y449043D01*
X1346966Y449418D01*
X1346833Y449751D01*
X1346673Y449918D01*
X1346486Y450001D01*
X1346273Y449918D01*
X1346113Y449751D01*
X1346006Y449501D01*
X1345953Y449168D01*
X1346006Y448876D01*
X1346139Y448584D01*
X1346299Y448418D01*
X1346486Y448376D01*
X1346699Y448459D01*
X1346859Y448668D01*
X1347019Y449043D01*
G01X1342408Y450723D02*
Y453223D01*
X1342088Y452723D01*
G01Y450723D02*
X1342728D01*
G01X1344608Y453223D02*
X1344395Y453140D01*
X1344235Y452931D01*
X1344128Y452681D01*
X1344048Y452348D01*
X1344021Y451973D01*
X1344048Y451598D01*
X1344128Y451265D01*
X1344235Y451015D01*
X1344395Y450806D01*
X1344608Y450723D01*
X1344821Y450806D01*
X1344981Y451015D01*
X1345088Y451265D01*
X1345168Y451598D01*
X1345195Y451973D01*
X1345168Y452348D01*
X1345088Y452681D01*
X1344981Y452931D01*
X1344821Y453140D01*
X1344608Y453223D01*
G01X1338814Y450140D02*
X1336878D01*
G01X1343948D02*
X1340814D01*
G01X1343948Y448975D02*
Y450140D01*
G01X1336946Y464701D02*
Y461501D01*
G01X1342246Y460701D02*
X1345446D01*
G01X1346246D02*
X1349446D01*
G01X1338246D02*
X1341446D01*
G01X1340574Y476160D02*
Y472960D01*
G01X1343893Y751275D02*
Y748075D01*
G01X1337693D02*
Y751275D01*
G01X1343893Y748075D02*
X1337693D01*
G01X1343893Y747275D02*
Y744075D01*
G01X1337693Y747275D02*
X1343893D01*
G01X1337693Y744075D02*
Y747275D01*
G01X1343893Y744075D02*
X1337693D01*
G01X1343893Y743275D02*
Y740075D01*
G01X1337693Y743275D02*
X1343893D01*
G01X1337693Y740075D02*
Y743275D01*
G01X1343893Y740075D02*
X1337693D01*
G01X1343893Y739275D02*
Y736075D01*
G01X1337693Y739275D02*
X1343893D01*
G01X1337693Y736075D02*
Y739275D01*
G01X1343893Y736075D02*
X1337693D01*
G01Y751275D02*
X1343893D01*
G01Y767275D02*
Y764075D01*
G01X1337693D02*
Y767275D01*
G01X1343893Y764075D02*
X1337693D01*
G01X1343893Y763275D02*
Y760075D01*
G01X1337693Y763275D02*
X1343893D01*
G01X1337693Y760075D02*
Y763275D01*
G01X1343893Y760075D02*
X1337693D01*
G01X1343893Y759275D02*
Y756075D01*
G01X1337693Y759275D02*
X1343893D01*
G01X1337693Y756075D02*
Y759275D01*
G01X1343893Y756075D02*
X1337693D01*
G01X1343893Y755275D02*
Y752075D01*
G01X1337693Y755275D02*
X1343893D01*
G01X1337693Y752075D02*
Y755275D01*
G01X1343893Y752075D02*
X1337693D01*
G01Y767275D02*
X1343893D01*
G01Y771275D02*
Y768075D01*
G01X1337693Y771275D02*
X1343893D01*
G01X1337693Y768075D02*
Y771275D01*
G01X1343893Y768075D02*
X1337693D01*
G01Y772075D02*
Y775275D01*
G01X1343893Y772075D02*
X1337693D01*
G01X1343893Y775275D02*
Y772075D01*
G01X1337693Y775275D02*
X1343893D01*
G01Y783275D02*
Y780075D01*
G01X1337693D02*
Y783275D01*
G01X1343893Y780075D02*
X1337693D01*
G01X1339400Y795100D02*
X1342600D01*
G01X1339400Y788900D02*
Y795100D01*
G01X1342600Y788900D02*
X1339400D01*
G01X1342600Y795100D02*
Y788900D01*
G01X1346600D02*
X1343400D01*
G01X1346600Y795100D02*
Y788900D01*
G01X1343400Y795100D02*
X1346600D01*
G01X1343400Y788900D02*
Y795100D01*
G01X1335400D02*
X1338600D01*
G01X1335400Y788900D02*
Y795100D01*
G01X1338600Y788900D02*
X1335400D01*
G01X1338600Y795100D02*
Y788900D01*
G01X1337693Y783275D02*
X1343893D01*
G01X1347317Y788900D02*
Y795100D01*
X1350517D01*
Y788900D01*
X1347317D01*
G01X1351217D02*
Y795100D01*
X1354417D01*
Y788900D01*
X1351217D01*
G01X1339400Y811100D02*
X1342600D01*
G01X1339400Y804900D02*
Y811100D01*
G01X1342600Y804900D02*
X1339400D01*
G01X1342600Y811100D02*
Y804900D01*
G01X1343400Y811100D02*
X1346600D01*
G01X1343400Y804900D02*
Y811100D01*
G01X1346600Y804900D02*
X1343400D01*
G01X1346600Y811100D02*
Y804900D01*
G01X1347400Y811100D02*
X1350600D01*
G01X1347400Y804900D02*
Y811100D01*
G01X1350600Y804900D02*
X1347400D01*
G01X1350600Y811100D02*
Y804900D01*
G01X1335400Y811100D02*
X1338600D01*
G01X1335400Y804900D02*
Y811100D01*
G01X1338600Y804900D02*
X1335400D01*
G01X1338600Y811100D02*
Y804900D01*
G01X1348900Y924600D02*
X1352100D01*
G01X1348900Y918400D02*
Y924600D01*
G01X1352100Y918400D02*
X1348900D01*
G01X1344100D02*
X1340900D01*
G01X1344100Y924600D02*
Y918400D01*
G01X1340900Y924600D02*
X1344100D01*
G01X1340900Y918400D02*
Y924600D01*
G01X1340100Y918400D02*
X1336900D01*
G01X1340100Y924600D02*
Y918400D01*
G01X1336900Y924600D02*
X1340100D01*
G01X1336900Y918400D02*
Y924600D01*
G01X1336100D02*
Y918400D01*
G01X1347548Y944503D02*
X1344348D01*
G01X1347548Y950703D02*
Y944503D01*
G01X1344348D02*
Y950703D01*
G01X1351548Y944503D02*
X1348348D01*
G01D02*
Y950703D01*
G01X1337600Y935600D02*
Y929400D01*
G01Y942600D02*
Y936400D01*
G01X1335791Y956536D02*
X1338013D01*
X1338478Y956689D01*
X1338788Y956996D01*
X1338891Y957379D01*
X1338788Y957762D01*
X1338478Y958069D01*
X1338013Y958222D01*
X1335791D01*
G01X1338891Y960479D02*
X1335791D01*
X1336411Y960019D01*
G01X1338891D02*
Y960939D01*
G01Y964039D02*
X1335791D01*
X1338013Y962621D01*
Y964537D01*
G01X1338891Y967139D02*
X1335791D01*
X1338013Y965721D01*
Y967637D01*
G01X1336091Y953243D02*
X1339291D01*
G01X1336091Y947043D02*
Y953243D01*
G01X1339291Y947043D02*
X1336091D01*
G01X1339291Y953243D02*
Y947043D01*
G01X1344348Y950703D02*
X1347548D01*
G01X1348348D02*
X1351548D01*
G01X1348718Y1056313D02*
X1339032D01*
G01D02*
Y1078148D01*
G01X1338184Y1067778D02*
X1335084D01*
Y1068698D01*
X1335239Y1069005D01*
X1335601Y1069235D01*
X1336014Y1069312D01*
X1336427Y1069235D01*
X1336737Y1069043D01*
X1336892Y1068698D01*
Y1067778D01*
G01X1335084Y1070878D02*
X1338184D01*
Y1072412D01*
G01Y1074745D02*
X1335084D01*
X1335704Y1074285D01*
G01X1338184D02*
Y1075205D01*
G01Y1077845D02*
X1335084D01*
X1335704Y1077385D01*
G01X1338184D02*
Y1078305D01*
G01X1339032Y1078148D02*
X1343969Y1083085D01*
G01D02*
X1348718D01*
G01X1340487Y1103442D02*
X1343687D01*
G01X1340487Y1097242D02*
Y1103442D01*
G01X1343687Y1097242D02*
X1340487D01*
G01X1343687Y1103442D02*
Y1097242D01*
G01X1338306Y1103442D02*
Y1097242D01*
X1335106D01*
Y1103442D01*
X1338306D01*
G01X1343859Y1114996D02*
X1347059D01*
G01X1343859Y1108796D02*
Y1114996D01*
G01X1347059Y1108796D02*
X1343859D01*
G01X1347059Y1114996D02*
Y1108796D01*
G01Y1119296D02*
X1343859D01*
G01X1347059Y1125496D02*
Y1119296D01*
G01X1343859D02*
Y1125496D01*
G01X1351061Y1118297D02*
X1347861D01*
G01X1351061Y1124497D02*
Y1118297D01*
G01X1347861D02*
Y1124497D01*
G01X1341228Y1124250D02*
Y1122552D01*
G01Y1109839D02*
X1340220D01*
G01X1341228Y1111693D02*
Y1109839D01*
G01X1343859Y1125496D02*
X1347059D01*
G01X1347861Y1124497D02*
X1351061D01*
G01X1341228Y1133461D02*
Y1130861D01*
G01X1340435Y1133461D02*
X1341228D01*
G01X1348465Y1136752D02*
Y1174548D01*
G01X1354463Y1136752D02*
X1348465D01*
G01X1345833D02*
X1339835D01*
G01X1345833Y1174548D02*
Y1136752D01*
G01X1346106Y1177793D02*
X1363046Y1177790D01*
G01X1346106Y1177193D02*
X1363081Y1177189D01*
G01X1346106Y1176593D02*
X1363089Y1176599D01*
G01X1346106Y1176593D02*
Y1177793D01*
G01X1363038D02*
X1346108D01*
G01D02*
Y1213533D01*
G01X1336109Y1176643D02*
X1336105Y1178152D01*
G01X1336108Y1213533D02*
Y1177793D01*
G01X1348465Y1174548D02*
X1354463D01*
G01X1339835D02*
X1345833D01*
G01X1338108Y1189471D02*
Y1201471D01*
G01X1344108Y1189471D02*
X1338108D01*
G01X1344108Y1201471D02*
Y1189471D01*
G01X1338108Y1201471D02*
X1344108D01*
G01X1343754Y1219762D02*
Y1209562D01*
X1339154D01*
Y1219762D01*
X1343754D01*
G01X1349643Y1215076D02*
X1367345D01*
G01X1349643Y1228189D02*
Y1215076D01*
G01X1346108Y1213533D02*
X1363038D01*
G01X1348351Y1230276D02*
Y1239176D01*
G01X1368637Y1230276D02*
X1348351D01*
G01X1349643Y1254376D02*
Y1241330D01*
G01X1348343Y1249202D02*
Y1266904D01*
G01X1335420Y1249202D02*
X1348343D01*
G01X1348351Y1239176D02*
X1368637D01*
G01X1367345Y1254376D02*
X1349643D01*
G01X1348343Y1266904D02*
X1335307D01*
G01X1360777Y154138D02*
Y144690D01*
G01X1352522Y139647D02*
Y142847D01*
G01X1358722Y139647D02*
X1352522D01*
G01X1358722Y142847D02*
Y139647D01*
G01X1352522Y142847D02*
X1358722D01*
G01X1351743D02*
Y139647D01*
G01X1362184Y148168D02*
Y151368D01*
G01X1368384Y148168D02*
X1362184D01*
G01Y144168D02*
Y147368D01*
G01X1368384Y144168D02*
X1362184D01*
G01Y147368D02*
X1368384D01*
G01X1357359Y154138D02*
X1360777D01*
G01X1355359Y152414D02*
X1357359Y154138D01*
G01X1353359D02*
X1355359Y152414D01*
G01X1362184Y151368D02*
X1368384D01*
G01X1359893Y304598D02*
Y307698D01*
G01X1361503D02*
Y304598D01*
G01Y306148D02*
X1359893D01*
G01X1363070Y305890D02*
X1363338Y306251D01*
X1363568Y306458D01*
X1363875Y306561D01*
X1364143Y306458D01*
X1364335Y306251D01*
X1364488Y305941D01*
X1364526Y305580D01*
X1364488Y305270D01*
X1364335Y304960D01*
X1364105Y304701D01*
X1363836Y304598D01*
X1363530Y304701D01*
X1363261Y305011D01*
X1363108Y305476D01*
X1363070Y305993D01*
X1363146Y306665D01*
X1363261Y307026D01*
X1363453Y307388D01*
X1363721Y307646D01*
X1363990Y307698D01*
X1364258Y307595D01*
X1364450Y307336D01*
G01X1366898Y307698D02*
X1366591Y307595D01*
X1366361Y307336D01*
X1366208Y307026D01*
X1366093Y306613D01*
X1366055Y306148D01*
X1366093Y305683D01*
X1366208Y305270D01*
X1366361Y304960D01*
X1366591Y304701D01*
X1366898Y304598D01*
X1367205Y304701D01*
X1367435Y304960D01*
X1367588Y305270D01*
X1367703Y305683D01*
X1367741Y306148D01*
X1367703Y306613D01*
X1367588Y307026D01*
X1367435Y307336D01*
X1367205Y307595D01*
X1366898Y307698D01*
G01X1359844Y326177D02*
Y328027D01*
G01X1353644Y326177D02*
Y328402D01*
G01X1359844Y326177D02*
X1353644D01*
G01X1359844Y341925D02*
Y344120D01*
G01Y334051D02*
Y336222D01*
G01Y340851D02*
Y338584D01*
G01X1354480Y337651D02*
X1358996D01*
G01X1354480Y337251D02*
X1358996D01*
G01X1359844Y332977D02*
Y330786D01*
G01X1354491Y329777D02*
X1358967D01*
G01X1354491Y329377D02*
X1358967D01*
G01X1353644Y332977D02*
Y330992D01*
G01Y334051D02*
Y336242D01*
G01Y340851D02*
Y338782D01*
G01Y341925D02*
Y344000D01*
G01Y332977D02*
X1359844D01*
G01Y334051D02*
X1353644D01*
G01Y340851D02*
X1359844D01*
G01Y341925D02*
X1353644D01*
G01X1359844Y356599D02*
Y354395D01*
G01X1354599Y352999D02*
X1358976D01*
G01X1354599Y353399D02*
X1358976D01*
G01X1359844Y349799D02*
Y351840D01*
G01Y348725D02*
Y346477D01*
G01X1354520Y345125D02*
X1359014D01*
G01X1354520Y345525D02*
X1359014D01*
G01X1353644Y348725D02*
Y346629D01*
G01Y349799D02*
Y351959D01*
G01Y356599D02*
Y354469D01*
G01Y348725D02*
X1359844D01*
G01Y349799D02*
X1353644D01*
G01Y356599D02*
X1359844D01*
G01X1352244Y406628D02*
Y422140D01*
G01X1359446Y426201D02*
Y423001D01*
G01X1353246D02*
Y426201D01*
G01X1359446Y423001D02*
X1353246D01*
G01X1359446Y429701D02*
Y426501D01*
G01X1353246Y429701D02*
X1359446D01*
G01X1353246Y426501D02*
Y429701D01*
G01X1359446Y426501D02*
X1353246D01*
G01Y433501D02*
Y436701D01*
G01X1359446Y433501D02*
X1353246D01*
G01X1359446Y436701D02*
Y433501D01*
G01X1353246Y436701D02*
X1359446D01*
G01X1353246Y441501D02*
Y444701D01*
G01X1359446Y441501D02*
X1353246D01*
G01X1359446Y444701D02*
Y441501D01*
G01X1351347Y443639D02*
Y437439D01*
G01X1353246Y426201D02*
X1359446D01*
G01X1353246Y437501D02*
Y440701D01*
G01X1359446Y437501D02*
X1353246D01*
G01X1359446Y440701D02*
Y437501D01*
G01X1353246Y440701D02*
X1359446D01*
G01Y433201D02*
Y430001D01*
G01X1353246Y433201D02*
X1359446D01*
G01X1353246Y430001D02*
Y433201D01*
G01X1359446Y430001D02*
X1353246D01*
G01Y444701D02*
X1359446D01*
G01X1353246Y445501D02*
Y448701D01*
G01X1359446Y445501D02*
X1353246D01*
G01X1359446Y448701D02*
Y445501D01*
G01X1353246Y448701D02*
X1359446D01*
G01X1353246Y451001D02*
Y454201D01*
G01X1359446Y451001D02*
X1353246D01*
G01X1359446Y454201D02*
Y451001D01*
G01X1353246Y454201D02*
X1359446D01*
G01X1354242Y559949D02*
X1370758D01*
G01X1354242Y591051D02*
Y559949D01*
G01X1368051Y591051D02*
X1362500Y585500D01*
G01D02*
X1356949Y591051D01*
G01X1357107Y595367D02*
Y593145D01*
X1357260Y592680D01*
X1357567Y592370D01*
X1357950Y592267D01*
X1358333Y592370D01*
X1358640Y592680D01*
X1358793Y593145D01*
Y595367D01*
G01X1360207Y592887D02*
X1360437Y592525D01*
X1360743Y592319D01*
X1361088Y592267D01*
X1361395Y592319D01*
X1361702Y592577D01*
X1361893Y592887D01*
X1361932Y593197D01*
X1361855Y593559D01*
X1361587Y593817D01*
X1361318Y593920D01*
X1360973D01*
G01X1361318D02*
X1361548Y594075D01*
X1361740Y594334D01*
X1361817Y594644D01*
X1361740Y594954D01*
X1361548Y595212D01*
X1361203Y595367D01*
X1360858Y595315D01*
X1360513Y595109D01*
G01X1363307Y592732D02*
X1363537Y592474D01*
X1363805Y592319D01*
X1364150Y592267D01*
X1364495Y592370D01*
X1364763Y592577D01*
X1364955Y592939D01*
X1364993Y593352D01*
X1364917Y593765D01*
X1364725Y594024D01*
X1364457Y594230D01*
X1364188Y594282D01*
X1363920Y594230D01*
X1363575Y594024D01*
X1363690Y595367D01*
X1364725D01*
G01X1367250D02*
X1366943Y595264D01*
X1366713Y595005D01*
X1366560Y594695D01*
X1366445Y594282D01*
X1366407Y593817D01*
X1366445Y593352D01*
X1366560Y592939D01*
X1366713Y592629D01*
X1366943Y592370D01*
X1367250Y592267D01*
X1367557Y592370D01*
X1367787Y592629D01*
X1367940Y592939D01*
X1368055Y593352D01*
X1368093Y593817D01*
X1368055Y594282D01*
X1367940Y594695D01*
X1367787Y595005D01*
X1367557Y595264D01*
X1367250Y595367D01*
G01X1356949Y591051D02*
X1354242D01*
G01Y606449D02*
X1370758D01*
G01X1354242Y637551D02*
Y606449D01*
G01X1368051Y637551D02*
X1362500Y632000D01*
G01D02*
X1356949Y637551D01*
G01X1357107Y641867D02*
Y639645D01*
X1357260Y639180D01*
X1357567Y638870D01*
X1357950Y638767D01*
X1358333Y638870D01*
X1358640Y639180D01*
X1358793Y639645D01*
Y641867D01*
G01X1360207Y639387D02*
X1360437Y639025D01*
X1360743Y638819D01*
X1361088Y638767D01*
X1361395Y638819D01*
X1361702Y639077D01*
X1361893Y639387D01*
X1361932Y639697D01*
X1361855Y640059D01*
X1361587Y640317D01*
X1361318Y640420D01*
X1360973D01*
G01X1361318D02*
X1361548Y640575D01*
X1361740Y640834D01*
X1361817Y641144D01*
X1361740Y641454D01*
X1361548Y641712D01*
X1361203Y641867D01*
X1360858Y641815D01*
X1360513Y641609D01*
G01X1364610Y638767D02*
Y641867D01*
X1363192Y639645D01*
X1365108D01*
G01X1366598Y639129D02*
X1366867Y638870D01*
X1367173Y638767D01*
X1367480Y638870D01*
X1367748Y639180D01*
X1367940Y639645D01*
X1368017Y640110D01*
Y640679D01*
X1367940Y641144D01*
X1367748Y641557D01*
X1367518Y641764D01*
X1367250Y641867D01*
X1366943Y641764D01*
X1366713Y641557D01*
X1366560Y641247D01*
X1366483Y640834D01*
X1366560Y640472D01*
X1366752Y640110D01*
X1366982Y639904D01*
X1367250Y639852D01*
X1367557Y639955D01*
X1367787Y640214D01*
X1368017Y640679D01*
G01X1356949Y637551D02*
X1354242D01*
G01Y650949D02*
X1370758D01*
G01X1354242Y682051D02*
Y650949D01*
G01X1357107Y686367D02*
Y684145D01*
X1357260Y683680D01*
X1357567Y683370D01*
X1357950Y683267D01*
X1358333Y683370D01*
X1358640Y683680D01*
X1358793Y684145D01*
Y686367D01*
G01X1360207Y683887D02*
X1360437Y683525D01*
X1360743Y683319D01*
X1361088Y683267D01*
X1361395Y683319D01*
X1361702Y683577D01*
X1361893Y683887D01*
X1361932Y684197D01*
X1361855Y684559D01*
X1361587Y684817D01*
X1361318Y684920D01*
X1360973D01*
G01X1361318D02*
X1361548Y685075D01*
X1361740Y685334D01*
X1361817Y685644D01*
X1361740Y685954D01*
X1361548Y686212D01*
X1361203Y686367D01*
X1360858Y686315D01*
X1360513Y686109D01*
G01X1364610Y683267D02*
Y686367D01*
X1363192Y684145D01*
X1365108D01*
G01X1367250Y683267D02*
X1367518Y683319D01*
X1367825Y683474D01*
X1368017Y683732D01*
X1368093Y684094D01*
X1368017Y684455D01*
X1367787Y684765D01*
X1367442Y684920D01*
X1367058D01*
X1366828Y685024D01*
X1366637Y685282D01*
X1366560Y685644D01*
X1366675Y686005D01*
X1366943Y686264D01*
X1367250Y686367D01*
X1367557Y686264D01*
X1367825Y686005D01*
X1367940Y685644D01*
X1367863Y685282D01*
X1367672Y685024D01*
X1367442Y684920D01*
X1367058D01*
X1366713Y684765D01*
X1366483Y684455D01*
X1366407Y684094D01*
X1366483Y683732D01*
X1366675Y683474D01*
X1366982Y683319D01*
X1367250Y683267D01*
G01X1368051Y682051D02*
X1362500Y676500D01*
G01X1356949Y682051D02*
X1354242D01*
G01X1362500Y676500D02*
X1356949Y682051D01*
G01X1354242Y697949D02*
X1370758D01*
G01X1354242Y729051D02*
Y697949D01*
G01X1357107Y733367D02*
Y731145D01*
X1357260Y730680D01*
X1357567Y730370D01*
X1357950Y730267D01*
X1358333Y730370D01*
X1358640Y730680D01*
X1358793Y731145D01*
Y733367D01*
G01X1360207Y730887D02*
X1360437Y730525D01*
X1360743Y730319D01*
X1361088Y730267D01*
X1361395Y730319D01*
X1361702Y730577D01*
X1361893Y730887D01*
X1361932Y731197D01*
X1361855Y731559D01*
X1361587Y731817D01*
X1361318Y731920D01*
X1360973D01*
G01X1361318D02*
X1361548Y732075D01*
X1361740Y732334D01*
X1361817Y732644D01*
X1361740Y732954D01*
X1361548Y733212D01*
X1361203Y733367D01*
X1360858Y733315D01*
X1360513Y733109D01*
G01X1364610Y730267D02*
Y733367D01*
X1363192Y731145D01*
X1365108D01*
G01X1367173Y730267D02*
X1367250Y730939D01*
X1367365Y731507D01*
X1367518Y732024D01*
X1367710Y732592D01*
X1368017Y733367D01*
X1366483D01*
G01X1368051Y729051D02*
X1362500Y723500D01*
G01X1356949Y729051D02*
X1354242D01*
G01X1362500Y723500D02*
X1356949Y729051D01*
G01X1360243Y783666D02*
Y786766D01*
G01X1361853D02*
Y783666D01*
G01Y785216D02*
X1360243D01*
G01X1363420Y784958D02*
X1363688Y785319D01*
X1363918Y785526D01*
X1364225Y785629D01*
X1364493Y785526D01*
X1364685Y785319D01*
X1364838Y785009D01*
X1364876Y784648D01*
X1364838Y784338D01*
X1364685Y784028D01*
X1364455Y783769D01*
X1364186Y783666D01*
X1363880Y783769D01*
X1363611Y784079D01*
X1363458Y784544D01*
X1363420Y785061D01*
X1363496Y785733D01*
X1363611Y786094D01*
X1363803Y786456D01*
X1364071Y786714D01*
X1364340Y786766D01*
X1364608Y786663D01*
X1364800Y786404D01*
G01X1367248Y783666D02*
X1367516Y783718D01*
X1367823Y783873D01*
X1368015Y784131D01*
X1368091Y784493D01*
X1368015Y784854D01*
X1367785Y785164D01*
X1367440Y785319D01*
X1367056D01*
X1366826Y785423D01*
X1366635Y785681D01*
X1366558Y786043D01*
X1366673Y786404D01*
X1366941Y786663D01*
X1367248Y786766D01*
X1367555Y786663D01*
X1367823Y786404D01*
X1367938Y786043D01*
X1367861Y785681D01*
X1367670Y785423D01*
X1367440Y785319D01*
X1367056D01*
X1366711Y785164D01*
X1366481Y784854D01*
X1366405Y784493D01*
X1366481Y784131D01*
X1366673Y783873D01*
X1366980Y783718D01*
X1367248Y783666D01*
G01X1366600Y804900D02*
X1363400D01*
G01X1366600Y811100D02*
Y804900D01*
G01X1363400Y811100D02*
X1366600D01*
G01X1363400Y804900D02*
Y811100D01*
G01X1370600Y804900D02*
X1367400D01*
G01Y811100D02*
X1370600D01*
G01X1367400Y804900D02*
Y811100D01*
G01X1362600Y804900D02*
X1359400D01*
G01X1362600Y811100D02*
Y804900D01*
G01X1359400Y811100D02*
X1362600D01*
G01X1359400Y804900D02*
Y811100D01*
G01X1358600Y804900D02*
X1355400D01*
G01X1358600Y811100D02*
Y804900D01*
G01X1355400Y811100D02*
X1358600D01*
G01X1355400Y804900D02*
Y811100D01*
G01X1351400D02*
X1354600D01*
G01X1351400Y804900D02*
Y811100D01*
G01X1354600Y804900D02*
X1351400D01*
G01X1354600Y811100D02*
Y804900D01*
G01X1352900Y924600D02*
X1356100D01*
G01X1352900Y918400D02*
Y924600D01*
G01X1356100Y918400D02*
X1352900D01*
G01X1356100Y924600D02*
Y918400D01*
G01X1356900Y924600D02*
X1360100D01*
G01X1356900Y918400D02*
Y924600D01*
G01X1360100Y918400D02*
X1356900D01*
G01X1360100Y924600D02*
Y918400D01*
G01X1360900Y924600D02*
X1364100D01*
G01X1360900Y918400D02*
Y924600D01*
G01X1364100Y918400D02*
X1360900D01*
G01X1364100Y924600D02*
Y918400D01*
G01X1364900Y924600D02*
X1368100D01*
G01X1364900Y918400D02*
Y924600D01*
G01X1368100Y918400D02*
X1364900D01*
G01X1352100Y924600D02*
Y918400D01*
G01X1367548Y950703D02*
Y944503D01*
G01X1364348D02*
Y950703D01*
G01X1367548Y944503D02*
X1364348D01*
G01X1359548D02*
X1356348D01*
G01X1359548Y950703D02*
Y944503D01*
G01X1356348D02*
Y950703D01*
G01X1355548Y944503D02*
X1352348D01*
G01X1355548Y950703D02*
Y944503D01*
G01X1352348D02*
Y950703D01*
G01X1351548D02*
Y944503D01*
G01X1363548D02*
X1360348D01*
G01X1363548Y950703D02*
Y944503D01*
G01X1360348D02*
Y950703D01*
G01X1364348D02*
X1367548D01*
G01X1356348D02*
X1359548D01*
G01X1352348D02*
X1355548D01*
G01X1360348D02*
X1363548D01*
G01X1376265Y993766D02*
X1364265D01*
G01D02*
Y999766D01*
G01D02*
X1376265D01*
G01X1364587Y1007675D02*
X1361487D01*
Y1008595D01*
X1361642Y1008902D01*
X1362004Y1009132D01*
X1362417Y1009209D01*
X1362830Y1009132D01*
X1363140Y1008940D01*
X1363295Y1008595D01*
Y1007675D01*
G01X1361487Y1010699D02*
X1363709D01*
X1364174Y1010852D01*
X1364484Y1011159D01*
X1364587Y1011542D01*
X1364484Y1011925D01*
X1364174Y1012232D01*
X1363709Y1012385D01*
X1361487D01*
G01X1364587Y1014642D02*
X1361487D01*
X1362107Y1014182D01*
G01X1364587D02*
Y1015102D01*
G01Y1017742D02*
X1361487D01*
X1362107Y1017282D01*
G01X1364587D02*
Y1018202D01*
G01X1366359Y1013925D02*
X1372559D01*
G01X1366359Y1010725D02*
Y1013925D01*
G01X1372559Y1010725D02*
X1366359D01*
G01Y1017925D02*
X1372559D01*
G01X1366359Y1014725D02*
Y1017925D01*
G01X1372559Y1014725D02*
X1366359D01*
G01X1364365Y1024366D02*
Y1021166D01*
G01X1358165Y1024366D02*
X1364365D01*
G01X1358165Y1021166D02*
Y1024366D01*
G01X1364365Y1021166D02*
X1358165D01*
G01Y1024666D02*
Y1027866D01*
G01X1364365Y1024666D02*
X1358165D01*
G01X1364365Y1027866D02*
Y1024666D01*
G01X1366665Y1026366D02*
X1372865D01*
Y1023166D01*
X1366665D01*
Y1026366D01*
G01X1358165Y1027866D02*
X1364365D01*
G01Y1035866D02*
Y1032666D01*
G01X1358165Y1035866D02*
X1364365D01*
G01X1358165Y1032666D02*
Y1035866D01*
G01X1364365Y1032666D02*
X1358165D01*
G01X1371443Y1041540D02*
X1365243D01*
Y1044740D01*
X1371443D01*
Y1041540D01*
G01X1364365Y1028666D02*
X1358165D01*
Y1031866D01*
X1364365D01*
Y1028666D01*
G01X1371366Y1045447D02*
X1365166D01*
Y1048647D01*
X1371366D01*
Y1045447D01*
G01X1356118Y1056313D02*
X1365804D01*
G01D02*
Y1078148D01*
G01X1351418Y1090088D02*
Y1096088D01*
G01X1363418Y1090088D02*
X1351418D01*
G01X1363418Y1096088D02*
Y1090088D01*
G01X1365804Y1078148D02*
X1360867Y1083085D01*
G01D02*
X1356118D01*
G01X1351418Y1096088D02*
X1363418D01*
G01X1355370Y1107230D02*
X1358570D01*
G01X1355370Y1101030D02*
Y1107230D01*
G01X1358570Y1101030D02*
X1355370D01*
G01X1358570Y1107230D02*
Y1101030D01*
G01X1353892Y1097226D02*
Y1100426D01*
G01X1360092Y1097226D02*
X1353892D01*
G01X1360092Y1100426D02*
Y1097226D01*
G01X1353892Y1100426D02*
X1360092D01*
G01X1359157Y1107230D02*
X1362357D01*
G01X1359157Y1101030D02*
Y1107230D01*
G01X1362357Y1101030D02*
X1359157D01*
G01X1362357Y1107230D02*
Y1101030D01*
G01X1370434Y1103442D02*
Y1097242D01*
X1367234D01*
Y1103442D01*
X1370434D01*
G01X1353670Y1109839D02*
Y1112030D01*
G01X1354403Y1109839D02*
X1353670D01*
G01Y1133461D02*
X1354463D01*
G01X1353670Y1130861D02*
Y1133461D01*
G01X1365855Y1178444D02*
Y1180684D01*
G01X1364230Y1179471D02*
X1367480D01*
G01X1363039Y1176643D02*
X1363035Y1178152D01*
G01X1363038Y1213533D02*
Y1177793D01*
G01X1365038Y1189471D02*
Y1201471D01*
G01X1371038Y1189471D02*
X1365038D01*
G01Y1201471D02*
X1371038D01*
G01X1367345Y1215076D02*
Y1228016D01*
G01X1365113Y1211128D02*
Y1213554D01*
G01X1367345Y1241762D02*
Y1254376D01*
G01X1371960Y111951D02*
Y118151D01*
G01X1375160Y111951D02*
X1371960D01*
G01X1375160Y118151D02*
Y111951D01*
G01X1382880Y109424D02*
X1386080D01*
G01X1382880Y103224D02*
Y109424D01*
G01X1386080Y103224D02*
X1382880D01*
G01X1378880Y109424D02*
X1382080D01*
G01X1378880Y103224D02*
Y109424D01*
G01X1382080Y103224D02*
X1378880D01*
G01X1382080Y109424D02*
Y103224D01*
G01X1377334Y111734D02*
Y123508D01*
G01X1387096Y111734D02*
X1377334D01*
G01X1371960Y118151D02*
X1375160D01*
G01X1380105Y126223D02*
X1376905D01*
G01X1380105Y132423D02*
Y126223D01*
G01X1376905Y132423D02*
X1380105D01*
G01X1376905Y126223D02*
Y132423D01*
G01X1380905D02*
X1384105D01*
G01X1380905Y126223D02*
Y132423D01*
G01X1384105Y126223D02*
X1380905D01*
G01X1371753Y118830D02*
X1368653D01*
Y119750D01*
X1368808Y120057D01*
X1369170Y120287D01*
X1369583Y120364D01*
X1369996Y120287D01*
X1370306Y120095D01*
X1370461Y119750D01*
Y118830D01*
G01X1368653Y121854D02*
X1370875D01*
X1371340Y122007D01*
X1371650Y122314D01*
X1371753Y122697D01*
X1371650Y123080D01*
X1371340Y123387D01*
X1370875Y123540D01*
X1368653D01*
G01X1371753Y125797D02*
X1368653D01*
X1369273Y125337D01*
G01X1371753D02*
Y126257D01*
G01X1371133Y128054D02*
X1371495Y128284D01*
X1371701Y128590D01*
X1371753Y128935D01*
X1371701Y129242D01*
X1371443Y129549D01*
X1371133Y129740D01*
X1370823Y129779D01*
X1370461Y129702D01*
X1370203Y129434D01*
X1370100Y129165D01*
Y128820D01*
G01Y129165D02*
X1369945Y129395D01*
X1369686Y129587D01*
X1369376Y129664D01*
X1369066Y129587D01*
X1368808Y129395D01*
X1368653Y129050D01*
X1368705Y128705D01*
X1368911Y128360D01*
G01X1371753Y131997D02*
X1368653D01*
X1369273Y131537D01*
G01X1371753D02*
Y132457D01*
G01X1377334Y123508D02*
X1387096D01*
G01X1368384Y151368D02*
Y148168D01*
G01Y147368D02*
Y144168D01*
G01X1377294Y146229D02*
X1374094D01*
G01X1377294Y152429D02*
Y146229D01*
G01X1374094D02*
Y152429D01*
G01X1369500Y135107D02*
X1371722D01*
X1372187Y135260D01*
X1372497Y135567D01*
X1372600Y135950D01*
X1372497Y136333D01*
X1372187Y136640D01*
X1371722Y136793D01*
X1369500D01*
G01X1371980Y138207D02*
X1372342Y138437D01*
X1372548Y138743D01*
X1372600Y139088D01*
X1372548Y139395D01*
X1372290Y139702D01*
X1371980Y139893D01*
X1371670Y139932D01*
X1371308Y139855D01*
X1371050Y139587D01*
X1370947Y139318D01*
Y138973D01*
G01Y139318D02*
X1370792Y139548D01*
X1370533Y139740D01*
X1370223Y139817D01*
X1369913Y139740D01*
X1369655Y139548D01*
X1369500Y139203D01*
X1369552Y138858D01*
X1369758Y138513D01*
G01X1372238Y141498D02*
X1372497Y141767D01*
X1372600Y142073D01*
X1372497Y142380D01*
X1372187Y142648D01*
X1371722Y142840D01*
X1371257Y142917D01*
X1370688D01*
X1370223Y142840D01*
X1369810Y142648D01*
X1369603Y142418D01*
X1369500Y142150D01*
X1369603Y141843D01*
X1369810Y141613D01*
X1370120Y141460D01*
X1370533Y141383D01*
X1370895Y141460D01*
X1371257Y141652D01*
X1371463Y141882D01*
X1371515Y142150D01*
X1371412Y142457D01*
X1371153Y142687D01*
X1370688Y142917D01*
G01X1372135Y144407D02*
X1372393Y144637D01*
X1372548Y144905D01*
X1372600Y145250D01*
X1372497Y145595D01*
X1372290Y145863D01*
X1371928Y146055D01*
X1371515Y146093D01*
X1371102Y146017D01*
X1370843Y145825D01*
X1370637Y145557D01*
X1370585Y145288D01*
X1370637Y145020D01*
X1370843Y144675D01*
X1369500Y144790D01*
Y145825D01*
G01X1375784Y144395D02*
Y135095D01*
G01X1386384Y144395D02*
X1375784D01*
G01Y134995D02*
X1386384D01*
G01X1374094Y152429D02*
X1377294D01*
G01X1374094Y159540D02*
X1377294D01*
G01X1374094Y153340D02*
Y159540D01*
G01X1377294Y153340D02*
X1374094D01*
G01X1377294Y159540D02*
Y153340D01*
G01X1380583Y179400D02*
Y182500D01*
X1381503D01*
X1381810Y182345D01*
X1382040Y181983D01*
X1382117Y181570D01*
X1382040Y181157D01*
X1381848Y180847D01*
X1381503Y180692D01*
X1380583D01*
G01X1383607Y179400D02*
Y182500D01*
X1384373D01*
X1384680Y182345D01*
X1384910Y182138D01*
X1385102Y181828D01*
X1385255Y181467D01*
X1385293Y180950D01*
X1385255Y180433D01*
X1385102Y180072D01*
X1384910Y179762D01*
X1384680Y179555D01*
X1384373Y179400D01*
X1383607D01*
G01X1386822Y180692D02*
X1387090Y181053D01*
X1387320Y181260D01*
X1387627Y181363D01*
X1387895Y181260D01*
X1388087Y181053D01*
X1388240Y180743D01*
X1388278Y180382D01*
X1388240Y180072D01*
X1388087Y179762D01*
X1387857Y179503D01*
X1387588Y179400D01*
X1387282Y179503D01*
X1387013Y179813D01*
X1386860Y180278D01*
X1386822Y180795D01*
X1386898Y181467D01*
X1387013Y181828D01*
X1387205Y182190D01*
X1387473Y182448D01*
X1387742Y182500D01*
X1388010Y182397D01*
X1388202Y182138D01*
G01X1389998Y179762D02*
X1390267Y179503D01*
X1390573Y179400D01*
X1390880Y179503D01*
X1391148Y179813D01*
X1391340Y180278D01*
X1391417Y180743D01*
Y181312D01*
X1391340Y181777D01*
X1391148Y182190D01*
X1390918Y182397D01*
X1390650Y182500D01*
X1390343Y182397D01*
X1390113Y182190D01*
X1389960Y181880D01*
X1389883Y181467D01*
X1389960Y181105D01*
X1390152Y180743D01*
X1390382Y180537D01*
X1390650Y180485D01*
X1390957Y180588D01*
X1391187Y180847D01*
X1391417Y181312D01*
G01X1376888Y189435D02*
X1379128D01*
G01X1377915Y191060D02*
Y187810D01*
G01X1380529Y195583D02*
X1410088D01*
G01X1380529Y184087D02*
Y195583D01*
G01X1410088Y184087D02*
X1380529D01*
G01X1380682Y204506D02*
Y216506D01*
G01X1386682Y204506D02*
X1380682D01*
G01Y216506D02*
X1386682D01*
G01X1383450Y243678D02*
X1389650D01*
G01X1383450Y240478D02*
Y243678D01*
G01X1389650Y240478D02*
X1383450D01*
G01X1379480Y246771D02*
Y249971D01*
G01X1385680Y246771D02*
X1379480D01*
G01Y249971D02*
X1385680D01*
G01X1379480Y253971D02*
X1385680D01*
G01X1379480Y250771D02*
Y253971D01*
G01X1385680Y250771D02*
X1379480D01*
G01X1376351Y319271D02*
Y322471D01*
G01X1382551Y319271D02*
X1376351D01*
G01X1382551Y322471D02*
Y319271D01*
G01X1376351Y322471D02*
X1382551D01*
G01X1376351Y323771D02*
Y326971D01*
G01X1382551Y323771D02*
X1376351D01*
G01X1382551Y326971D02*
Y323771D01*
G01X1376351Y326971D02*
X1382551D01*
G01X1376351Y341771D02*
Y344971D01*
G01X1382551Y341771D02*
X1376351D01*
G01X1382551Y344971D02*
Y341771D01*
G01X1376351Y337271D02*
Y340471D01*
G01X1382551Y337271D02*
X1376351D01*
G01X1382551Y340471D02*
Y337271D01*
G01X1376351Y340471D02*
X1382551D01*
G01X1376351Y332771D02*
Y335971D01*
G01X1382551Y332771D02*
X1376351D01*
G01X1382551Y335971D02*
Y332771D01*
G01X1376351Y335971D02*
X1382551D01*
G01X1376351Y328271D02*
Y331471D01*
G01X1382551Y328271D02*
X1376351D01*
G01X1382551Y331471D02*
Y328271D01*
G01X1376351Y331471D02*
X1382551D01*
G01X1376351Y344971D02*
X1382551D01*
G01X1376351Y346271D02*
Y349471D01*
G01X1382551Y346271D02*
X1376351D01*
G01X1382551Y349471D02*
Y346271D01*
G01X1376351Y349471D02*
X1382551D01*
G01X1376351Y359771D02*
Y362971D01*
G01X1382551Y359771D02*
X1376351D01*
G01X1382551Y362971D02*
Y359771D01*
G01X1376351Y355271D02*
Y358471D01*
G01X1382551Y355271D02*
X1376351D01*
G01X1382551Y358471D02*
Y355271D01*
G01X1376351Y358471D02*
X1382551D01*
G01X1376351Y350771D02*
Y353971D01*
G01X1382551Y350771D02*
X1376351D01*
G01X1382551Y353971D02*
Y350771D01*
G01X1376351Y353971D02*
X1382551D01*
G01X1376351Y362971D02*
X1382551D01*
G01X1383641Y567400D02*
Y570600D01*
G01X1389841Y567400D02*
X1383641D01*
G01Y570600D02*
X1389841D01*
G01X1383641Y563400D02*
Y566600D01*
G01X1389841Y563400D02*
X1383641D01*
G01Y566600D02*
X1389841D01*
G01X1383641Y559400D02*
Y562600D01*
G01X1389841Y559400D02*
X1383641D01*
G01Y562600D02*
X1389841D01*
G01X1370758Y559949D02*
Y591051D01*
G01X1382100Y588900D02*
X1378900D01*
G01X1382100Y595100D02*
Y588900D01*
G01X1378900Y595100D02*
X1382100D01*
G01X1378900Y588900D02*
Y595100D01*
G01X1370758Y591051D02*
X1368051D01*
G01X1383641Y613900D02*
Y617100D01*
G01X1389841Y613900D02*
X1383641D01*
G01Y617100D02*
X1389841D01*
G01X1383641Y609900D02*
Y613100D01*
G01X1389841Y609900D02*
X1383641D01*
G01Y613100D02*
X1389841D01*
G01X1383641Y605900D02*
Y609100D01*
G01X1389841Y605900D02*
X1383641D01*
G01Y609100D02*
X1389841D01*
G01X1370758Y606449D02*
Y637551D01*
G01X1382100Y635400D02*
X1378900D01*
G01X1382100Y641600D02*
Y635400D01*
G01X1378900D02*
Y641600D01*
G01D02*
X1382100D01*
G01X1370758Y637551D02*
X1368051D01*
G01X1370758Y650949D02*
Y682051D01*
G01X1382100Y679900D02*
X1378900D01*
G01X1382100Y686100D02*
Y679900D01*
G01X1378900D02*
Y686100D01*
G01X1370758Y682051D02*
X1368051D01*
G01X1378900Y686100D02*
X1382100D01*
G01X1370758Y697949D02*
Y729051D01*
G01X1382100Y726900D02*
X1378900D01*
G01X1382100Y733100D02*
Y726900D01*
G01X1378900Y733100D02*
X1382100D01*
G01X1378900Y726900D02*
Y733100D01*
G01X1370758Y729051D02*
X1368051D01*
G01X1374600Y804900D02*
X1371400D01*
G01X1374600Y811100D02*
Y804900D01*
G01X1371400Y811100D02*
X1374600D01*
G01X1371400Y804900D02*
Y811100D01*
G01X1382600Y804900D02*
X1379400D01*
G01X1382600Y811100D02*
Y804900D01*
G01X1379400Y811100D02*
X1382600D01*
G01X1379400Y804900D02*
Y811100D01*
G01X1370600D02*
Y804900D01*
G01X1375417Y804898D02*
Y811098D01*
X1378617D01*
Y804898D01*
X1375417D01*
G01X1368900Y924600D02*
X1372100D01*
G01X1368900Y918400D02*
Y924600D01*
G01X1372100Y918400D02*
X1368900D01*
G01X1372100Y924600D02*
Y918400D01*
G01X1376900Y924600D02*
X1380100D01*
G01X1376900Y918400D02*
Y924600D01*
G01X1380100Y918400D02*
X1376900D01*
G01X1380100Y924600D02*
Y918400D01*
G01X1372900Y924600D02*
X1376100D01*
G01X1372900Y918400D02*
Y924600D01*
G01X1376100Y918400D02*
X1372900D01*
G01X1376100Y924600D02*
Y918400D01*
G01X1380900Y924600D02*
X1384100D01*
G01X1380900Y918400D02*
Y924600D01*
G01X1384100Y918400D02*
X1380900D01*
G01X1368100Y924600D02*
Y918400D01*
G01X1372348Y944503D02*
Y950703D01*
G01X1375548Y944503D02*
X1372348D01*
G01X1375548Y950703D02*
Y944503D01*
G01X1371548Y950703D02*
Y944503D01*
G01X1368348D02*
Y950703D01*
G01X1371548Y944503D02*
X1368348D01*
G01X1380960Y932721D02*
Y938921D01*
X1384160D01*
Y932721D01*
X1380960D01*
G01X1376903Y932720D02*
Y938920D01*
X1380103D01*
Y932720D01*
X1376903D01*
G01X1372348Y950703D02*
X1375548D01*
G01X1368348D02*
X1371548D01*
G01X1376265Y999766D02*
Y993766D01*
G01X1375059Y1003780D02*
Y1000580D01*
G01X1368859Y1003780D02*
X1375059D01*
G01X1368859Y1000580D02*
Y1003780D01*
G01X1375059Y1000580D02*
X1368859D01*
G01X1375059Y1008780D02*
Y1005580D01*
G01X1368859Y1008780D02*
X1375059D01*
G01X1368859Y1005580D02*
Y1008780D01*
G01X1375059Y1005580D02*
X1368859D01*
G01X1378602Y1005823D02*
X1376102D01*
X1377894Y1004836D01*
Y1006170D01*
G01X1376102Y1007703D02*
X1376185Y1007490D01*
X1376394Y1007330D01*
X1376644Y1007223D01*
X1376977Y1007143D01*
X1377352Y1007116D01*
X1377727Y1007143D01*
X1378060Y1007223D01*
X1378310Y1007330D01*
X1378519Y1007490D01*
X1378602Y1007703D01*
X1378519Y1007916D01*
X1378310Y1008076D01*
X1378060Y1008183D01*
X1377727Y1008263D01*
X1377352Y1008290D01*
X1376977Y1008263D01*
X1376644Y1008183D01*
X1376394Y1008076D01*
X1376185Y1007916D01*
X1376102Y1007703D01*
G01X1381732Y1007460D02*
X1379826D01*
G01X1378369Y1010203D02*
X1375369D01*
G01X1379826Y1007460D02*
Y1009366D01*
G01X1376865Y1023166D02*
X1373665D01*
G01X1376865Y1029366D02*
Y1023166D01*
G01X1373665D02*
Y1029366D01*
G01X1372559Y1013925D02*
Y1010725D01*
G01Y1017925D02*
Y1014725D01*
G01X1377160Y1019216D02*
X1377452Y1019376D01*
X1377618Y1019590D01*
X1377660Y1019830D01*
X1377618Y1020043D01*
X1377410Y1020256D01*
X1377160Y1020390D01*
X1376910Y1020416D01*
X1376618Y1020363D01*
X1376410Y1020176D01*
X1376327Y1019990D01*
Y1019750D01*
G01Y1019990D02*
X1376202Y1020150D01*
X1375993Y1020283D01*
X1375743Y1020336D01*
X1375493Y1020283D01*
X1375285Y1020150D01*
X1375160Y1019910D01*
X1375202Y1019670D01*
X1375368Y1019430D01*
G01X1377660Y1022003D02*
X1375160D01*
X1375660Y1021683D01*
G01X1377660D02*
Y1022323D01*
G01X1379826Y1025240D02*
Y1027146D01*
G01X1376919Y1018003D02*
X1378419D01*
G01X1373665Y1029366D02*
X1376865D01*
G01X1377682Y1029370D02*
X1377842Y1029078D01*
X1378056Y1028912D01*
X1378296Y1028870D01*
X1378509Y1028912D01*
X1378722Y1029120D01*
X1378856Y1029370D01*
X1378882Y1029620D01*
X1378829Y1029912D01*
X1378642Y1030120D01*
X1378456Y1030203D01*
X1378216D01*
G01X1378456D02*
X1378616Y1030328D01*
X1378749Y1030537D01*
X1378802Y1030787D01*
X1378749Y1031037D01*
X1378616Y1031245D01*
X1378376Y1031370D01*
X1378136Y1031328D01*
X1377896Y1031162D01*
G01X1380469Y1031370D02*
X1380256Y1031287D01*
X1380096Y1031078D01*
X1379989Y1030828D01*
X1379909Y1030495D01*
X1379882Y1030120D01*
X1379909Y1029745D01*
X1379989Y1029412D01*
X1380096Y1029162D01*
X1380256Y1028953D01*
X1380469Y1028870D01*
X1380682Y1028953D01*
X1380842Y1029162D01*
X1380949Y1029412D01*
X1381029Y1029745D01*
X1381056Y1030120D01*
X1381029Y1030495D01*
X1380949Y1030828D01*
X1380842Y1031078D01*
X1380682Y1031287D01*
X1380469Y1031370D01*
G01X1379826Y1027146D02*
X1381732D01*
G01X1382669Y1028603D02*
Y1031603D01*
G01X1381720Y1056313D02*
X1372034D01*
G01D02*
Y1078148D01*
G01X1387451Y1090068D02*
X1375451D01*
G01D02*
Y1096068D01*
G01X1372034Y1078148D02*
X1376971Y1083085D01*
G01D02*
X1381720D01*
G01X1375451Y1096068D02*
X1387451D01*
G01X1372615Y1103442D02*
X1375815D01*
G01X1372615Y1097242D02*
Y1103442D01*
G01X1375815Y1097242D02*
X1372615D01*
G01X1375815Y1103442D02*
Y1097242D01*
G01X1375987Y1114996D02*
X1379187D01*
G01X1375987Y1108796D02*
Y1114996D01*
G01X1379187Y1108796D02*
X1375987D01*
G01X1379187Y1114996D02*
Y1108796D01*
G01Y1119296D02*
X1375987D01*
G01X1379187Y1125496D02*
Y1119296D01*
G01X1375987D02*
Y1125496D01*
G01X1384520Y1118297D02*
X1381320D01*
G01D02*
Y1124497D01*
G01X1373356Y1124250D02*
Y1122552D01*
G01Y1109839D02*
X1372348D01*
G01X1373356Y1111693D02*
Y1109839D01*
G01X1375987Y1125496D02*
X1379187D01*
G01X1381320Y1124497D02*
X1384520D01*
G01X1373356Y1133461D02*
Y1130861D01*
G01X1372563Y1133461D02*
X1373356D01*
G01X1373661Y1136752D02*
X1367663D01*
G01X1373661Y1174548D02*
Y1136752D01*
G01X1375261Y1153659D02*
Y1159859D01*
G01X1378461Y1153659D02*
X1375261D01*
G01X1378461Y1159859D02*
Y1153659D01*
G01X1381424D02*
Y1159859D01*
G01X1384624Y1153659D02*
X1381424D01*
G01X1375261Y1159859D02*
X1378461D01*
G01X1381424D02*
X1384624D01*
G01X1367663Y1174548D02*
X1373661D01*
G01X1371038Y1201471D02*
Y1189471D01*
G01X1388183Y1208029D02*
Y1210455D01*
G01X1368637Y1239176D02*
Y1230276D01*
G01X1398758Y96067D02*
Y99267D01*
G01X1404958Y96067D02*
X1398758D01*
G01Y99267D02*
X1404958D01*
G01X1395497Y122172D02*
Y110172D01*
G01X1389497D02*
Y122172D01*
G01X1395497Y110172D02*
X1389497D01*
G01X1386880Y109424D02*
X1390080D01*
G01X1386880Y103224D02*
Y109424D01*
G01X1390080Y103224D02*
X1386880D01*
G01X1390080Y109424D02*
Y103224D01*
G01X1394574Y108095D02*
X1400774D01*
G01X1394574Y104895D02*
Y108095D01*
G01X1400774Y104895D02*
X1394574D01*
G01Y100895D02*
Y104095D01*
G01X1400774Y100895D02*
X1394574D01*
G01Y104095D02*
X1400774D01*
G01X1386080Y109424D02*
Y103224D01*
G01X1387096Y123508D02*
Y111734D01*
G01X1389497Y122172D02*
X1395497D01*
G01X1388105Y126223D02*
X1384905D01*
G01X1388105Y132423D02*
Y126223D01*
G01X1384905Y132423D02*
X1388105D01*
G01X1384905Y126223D02*
Y132423D01*
G01X1392159Y126228D02*
X1388959D01*
G01X1392159Y132428D02*
Y126228D01*
G01X1388959Y132428D02*
X1392159D01*
G01X1388959Y126228D02*
Y132428D01*
G01X1384105Y132423D02*
Y126223D01*
G01X1392338Y141337D02*
X1389138D01*
G01X1392338Y147537D02*
Y141337D01*
G01X1389138Y147537D02*
X1392338D01*
G01X1389138Y141337D02*
Y147537D01*
G01X1389003Y133238D02*
Y136438D01*
G01X1395203Y133238D02*
X1389003D01*
G01X1395203Y136438D02*
Y133238D01*
G01X1389003Y136438D02*
X1395203D01*
G01X1389003Y137238D02*
Y140438D01*
G01X1395203Y137238D02*
X1389003D01*
G01X1395203Y140438D02*
Y137238D01*
G01X1389003Y140438D02*
X1395203D01*
G01X1395549Y148437D02*
X1398749D01*
G01X1395549Y142237D02*
Y148437D01*
G01X1398749Y142237D02*
X1395549D01*
G01X1398749Y148437D02*
Y142237D01*
G01X1386384Y134995D02*
Y144395D01*
G01X1398100Y152907D02*
X1400322D01*
X1400787Y153060D01*
X1401097Y153367D01*
X1401200Y153750D01*
X1401097Y154133D01*
X1400787Y154440D01*
X1400322Y154593D01*
X1398100D01*
G01X1400580Y156007D02*
X1400942Y156237D01*
X1401148Y156543D01*
X1401200Y156888D01*
X1401148Y157195D01*
X1400890Y157502D01*
X1400580Y157693D01*
X1400270Y157732D01*
X1399908Y157655D01*
X1399650Y157387D01*
X1399547Y157118D01*
Y156773D01*
G01Y157118D02*
X1399392Y157348D01*
X1399133Y157540D01*
X1398823Y157617D01*
X1398513Y157540D01*
X1398255Y157348D01*
X1398100Y157003D01*
X1398152Y156658D01*
X1398358Y156313D01*
G01X1401200Y159873D02*
X1400528Y159950D01*
X1399960Y160065D01*
X1399443Y160218D01*
X1398875Y160410D01*
X1398100Y160717D01*
Y159183D01*
G01X1398617Y162322D02*
X1398307Y162552D01*
X1398152Y162820D01*
X1398100Y163127D01*
X1398203Y163510D01*
X1398462Y163778D01*
X1398772Y163855D01*
X1399082Y163817D01*
X1399340Y163663D01*
X1399857Y162897D01*
X1400218Y162552D01*
X1400735Y162322D01*
X1401200Y162245D01*
Y163855D01*
G01X1384007Y149950D02*
Y165304D01*
G01X1396685Y149950D02*
X1384007D01*
G01X1396685Y165304D02*
Y149950D01*
G01X1384204Y165304D02*
X1396685D01*
G01X1399505Y197645D02*
X1387505D01*
G01X1399505Y203645D02*
Y197645D01*
G01X1387505D02*
Y203645D01*
G01D02*
X1399505D01*
G01X1386682Y216506D02*
Y204506D01*
G01X1387482Y208306D02*
Y214506D01*
G01X1390682Y208306D02*
X1387482D01*
G01X1390682Y214506D02*
Y208306D01*
G01X1397458Y208464D02*
Y205264D01*
G01X1391258Y208464D02*
X1397458D01*
G01X1391258Y205264D02*
Y208464D01*
G01X1397458Y205264D02*
X1391258D01*
G01X1392288Y226801D02*
X1404492D01*
Y211497D01*
X1392288D01*
Y226801D01*
G01X1387482Y214506D02*
X1390682D01*
G01X1387848Y245521D02*
Y254969D01*
G01X1398684Y245521D02*
X1387848D01*
G01X1398684Y254969D02*
Y245521D01*
G01X1391424Y231334D02*
X1388224D01*
G01X1391424Y237534D02*
Y231334D01*
G01X1388224Y237534D02*
X1391424D01*
G01X1388224Y231334D02*
Y237534D01*
G01X1396951Y231446D02*
X1393751D01*
G01X1396951Y237646D02*
Y231446D01*
G01X1393751Y237646D02*
X1396951D01*
G01X1393751Y231446D02*
Y237646D01*
G01X1400826Y231434D02*
X1397626D01*
G01Y237634D02*
X1400826D01*
G01X1397626Y231434D02*
Y237634D01*
G01X1396629Y243678D02*
Y240478D01*
G01X1390429Y243678D02*
X1396629D01*
G01X1390429Y240478D02*
Y243678D01*
G01X1396629Y240478D02*
X1390429D01*
G01X1389650Y243678D02*
Y240478D01*
G01X1385680Y249971D02*
Y246771D01*
G01X1398550Y256400D02*
X1398243Y256452D01*
X1397975Y256658D01*
X1397745Y256968D01*
X1397592Y257330D01*
X1397515Y257743D01*
Y258157D01*
X1397592Y258570D01*
X1397745Y258932D01*
X1397975Y259242D01*
X1398243Y259448D01*
X1398550Y259500D01*
X1398857Y259448D01*
X1399125Y259242D01*
X1399355Y258932D01*
X1399508Y258570D01*
X1399585Y258157D01*
Y257743D01*
X1399508Y257330D01*
X1399355Y256968D01*
X1399125Y256658D01*
X1398857Y256452D01*
X1398550Y256400D01*
G01X1398857Y257227D02*
X1399317Y256400D01*
G01X1400922Y258983D02*
X1401152Y259293D01*
X1401420Y259448D01*
X1401727Y259500D01*
X1402110Y259397D01*
X1402378Y259138D01*
X1402455Y258828D01*
X1402417Y258518D01*
X1402263Y258260D01*
X1401497Y257743D01*
X1401152Y257382D01*
X1400922Y256865D01*
X1400845Y256400D01*
X1402455D01*
G01X1404750Y259500D02*
X1404443Y259397D01*
X1404213Y259138D01*
X1404060Y258828D01*
X1403945Y258415D01*
X1403907Y257950D01*
X1403945Y257485D01*
X1404060Y257072D01*
X1404213Y256762D01*
X1404443Y256503D01*
X1404750Y256400D01*
X1405057Y256503D01*
X1405287Y256762D01*
X1405440Y257072D01*
X1405555Y257485D01*
X1405593Y257950D01*
X1405555Y258415D01*
X1405440Y258828D01*
X1405287Y259138D01*
X1405057Y259397D01*
X1404750Y259500D01*
G01X1407850Y256400D02*
X1408118Y256452D01*
X1408425Y256607D01*
X1408617Y256865D01*
X1408693Y257227D01*
X1408617Y257588D01*
X1408387Y257898D01*
X1408042Y258053D01*
X1407658D01*
X1407428Y258157D01*
X1407237Y258415D01*
X1407160Y258777D01*
X1407275Y259138D01*
X1407543Y259397D01*
X1407850Y259500D01*
X1408157Y259397D01*
X1408425Y259138D01*
X1408540Y258777D01*
X1408463Y258415D01*
X1408272Y258157D01*
X1408042Y258053D01*
X1407658D01*
X1407313Y257898D01*
X1407083Y257588D01*
X1407007Y257227D01*
X1407083Y256865D01*
X1407275Y256607D01*
X1407582Y256452D01*
X1407850Y256400D01*
G01X1395266Y254969D02*
X1398684D01*
G01X1393266Y253245D02*
X1395266Y254969D01*
G01X1391266D02*
X1393266Y253245D01*
G01X1387848Y254969D02*
X1391266D01*
G01X1385680Y253971D02*
Y250771D01*
G01X1386351Y319271D02*
Y322471D01*
G01X1392551Y319271D02*
X1386351D01*
G01X1392551Y322471D02*
Y319271D01*
G01X1386351Y322471D02*
X1392551D01*
G01X1386351Y323771D02*
Y326971D01*
G01X1392551Y323771D02*
X1386351D01*
G01X1392551Y326971D02*
Y323771D01*
G01X1386351Y326971D02*
X1392551D01*
G01X1386351Y328271D02*
Y331471D01*
G01X1392551Y328271D02*
X1386351D01*
G01X1392551Y331471D02*
Y328271D01*
G01X1386351Y331471D02*
X1392551D01*
G01X1386351Y341771D02*
Y344971D01*
G01X1392551Y341771D02*
X1386351D01*
G01X1392551Y344971D02*
Y341771D01*
G01X1386351Y337271D02*
Y340471D01*
G01X1392551Y337271D02*
X1386351D01*
G01X1392551Y340471D02*
Y337271D01*
G01X1386351Y340471D02*
X1392551D01*
G01X1386351Y332771D02*
Y335971D01*
G01X1392551Y332771D02*
X1386351D01*
G01X1392551Y335971D02*
Y332771D01*
G01X1386351Y335971D02*
X1392551D01*
G01X1386351Y344971D02*
X1392551D01*
G01Y362971D02*
Y359771D01*
G01X1386351D02*
Y362971D01*
G01X1392551Y359771D02*
X1386351D01*
G01Y350771D02*
Y353971D01*
G01X1392551Y350771D02*
X1386351D01*
G01X1392551Y353971D02*
Y350771D01*
G01X1386351Y353971D02*
X1392551D01*
G01X1386351Y346271D02*
Y349471D01*
G01X1392551Y346271D02*
X1386351D01*
G01X1392551Y349471D02*
Y346271D01*
G01X1386351Y349471D02*
X1392551D01*
G01Y358471D02*
Y355271D01*
G01X1386351Y358471D02*
X1392551D01*
G01X1386351Y355271D02*
Y358471D01*
G01X1392551Y355271D02*
X1386351D01*
G01Y362971D02*
X1392551D01*
G01X1398134Y538326D02*
X1404334D01*
G01X1398134Y535126D02*
Y538326D01*
G01X1404334Y535126D02*
X1398134D01*
G01Y533326D02*
X1404334D01*
G01X1398134Y530126D02*
Y533326D01*
G01X1404334Y530126D02*
X1398134D01*
G01Y526126D02*
Y529326D01*
G01X1404334Y526126D02*
X1398134D01*
G01Y529326D02*
X1404334D01*
G01Y539126D02*
X1398134D01*
Y542326D01*
X1404334D01*
Y539126D01*
G01X1398134Y547126D02*
Y550326D01*
G01X1404334Y547126D02*
X1398134D01*
G01Y550326D02*
X1404334D01*
G01X1398134Y546326D02*
X1404334D01*
G01X1398134Y543126D02*
Y546326D01*
G01X1404334Y543126D02*
X1398134D01*
G01X1404334Y551126D02*
X1398134D01*
Y554326D01*
X1404334D01*
Y551126D01*
G01X1389841Y570600D02*
Y567400D01*
G01Y566600D02*
Y563400D01*
G01Y562600D02*
Y559400D01*
G01X1394193Y585713D02*
X1396433D01*
G01X1395220Y587338D02*
Y584088D01*
G01X1397834Y580365D02*
Y591861D01*
G01X1427393Y580365D02*
X1397834D01*
G01X1390186Y578792D02*
Y575592D01*
G01X1383986Y578792D02*
X1390186D01*
G01X1383986Y575592D02*
Y578792D01*
G01X1390186Y575592D02*
X1383986D01*
G01X1383987Y579717D02*
Y582917D01*
G01X1390187Y579717D02*
X1383987D01*
G01X1390187Y582917D02*
Y579717D01*
G01X1383987Y582917D02*
X1390187D01*
G01X1398003Y593480D02*
Y596580D01*
X1398923D01*
X1399230Y596425D01*
X1399460Y596063D01*
X1399537Y595650D01*
X1399460Y595237D01*
X1399268Y594927D01*
X1398923Y594772D01*
X1398003D01*
G01X1401027Y593480D02*
Y596580D01*
X1401793D01*
X1402100Y596425D01*
X1402330Y596218D01*
X1402522Y595908D01*
X1402675Y595547D01*
X1402713Y595030D01*
X1402675Y594513D01*
X1402522Y594152D01*
X1402330Y593842D01*
X1402100Y593635D01*
X1401793Y593480D01*
X1401027D01*
G01X1404970D02*
Y596580D01*
X1404510Y595960D01*
G01Y593480D02*
X1405430D01*
G01X1407227Y593945D02*
X1407457Y593687D01*
X1407725Y593532D01*
X1408070Y593480D01*
X1408415Y593583D01*
X1408683Y593790D01*
X1408875Y594152D01*
X1408913Y594565D01*
X1408837Y594978D01*
X1408645Y595237D01*
X1408377Y595443D01*
X1408108Y595495D01*
X1407840Y595443D01*
X1407495Y595237D01*
X1407610Y596580D01*
X1408645D01*
G01X1397834Y591861D02*
X1427393D01*
G01X1389841Y617100D02*
Y613900D01*
G01Y613100D02*
Y609900D01*
G01Y609100D02*
Y605900D01*
G01X1399852Y619711D02*
Y622911D01*
G01X1406052Y619711D02*
X1399852D01*
G01X1395852Y618411D02*
X1399052D01*
G01X1395852Y612211D02*
Y618411D01*
G01X1399052Y612211D02*
X1395852D01*
G01X1399052Y618411D02*
Y612211D01*
G01X1399852Y618411D02*
X1403052D01*
G01X1399852Y612211D02*
Y618411D01*
G01X1403052Y612211D02*
X1399852D01*
G01Y630911D02*
X1406052D01*
G01X1399852Y627711D02*
Y630911D01*
G01X1406052Y627711D02*
X1399852D01*
G01Y626911D02*
X1406052D01*
G01X1399852Y623711D02*
Y626911D01*
G01X1406052Y623711D02*
X1399852D01*
G01X1390187Y629417D02*
Y626217D01*
G01X1383987Y629417D02*
X1390187D01*
G01X1383987Y626217D02*
Y629417D01*
G01X1390187Y626217D02*
X1383987D01*
G01X1383986Y622092D02*
Y625292D01*
G01X1390186Y622092D02*
X1383986D01*
G01X1390186Y625292D02*
Y622092D01*
G01X1383986Y625292D02*
X1390186D01*
G01X1399852Y622911D02*
X1406052D01*
G01X1389900Y650400D02*
Y653600D01*
G01X1396100Y650400D02*
X1389900D01*
G01X1396100Y653600D02*
Y650400D01*
G01X1397900D02*
Y653600D01*
G01X1404100Y650400D02*
X1397900D01*
G01X1389900Y653600D02*
X1396100D01*
G01X1397900D02*
X1404100D01*
G01X1397900Y654400D02*
Y657600D01*
G01X1404100Y654400D02*
X1397900D01*
G01Y657600D02*
X1404100D01*
G01X1389900Y654400D02*
Y657600D01*
G01X1396100Y654400D02*
X1389900D01*
G01X1396100Y657600D02*
Y654400D01*
G01X1389900Y657600D02*
X1396100D01*
G01X1389900Y658400D02*
Y661600D01*
G01X1396100Y658400D02*
X1389900D01*
G01X1396100Y661600D02*
Y658400D01*
G01X1389900Y661600D02*
X1396100D01*
G01X1397900D02*
X1404100D01*
G01X1397900Y658400D02*
Y661600D01*
G01X1404100Y658400D02*
X1397900D01*
G01X1389400Y673400D02*
Y676600D01*
G01X1395600Y673400D02*
X1389400D01*
G01X1395600Y676600D02*
Y673400D01*
G01X1389400Y676600D02*
X1395600D01*
G01X1397400Y673400D02*
Y676600D01*
G01X1403600Y673400D02*
X1397400D01*
G01Y676600D02*
X1403600D01*
G01X1397900Y701400D02*
Y704600D01*
G01X1404100Y701400D02*
X1397900D01*
G01X1389900D02*
Y704600D01*
G01X1396100Y701400D02*
X1389900D01*
G01X1396100Y704600D02*
Y701400D01*
G01X1389900Y697400D02*
Y700600D01*
G01X1396100Y697400D02*
X1389900D01*
G01X1396100Y700600D02*
Y697400D01*
G01X1389900Y700600D02*
X1396100D01*
G01X1397900Y697400D02*
Y700600D01*
G01X1404100Y697400D02*
X1397900D01*
G01Y700600D02*
X1404100D01*
G01X1397900Y704600D02*
X1404100D01*
G01X1389900D02*
X1396100D01*
G01X1397900Y708600D02*
X1404100D01*
G01X1397900Y705400D02*
Y708600D01*
G01X1404100Y705400D02*
X1397900D01*
G01X1389900D02*
Y708600D01*
G01X1396100Y705400D02*
X1389900D01*
G01X1396100Y708600D02*
Y705400D01*
G01X1389900Y708600D02*
X1396100D01*
G01X1397400Y720400D02*
Y723600D01*
G01X1403600Y720400D02*
X1397400D01*
G01Y723600D02*
X1403600D01*
G01X1389400Y720400D02*
Y723600D01*
G01X1395600Y720400D02*
X1389400D01*
G01X1395600Y723600D02*
Y720400D01*
G01X1389400Y723600D02*
X1395600D01*
G01X1396137Y804579D02*
X1392937D01*
G01X1396137Y810779D02*
Y804579D01*
G01X1392937Y810779D02*
X1396137D01*
G01X1392937Y804579D02*
Y810779D01*
G01X1388937D02*
X1392137D01*
G01X1388937Y804579D02*
Y810779D01*
G01X1392137Y804579D02*
X1388937D01*
G01X1392137Y810779D02*
Y804579D01*
G01X1384735Y810804D02*
X1387935D01*
G01X1384735Y804604D02*
Y810804D01*
G01X1387935Y804604D02*
X1384735D01*
G01X1387935Y810804D02*
Y804604D01*
G01X1396917Y804617D02*
Y810817D01*
X1400117D01*
Y804617D01*
X1396917D01*
G01X1385803Y827114D02*
Y901918D01*
G01X1399400Y924600D02*
X1402600D01*
G01X1399400Y918400D02*
Y924600D01*
G01X1402600Y918400D02*
X1399400D01*
G01X1386746Y928745D02*
X1389946D01*
G01X1386746Y922545D02*
Y928745D01*
G01X1389946Y922545D02*
X1386746D01*
G01X1389946Y928745D02*
Y922545D01*
G01X1384100Y924600D02*
Y918400D01*
G01X1393282Y949473D02*
Y961423D01*
G01X1403282Y949473D02*
X1393282D01*
G01Y967523D02*
Y979473D01*
G01X1393065Y981660D02*
X1393257Y981350D01*
X1393487Y981143D01*
X1393755Y981040D01*
X1394062Y981143D01*
X1394292Y981350D01*
X1394522Y981660D01*
X1394599Y982073D01*
Y984140D01*
G01X1396089Y981505D02*
X1396319Y981247D01*
X1396587Y981092D01*
X1396932Y981040D01*
X1397277Y981143D01*
X1397545Y981350D01*
X1397737Y981712D01*
X1397775Y982125D01*
X1397699Y982538D01*
X1397507Y982797D01*
X1397239Y983003D01*
X1396970Y983055D01*
X1396702Y983003D01*
X1396357Y982797D01*
X1396472Y984140D01*
X1397507D01*
G01X1399189Y981505D02*
X1399419Y981247D01*
X1399687Y981092D01*
X1400032Y981040D01*
X1400377Y981143D01*
X1400645Y981350D01*
X1400837Y981712D01*
X1400875Y982125D01*
X1400799Y982538D01*
X1400607Y982797D01*
X1400339Y983003D01*
X1400070Y983055D01*
X1399802Y983003D01*
X1399457Y982797D01*
X1399572Y984140D01*
X1400607D01*
G01X1393282Y979473D02*
X1403282D01*
G01X1398869Y1003370D02*
Y1005870D01*
X1398549Y1005370D01*
G01Y1003370D02*
X1399189D01*
G01X1401069Y1005870D02*
X1400856Y1005787D01*
X1400696Y1005578D01*
X1400589Y1005328D01*
X1400509Y1004995D01*
X1400482Y1004620D01*
X1400509Y1004245D01*
X1400589Y1003912D01*
X1400696Y1003662D01*
X1400856Y1003453D01*
X1401069Y1003370D01*
X1401282Y1003453D01*
X1401442Y1003662D01*
X1401549Y1003912D01*
X1401629Y1004245D01*
X1401656Y1004620D01*
X1401629Y1004995D01*
X1401549Y1005328D01*
X1401442Y1005578D01*
X1401282Y1005787D01*
X1401069Y1005870D01*
G01X1399512Y1007460D02*
X1397616D01*
G01X1399512Y1009366D02*
Y1007460D01*
G01X1396769Y1002903D02*
Y1005903D01*
G01X1388969Y1004453D02*
Y1005953D01*
G01X1399512Y1027146D02*
Y1025240D01*
G01X1394859Y1033280D02*
X1401059D01*
G01X1394859Y1030080D02*
Y1033280D01*
G01X1401059Y1030080D02*
X1394859D01*
G01X1391390Y1030894D02*
X1391550Y1031144D01*
X1391737Y1031269D01*
X1391950Y1031311D01*
X1392217Y1031228D01*
X1392404Y1031019D01*
X1392457Y1030769D01*
X1392430Y1030519D01*
X1392324Y1030311D01*
X1391790Y1029894D01*
X1391550Y1029603D01*
X1391390Y1029186D01*
X1391337Y1028811D01*
X1392457D01*
G01X1394097D02*
Y1031311D01*
X1393777Y1030811D01*
G01Y1028811D02*
X1394417D01*
G01X1397606Y1027146D02*
X1399512D01*
G01X1390469Y1028653D02*
Y1030153D01*
G01X1389120Y1056313D02*
X1398806D01*
G01D02*
Y1078148D01*
G01X1387451Y1096068D02*
Y1090068D01*
G01X1398806Y1078148D02*
X1393869Y1083085D01*
G01D02*
X1389120D01*
G01X1388829Y1107230D02*
X1392029D01*
G01X1388829Y1101030D02*
Y1107230D01*
G01X1392029Y1101030D02*
X1388829D01*
G01X1392029Y1107230D02*
Y1101030D01*
G01X1387351Y1097226D02*
Y1100426D01*
G01X1393551Y1097226D02*
X1387351D01*
G01X1393551Y1100426D02*
Y1097226D01*
G01X1387351Y1100426D02*
X1393551D01*
G01X1392616Y1107230D02*
X1395816D01*
G01X1392616Y1101030D02*
Y1107230D01*
G01X1395816Y1101030D02*
X1392616D01*
G01X1395816Y1107230D02*
Y1101030D01*
G01X1384520Y1124497D02*
Y1118297D01*
G01X1387129Y1109839D02*
Y1112030D01*
G01X1387862Y1109839D02*
X1387129D01*
G01Y1133461D02*
X1387922D01*
G01X1387129Y1130861D02*
Y1133461D01*
G01X1386224Y1136752D02*
Y1174548D01*
G01X1392222Y1136752D02*
X1386224D01*
G01X1384624Y1159859D02*
Y1153659D01*
G01X1392378Y1177793D02*
X1409318Y1177790D01*
G01X1392378Y1177193D02*
X1409353Y1177189D01*
G01X1392378Y1176593D02*
X1409361Y1176599D01*
G01X1392378Y1176593D02*
Y1177793D01*
G01X1409310D02*
X1392380D01*
G01D02*
Y1213533D01*
G01X1386224Y1174548D02*
X1392222D01*
G01X1384380Y1189471D02*
Y1201471D01*
G01X1390380Y1189471D02*
X1384380D01*
G01X1390380Y1201471D02*
Y1189471D01*
G01X1384380Y1201471D02*
X1390380D01*
G01X1388352Y1215076D02*
X1406054D01*
G01X1388352Y1227583D02*
Y1215076D01*
G01X1392380Y1213533D02*
X1409310D01*
G01X1387060Y1230276D02*
Y1239176D01*
G01X1407346Y1230276D02*
X1387060D01*
G01X1388352Y1254376D02*
Y1241762D01*
G01X1387060Y1239176D02*
X1407346D01*
G01X1406054Y1254376D02*
X1388352D01*
G01X1389528Y1436969D02*
Y1677520D01*
G01X1399860Y1466015D02*
X1392360D01*
Y1468255D01*
X1392735Y1469002D01*
X1393610Y1469562D01*
X1394610Y1469749D01*
X1395610Y1469562D01*
X1396360Y1469095D01*
X1396735Y1468255D01*
Y1466015D01*
G01X1399860Y1473515D02*
X1392360D01*
Y1475849D01*
X1392735Y1476595D01*
X1393235Y1477062D01*
X1394235Y1477249D01*
X1395235Y1477062D01*
X1395860Y1476502D01*
X1396235Y1475849D01*
Y1473515D01*
G01Y1475849D02*
X1399860Y1477249D01*
G01Y1484749D02*
Y1481015D01*
X1392360D01*
Y1484749D01*
G01X1395985Y1483255D02*
Y1481015D01*
G01X1398860Y1488422D02*
X1399485Y1489169D01*
X1399860Y1490009D01*
Y1490755D01*
X1399485Y1491502D01*
X1398860Y1492062D01*
X1397985Y1492342D01*
X1397110Y1492155D01*
X1396360Y1491689D01*
X1395860Y1490849D01*
X1395610Y1489729D01*
X1395110Y1489075D01*
X1394235Y1488795D01*
X1393360Y1488982D01*
X1392735Y1489449D01*
X1392360Y1490102D01*
Y1490755D01*
X1392610Y1491409D01*
X1393235Y1491969D01*
G01X1398860Y1495922D02*
X1399485Y1496669D01*
X1399860Y1497509D01*
Y1498255D01*
X1399485Y1499002D01*
X1398860Y1499562D01*
X1397985Y1499842D01*
X1397110Y1499655D01*
X1396360Y1499189D01*
X1395860Y1498349D01*
X1395610Y1497229D01*
X1395110Y1496575D01*
X1394235Y1496295D01*
X1393360Y1496482D01*
X1392735Y1496949D01*
X1392360Y1497602D01*
Y1498255D01*
X1392610Y1498909D01*
X1393235Y1499469D01*
G01X1397360Y1504169D02*
Y1506595D01*
G01X1399860Y1511109D02*
X1392360D01*
Y1514655D01*
G01X1395985Y1513349D02*
Y1511109D01*
G01X1392360Y1519262D02*
Y1521502D01*
G01Y1520382D02*
X1399860D01*
G01Y1519262D02*
Y1521502D01*
G01X1392360Y1527882D02*
X1399860D01*
G01X1392360Y1525735D02*
Y1530029D01*
G01X1410197Y58150D02*
Y111447D01*
G01X1409901Y57756D02*
Y111447D01*
G01X1407391Y57548D02*
X1407701Y57740D01*
X1407908Y57970D01*
X1408011Y58238D01*
X1407908Y58545D01*
X1407701Y58775D01*
X1407391Y59005D01*
X1406978Y59082D01*
X1404911D01*
G01X1408011Y61875D02*
X1404911D01*
X1407133Y60457D01*
Y62373D01*
G01X1405428Y63787D02*
X1405118Y64017D01*
X1404963Y64285D01*
X1404911Y64592D01*
X1405014Y64975D01*
X1405273Y65243D01*
X1405583Y65320D01*
X1405893Y65282D01*
X1406151Y65128D01*
X1406668Y64362D01*
X1407029Y64017D01*
X1407546Y63787D01*
X1408011Y63710D01*
Y65320D01*
G01X1416282Y57756D02*
X1409901D01*
G01X1415877Y58150D02*
X1410197D01*
G01X1404958Y99267D02*
Y96067D01*
G01X1410197Y118848D02*
Y114048D01*
G01X1409901Y118848D02*
Y114048D01*
G01X1400774Y108095D02*
Y104895D01*
G01Y104095D02*
Y100895D01*
G01X1401631Y108086D02*
X1404831D01*
G01X1401631Y101886D02*
Y108086D01*
G01X1404831Y101886D02*
X1401631D01*
G01X1404831Y108086D02*
Y101886D01*
G01X1410197Y132607D02*
Y128340D01*
G01X1409901Y132607D02*
Y128340D01*
G01Y125781D02*
Y121219D01*
G01X1410197Y125781D02*
Y121219D01*
G01X1409901Y153150D02*
Y135568D01*
G01X1410197Y152756D02*
Y135568D01*
G01X1409901Y153150D02*
X1416282D01*
G01X1410197Y152756D02*
X1415877D01*
G01X1413628Y189535D02*
X1411202D01*
G01X1410088Y195583D02*
Y184087D01*
G01X1411356Y215988D02*
X1408256D01*
Y216908D01*
X1408411Y217215D01*
X1408773Y217445D01*
X1409186Y217522D01*
X1409599Y217445D01*
X1409909Y217253D01*
X1410064Y216908D01*
Y215988D01*
G01X1408256Y219012D02*
X1410478D01*
X1410943Y219165D01*
X1411253Y219472D01*
X1411356Y219855D01*
X1411253Y220238D01*
X1410943Y220545D01*
X1410478Y220698D01*
X1408256D01*
G01X1410064Y222227D02*
X1409703Y222495D01*
X1409496Y222725D01*
X1409393Y223032D01*
X1409496Y223300D01*
X1409703Y223492D01*
X1410013Y223645D01*
X1410374Y223683D01*
X1410684Y223645D01*
X1410994Y223492D01*
X1411253Y223262D01*
X1411356Y222993D01*
X1411253Y222687D01*
X1410943Y222418D01*
X1410478Y222265D01*
X1409961Y222227D01*
X1409289Y222303D01*
X1408928Y222418D01*
X1408566Y222610D01*
X1408308Y222878D01*
X1408256Y223147D01*
X1408359Y223415D01*
X1408618Y223607D01*
G01X1410736Y225212D02*
X1411098Y225442D01*
X1411304Y225748D01*
X1411356Y226093D01*
X1411304Y226400D01*
X1411046Y226707D01*
X1410736Y226898D01*
X1410426Y226937D01*
X1410064Y226860D01*
X1409806Y226592D01*
X1409703Y226323D01*
Y225978D01*
G01Y226323D02*
X1409548Y226553D01*
X1409289Y226745D01*
X1408979Y226822D01*
X1408669Y226745D01*
X1408411Y226553D01*
X1408256Y226208D01*
X1408308Y225863D01*
X1408514Y225518D01*
G01X1409061Y231459D02*
X1405861D01*
G01X1409061Y237659D02*
Y231459D01*
G01X1405861Y237659D02*
X1409061D01*
G01X1405861Y231459D02*
Y237659D01*
G01X1400826Y237634D02*
Y231434D01*
G01X1400487Y240081D02*
Y243281D01*
G01X1406687Y240081D02*
X1400487D01*
G01X1406687Y243281D02*
Y240081D01*
G01X1400487Y243281D02*
X1406687D01*
G01X1401861Y237659D02*
X1405061D01*
G01X1401861Y231459D02*
Y237659D01*
G01X1405061Y231459D02*
X1401861D01*
G01X1405061Y237659D02*
Y231459D01*
G01X1406291Y252199D02*
Y248999D01*
G01X1400091Y252199D02*
X1406291D01*
G01X1400091Y248999D02*
Y252199D01*
G01X1406291Y248999D02*
X1400091D01*
G01X1408086Y324961D02*
X1422686D01*
G01X1408086Y356063D02*
Y324961D01*
G01X1407093Y360279D02*
Y358057D01*
X1407246Y357592D01*
X1407553Y357282D01*
X1407936Y357179D01*
X1408319Y357282D01*
X1408626Y357592D01*
X1408779Y358057D01*
Y360279D01*
G01X1411036Y357179D02*
Y360279D01*
X1410576Y359659D01*
G01Y357179D02*
X1411496D01*
G01X1413408Y359762D02*
X1413638Y360072D01*
X1413906Y360227D01*
X1414213Y360279D01*
X1414596Y360176D01*
X1414864Y359917D01*
X1414941Y359607D01*
X1414903Y359297D01*
X1414749Y359039D01*
X1413983Y358522D01*
X1413638Y358161D01*
X1413408Y357644D01*
X1413331Y357179D01*
X1414941D01*
G01X1416393Y357644D02*
X1416623Y357386D01*
X1416891Y357231D01*
X1417236Y357179D01*
X1417581Y357282D01*
X1417849Y357489D01*
X1418041Y357851D01*
X1418079Y358264D01*
X1418003Y358677D01*
X1417811Y358936D01*
X1417543Y359142D01*
X1417274Y359194D01*
X1417006Y359142D01*
X1416661Y358936D01*
X1416776Y360279D01*
X1417811D01*
G01X1420437Y356063D02*
X1415386Y351012D01*
G01X1410335Y356063D02*
X1408086D01*
G01X1415386Y351012D02*
X1410335Y356063D01*
G01X1409000Y450550D02*
X1408948Y450243D01*
X1408742Y449975D01*
X1408432Y449745D01*
X1408070Y449592D01*
X1407657Y449515D01*
X1407243D01*
X1406830Y449592D01*
X1406468Y449745D01*
X1406158Y449975D01*
X1405952Y450243D01*
X1405900Y450550D01*
X1405952Y450857D01*
X1406158Y451125D01*
X1406468Y451355D01*
X1406830Y451508D01*
X1407243Y451585D01*
X1407657D01*
X1408070Y451508D01*
X1408432Y451355D01*
X1408742Y451125D01*
X1408948Y450857D01*
X1409000Y450550D01*
G01X1408173Y450857D02*
X1409000Y451317D01*
G01X1406417Y452922D02*
X1406107Y453152D01*
X1405952Y453420D01*
X1405900Y453727D01*
X1406003Y454110D01*
X1406262Y454378D01*
X1406572Y454455D01*
X1406882Y454417D01*
X1407140Y454263D01*
X1407657Y453497D01*
X1408018Y453152D01*
X1408535Y452922D01*
X1409000Y452845D01*
Y454455D01*
G01Y456750D02*
X1405900D01*
X1406520Y456290D01*
G01X1409000D02*
Y457210D01*
G01Y459850D02*
X1408948Y460118D01*
X1408793Y460425D01*
X1408535Y460617D01*
X1408173Y460693D01*
X1407812Y460617D01*
X1407502Y460387D01*
X1407347Y460042D01*
Y459658D01*
X1407243Y459428D01*
X1406985Y459237D01*
X1406623Y459160D01*
X1406262Y459275D01*
X1406003Y459543D01*
X1405900Y459850D01*
X1406003Y460157D01*
X1406262Y460425D01*
X1406623Y460540D01*
X1406985Y460463D01*
X1407243Y460272D01*
X1407347Y460042D01*
Y459658D01*
X1407502Y459313D01*
X1407812Y459083D01*
X1408173Y459007D01*
X1408535Y459083D01*
X1408793Y459275D01*
X1408948Y459582D01*
X1409000Y459850D01*
G01X1410179Y449501D02*
Y460337D01*
G01X1419627Y449501D02*
X1410179D01*
G01Y460337D02*
X1419627D01*
G01X1412503Y462819D02*
X1409303D01*
G01X1412503Y469019D02*
Y462819D01*
G01X1409303Y469019D02*
X1412503D01*
G01X1409303Y462819D02*
Y469019D01*
G01X1413303D02*
X1416503D01*
G01X1413303Y462819D02*
Y469019D01*
G01X1416503Y462819D02*
X1413303D01*
G01X1414800Y473141D02*
Y476241D01*
X1415720D01*
X1416027Y476086D01*
X1416257Y475724D01*
X1416334Y475311D01*
X1416257Y474898D01*
X1416065Y474588D01*
X1415720Y474433D01*
X1414800D01*
G01X1417824Y476241D02*
Y474019D01*
X1417977Y473554D01*
X1418284Y473244D01*
X1418667Y473141D01*
X1419050Y473244D01*
X1419357Y473554D01*
X1419510Y474019D01*
Y476241D01*
G01X1420924Y473606D02*
X1421154Y473348D01*
X1421422Y473193D01*
X1421767Y473141D01*
X1422112Y473244D01*
X1422380Y473451D01*
X1422572Y473813D01*
X1422610Y474226D01*
X1422534Y474639D01*
X1422342Y474898D01*
X1422074Y475104D01*
X1421805Y475156D01*
X1421537Y475104D01*
X1421192Y474898D01*
X1421307Y476241D01*
X1422342D01*
G01X1424867Y473141D02*
Y476241D01*
X1424407Y475621D01*
G01Y473141D02*
X1425327D01*
G01X1414165Y480582D02*
Y477382D01*
G01X1407965Y480582D02*
X1414165D01*
G01X1407965Y477382D02*
Y480582D01*
G01X1414165Y477382D02*
X1407965D01*
G01X1414165Y485582D02*
Y482382D01*
G01X1407965Y485582D02*
X1414165D01*
G01X1407965Y482382D02*
Y485582D01*
G01X1414165Y482382D02*
X1407965D01*
G01X1414165Y493582D02*
Y490382D01*
G01X1407965D02*
Y493582D01*
G01X1414165Y490382D02*
X1407965D01*
G01X1414165Y486382D02*
X1407965D01*
Y489582D01*
X1414165D01*
Y486382D01*
G01X1406618Y503265D02*
X1437710D01*
G01X1406618Y518777D02*
Y503265D01*
G01X1414165Y501582D02*
Y498382D01*
G01X1407965Y501582D02*
X1414165D01*
G01X1407965Y498382D02*
Y501582D01*
G01X1414165Y498382D02*
X1407965D01*
G01Y493582D02*
X1414165D01*
G01X1407965Y494382D02*
Y497582D01*
G01X1414165Y494382D02*
X1407965D01*
G01X1414165Y497582D02*
Y494382D01*
G01X1407965Y497582D02*
X1414165D01*
G01X1406583Y519800D02*
Y522900D01*
X1407503D01*
X1407810Y522745D01*
X1408040Y522383D01*
X1408117Y521970D01*
X1408040Y521557D01*
X1407848Y521247D01*
X1407503Y521092D01*
X1406583D01*
G01X1409607Y519800D02*
Y522900D01*
X1410373D01*
X1410680Y522745D01*
X1410910Y522538D01*
X1411102Y522228D01*
X1411255Y521867D01*
X1411293Y521350D01*
X1411255Y520833D01*
X1411102Y520472D01*
X1410910Y520162D01*
X1410680Y519955D01*
X1410373Y519800D01*
X1409607D01*
G01X1412898Y520162D02*
X1413167Y519903D01*
X1413473Y519800D01*
X1413780Y519903D01*
X1414048Y520213D01*
X1414240Y520678D01*
X1414317Y521143D01*
Y521712D01*
X1414240Y522177D01*
X1414048Y522590D01*
X1413818Y522797D01*
X1413550Y522900D01*
X1413243Y522797D01*
X1413013Y522590D01*
X1412860Y522280D01*
X1412783Y521867D01*
X1412860Y521505D01*
X1413052Y521143D01*
X1413282Y520937D01*
X1413550Y520885D01*
X1413857Y520988D01*
X1414087Y521247D01*
X1414317Y521712D01*
G01X1437710Y518777D02*
X1406618D01*
G01X1404334Y538326D02*
Y535126D01*
G01Y533326D02*
Y530126D01*
G01Y529326D02*
Y526126D01*
G01X1405595Y526810D02*
Y529910D01*
X1406515D01*
X1406822Y529755D01*
X1407052Y529393D01*
X1407129Y528980D01*
X1407052Y528567D01*
X1406860Y528257D01*
X1406515Y528102D01*
X1405595D01*
G01X1408619Y529910D02*
Y527688D01*
X1408772Y527223D01*
X1409079Y526913D01*
X1409462Y526810D01*
X1409845Y526913D01*
X1410152Y527223D01*
X1410305Y527688D01*
Y529910D01*
G01X1411834Y529393D02*
X1412064Y529703D01*
X1412332Y529858D01*
X1412639Y529910D01*
X1413022Y529807D01*
X1413290Y529548D01*
X1413367Y529238D01*
X1413329Y528928D01*
X1413175Y528670D01*
X1412409Y528153D01*
X1412064Y527792D01*
X1411834Y527275D01*
X1411757Y526810D01*
X1413367D01*
G01X1415585D02*
X1415662Y527482D01*
X1415777Y528050D01*
X1415930Y528567D01*
X1416122Y529135D01*
X1416429Y529910D01*
X1414895D01*
G01X1407837Y533338D02*
Y545542D01*
X1423141D01*
Y533338D01*
X1407837D01*
G01X1404334Y550326D02*
Y547126D01*
G01Y546326D02*
Y543126D01*
G01X1418719Y556194D02*
X1406719D01*
G01Y562194D02*
X1418719D01*
G01X1406719Y556194D02*
Y562194D01*
G01X1418719Y564194D02*
X1406719D01*
G01Y570194D02*
X1418719D01*
G01X1406719Y564194D02*
Y570194D01*
G01X1418719Y572194D02*
X1406719D01*
G01Y578194D02*
X1418719D01*
G01X1406719Y572194D02*
Y578194D01*
G01X1413552Y604111D02*
Y599511D01*
G01X1403352Y604111D02*
X1413552D01*
G01X1403352Y599511D02*
Y604111D01*
G01X1413552Y599511D02*
X1403352D01*
G01X1410259Y598993D02*
X1416459D01*
G01X1410259Y595793D02*
Y598993D01*
G01X1416459Y595793D02*
X1410259D01*
G01X1414383Y602800D02*
Y605900D01*
X1415303D01*
X1415610Y605745D01*
X1415840Y605383D01*
X1415917Y604970D01*
X1415840Y604557D01*
X1415648Y604247D01*
X1415303Y604092D01*
X1414383D01*
G01X1417407Y605900D02*
Y603678D01*
X1417560Y603213D01*
X1417867Y602903D01*
X1418250Y602800D01*
X1418633Y602903D01*
X1418940Y603213D01*
X1419093Y603678D01*
Y605900D01*
G01X1421350Y602800D02*
Y605900D01*
X1420890Y605280D01*
G01Y602800D02*
X1421810D01*
G01X1424450Y605900D02*
X1424143Y605797D01*
X1423913Y605538D01*
X1423760Y605228D01*
X1423645Y604815D01*
X1423607Y604350D01*
X1423645Y603885D01*
X1423760Y603472D01*
X1423913Y603162D01*
X1424143Y602903D01*
X1424450Y602800D01*
X1424757Y602903D01*
X1424987Y603162D01*
X1425140Y603472D01*
X1425255Y603885D01*
X1425293Y604350D01*
X1425255Y604815D01*
X1425140Y605228D01*
X1424987Y605538D01*
X1424757Y605797D01*
X1424450Y605900D01*
G01X1426707Y603265D02*
X1426937Y603007D01*
X1427205Y602852D01*
X1427550Y602800D01*
X1427895Y602903D01*
X1428163Y603110D01*
X1428355Y603472D01*
X1428393Y603885D01*
X1428317Y604298D01*
X1428125Y604557D01*
X1427857Y604763D01*
X1427588Y604815D01*
X1427320Y604763D01*
X1426975Y604557D01*
X1427090Y605900D01*
X1428125D01*
G01X1403352Y605011D02*
Y609611D01*
G01X1413552Y605011D02*
X1403352D01*
G01X1413552Y609611D02*
Y605011D01*
G01X1403352Y609611D02*
X1413552D01*
G01X1403652Y618411D02*
X1406852D01*
G01X1403652Y612211D02*
Y618411D01*
G01X1406852Y612211D02*
X1403652D01*
G01X1406852Y618411D02*
Y612211D01*
G01X1406052Y622911D02*
Y619711D01*
G01X1403052Y618411D02*
Y612211D01*
G01X1407920Y609619D02*
Y612119D01*
X1407600Y611619D01*
G01Y609619D02*
X1408240D01*
G01X1409613Y611702D02*
X1409773Y611952D01*
X1409960Y612077D01*
X1410173Y612119D01*
X1410440Y612036D01*
X1410627Y611827D01*
X1410680Y611577D01*
X1410653Y611327D01*
X1410547Y611119D01*
X1410013Y610702D01*
X1409773Y610411D01*
X1409613Y609994D01*
X1409560Y609619D01*
X1410680D01*
G01X1406981Y615625D02*
X1409481D01*
X1408981Y615945D01*
G01X1406981D02*
Y615305D01*
G01Y613425D02*
X1409481D01*
X1408981Y613745D01*
G01X1406981D02*
Y613105D01*
G01X1410413Y613209D02*
X1411578D01*
G01X1410413Y616343D02*
Y613209D01*
G01Y620279D02*
Y618343D01*
G01X1419052Y634711D02*
X1415852D01*
G01D02*
Y640911D01*
G01X1415052Y634711D02*
X1411852D01*
G01X1415052Y640911D02*
Y634711D01*
G01X1411852D02*
Y640911D01*
G01X1406052Y630911D02*
Y627711D01*
G01Y626911D02*
Y623711D01*
G01X1409552Y634711D02*
X1406352D01*
G01X1409552Y640911D02*
Y634711D01*
G01X1406352D02*
Y640911D01*
G01X1407067Y623735D02*
Y626235D01*
X1406747Y625735D01*
G01Y623735D02*
X1407387D01*
G01X1409267Y626235D02*
X1409054Y626152D01*
X1408894Y625943D01*
X1408787Y625693D01*
X1408707Y625360D01*
X1408680Y624985D01*
X1408707Y624610D01*
X1408787Y624277D01*
X1408894Y624027D01*
X1409054Y623818D01*
X1409267Y623735D01*
X1409480Y623818D01*
X1409640Y624027D01*
X1409747Y624277D01*
X1409827Y624610D01*
X1409854Y624985D01*
X1409827Y625360D01*
X1409747Y625693D01*
X1409640Y625943D01*
X1409480Y626152D01*
X1409267Y626235D01*
G01X1410705Y629352D02*
X1410519Y629561D01*
X1410305Y629644D01*
X1410092Y629561D01*
X1409905Y629311D01*
X1409772Y628936D01*
X1409719Y628561D01*
Y628102D01*
X1409772Y627727D01*
X1409905Y627394D01*
X1410065Y627227D01*
X1410252Y627144D01*
X1410465Y627227D01*
X1410625Y627394D01*
X1410732Y627644D01*
X1410785Y627977D01*
X1410732Y628269D01*
X1410599Y628561D01*
X1410439Y628727D01*
X1410252Y628769D01*
X1410039Y628686D01*
X1409879Y628477D01*
X1409719Y628102D01*
G01X1410413Y625413D02*
Y622279D01*
G01X1411578Y625413D02*
X1410413D01*
G01X1415852Y640911D02*
X1419052D01*
G01X1411852D02*
X1415052D01*
G01X1404100Y653600D02*
Y650400D01*
G01X1406352Y640911D02*
X1409552D01*
G01X1404100Y657600D02*
Y654400D01*
G01Y661600D02*
Y658400D01*
G01X1403600Y676600D02*
Y673400D01*
G01X1410900Y679400D02*
Y682600D01*
G01X1417100Y679400D02*
X1410900D01*
G01Y682600D02*
X1417100D01*
G01X1410900Y683400D02*
Y686600D01*
G01X1417100Y683400D02*
X1410900D01*
G01X1404100Y704600D02*
Y701400D01*
G01Y700600D02*
Y697400D01*
G01X1410900Y686600D02*
X1417100D01*
G01X1410900Y690600D02*
X1417100D01*
G01X1410900Y687400D02*
Y690600D01*
G01X1417100Y687400D02*
X1410900D01*
G01Y695400D02*
Y698600D01*
G01X1417100Y695400D02*
X1410900D01*
G01Y698600D02*
X1417100D01*
G01X1410900Y699400D02*
Y702600D01*
G01X1417100Y699400D02*
X1410900D01*
G01X1404100Y708600D02*
Y705400D01*
G01X1410900Y702600D02*
X1417100D01*
G01X1410900Y706600D02*
X1417100D01*
G01X1410900Y703400D02*
Y706600D01*
G01X1417100Y703400D02*
X1410900D01*
G01Y714600D02*
X1417100D01*
G01X1410900Y711400D02*
Y714600D01*
G01X1417100Y711400D02*
X1410900D01*
G01Y710600D02*
X1417100D01*
G01X1410900Y707400D02*
Y710600D01*
G01X1417100Y707400D02*
X1410900D01*
G01Y715400D02*
Y718600D01*
G01X1417100Y715400D02*
X1410900D01*
G01X1403600Y723600D02*
Y720400D01*
G01X1410900Y718600D02*
X1417100D01*
G01X1410900Y731400D02*
Y734600D01*
G01X1417100Y731400D02*
X1410900D01*
G01Y723400D02*
Y726600D01*
G01X1417100Y723400D02*
X1410900D01*
G01Y726600D02*
X1417100D01*
G01X1410900Y727400D02*
Y730600D01*
G01X1417100Y727400D02*
X1410900D01*
G01Y730600D02*
X1417100D01*
G01X1410869Y722494D02*
X1417069D01*
G01X1410869Y719294D02*
Y722494D01*
G01X1417069Y719294D02*
X1410869D01*
G01X1410900Y734600D02*
X1417100D01*
G01X1410900Y747400D02*
Y750600D01*
G01X1417100Y747400D02*
X1410900D01*
G01Y739400D02*
Y742600D01*
G01X1417100Y739400D02*
X1410900D01*
G01Y742600D02*
X1417100D01*
G01X1410900Y743400D02*
Y746600D01*
G01X1417100Y743400D02*
X1410900D01*
G01Y746600D02*
X1417100D01*
G01X1410900Y750600D02*
X1417100D01*
G01X1410900Y754600D02*
X1417100D01*
G01X1410900Y751400D02*
Y754600D01*
G01X1417100Y751400D02*
X1410900D01*
G01Y759400D02*
Y762600D01*
G01X1417100Y759400D02*
X1410900D01*
G01Y762600D02*
X1417100D01*
G01X1410900Y758600D02*
X1417100D01*
G01X1410900Y755400D02*
Y758600D01*
G01X1417100Y755400D02*
X1410900D01*
G01X1410923Y763743D02*
Y766943D01*
G01X1417123Y763743D02*
X1410923D01*
G01Y766943D02*
X1417123D01*
G01X1400917Y804617D02*
Y810817D01*
X1404117D01*
Y804617D01*
X1400917D01*
G01X1404883D02*
Y810817D01*
X1408083D01*
Y804617D01*
X1404883D01*
G01X1412698Y814083D02*
X1406498D01*
Y817283D01*
X1412698D01*
Y814083D01*
G01X1412600Y833600D02*
Y830400D01*
G01X1406400D02*
Y833600D01*
G01X1412600Y830400D02*
X1406400D01*
G01X1412600Y829600D02*
Y826400D01*
G01X1406400Y829600D02*
X1412600D01*
G01X1406400Y826400D02*
Y829600D01*
G01X1412600Y826400D02*
X1406400D01*
G01X1412549Y825534D02*
Y822334D01*
G01X1406349Y825534D02*
X1412549D01*
G01X1406349Y822334D02*
Y825534D01*
G01X1412549Y822334D02*
X1406349D01*
G01X1412502Y818217D02*
X1406302D01*
Y821417D01*
X1412502D01*
Y818217D01*
G01X1406400Y833600D02*
X1412600D01*
G01X1406400Y842400D02*
Y845600D01*
G01X1412600Y842400D02*
X1406400D01*
G01X1412600Y845600D02*
Y842400D01*
G01X1406400Y845600D02*
X1412600D01*
G01Y849600D02*
Y846400D01*
G01X1406400D02*
Y849600D01*
G01X1412600Y846400D02*
X1406400D01*
G01X1412600Y841600D02*
Y838400D01*
G01X1406400Y841600D02*
X1412600D01*
G01X1406400Y838400D02*
Y841600D01*
G01X1412600Y838400D02*
X1406400D01*
G01X1412600Y837600D02*
Y834400D01*
G01X1406400Y837600D02*
X1412600D01*
G01X1406400Y834400D02*
Y837600D01*
G01X1412600Y834400D02*
X1406400D01*
G01X1400070Y857677D02*
Y917913D01*
G01X1449145Y857677D02*
X1400070D01*
G01X1406400Y849600D02*
X1412600D01*
G01Y853600D02*
Y850400D01*
G01X1406400Y853600D02*
X1412600D01*
G01X1406400Y850400D02*
Y853600D01*
G01X1412600Y850400D02*
X1406400D01*
G01X1412600Y865600D02*
Y862400D01*
G01X1406400D02*
Y865600D01*
G01X1412600Y862400D02*
X1406400D01*
G01Y858400D02*
Y861600D01*
G01X1412600Y858400D02*
X1406400D01*
G01X1412600Y861600D02*
Y858400D01*
G01X1406400Y861600D02*
X1412600D01*
G01Y857600D02*
Y854400D01*
G01X1406400Y857600D02*
X1412600D01*
G01X1406400Y854400D02*
Y857600D01*
G01X1412600Y854400D02*
X1406400D01*
G01Y865600D02*
X1412600D01*
G01Y881600D02*
Y878400D01*
G01X1406400D02*
Y881600D01*
G01X1412600Y878400D02*
X1406400D01*
G01Y874400D02*
Y877600D01*
G01X1412600Y874400D02*
X1406400D01*
G01X1412600Y877600D02*
Y874400D01*
G01X1406400Y877600D02*
X1412600D01*
G01X1406400Y870400D02*
Y873600D01*
G01X1412600Y870400D02*
X1406400D01*
G01X1412600Y873600D02*
Y870400D01*
G01X1406400Y873600D02*
X1412600D01*
G01Y869600D02*
Y866400D01*
G01X1406400Y869600D02*
X1412600D01*
G01X1406400Y866400D02*
Y869600D01*
G01X1412600Y866400D02*
X1406400D01*
G01X1412600Y885600D02*
Y882400D01*
G01X1406400Y885600D02*
X1412600D01*
G01X1406400Y882400D02*
Y885600D01*
G01X1412600Y882400D02*
X1406400D01*
G01Y886400D02*
Y889600D01*
G01X1412600Y886400D02*
X1406400D01*
G01X1412600Y889600D02*
Y886400D01*
G01X1406400Y889600D02*
X1412600D01*
G01X1406400Y881600D02*
X1412600D01*
G01Y897600D02*
Y894400D01*
G01X1406400D02*
Y897600D01*
G01X1412600Y894400D02*
X1406400D01*
G01Y890400D02*
Y893600D01*
G01X1412600Y890400D02*
X1406400D01*
G01X1412600Y893600D02*
Y890400D01*
G01X1406400Y893600D02*
X1412600D01*
G01X1406400Y902400D02*
Y905600D01*
G01X1412600Y902400D02*
X1406400D01*
G01X1412600Y905600D02*
Y902400D01*
G01X1406400Y905600D02*
X1412600D01*
G01Y901600D02*
Y898400D01*
G01X1406400Y901600D02*
X1412600D01*
G01X1406400Y898400D02*
Y901600D01*
G01X1412600Y898400D02*
X1406400D01*
G01X1406214Y909537D02*
Y912737D01*
G01X1412414Y909537D02*
X1406214D01*
G01X1412414Y912737D02*
Y909537D01*
G01X1406214Y912737D02*
X1412414D01*
G01X1406400Y897600D02*
X1412600D01*
G01X1400070Y917913D02*
X1498220D01*
G01X1406214Y913586D02*
Y916786D01*
G01X1412414Y913586D02*
X1406214D01*
G01X1412414Y916786D02*
Y913586D01*
G01X1406214Y916786D02*
X1412414D01*
G01X1402600Y924600D02*
Y918400D01*
G01X1414495Y953630D02*
X1414857Y953860D01*
X1415063Y954166D01*
X1415115Y954511D01*
X1415063Y954818D01*
X1414805Y955125D01*
X1414495Y955316D01*
X1414185Y955355D01*
X1413823Y955278D01*
X1413565Y955010D01*
X1413462Y954741D01*
Y954396D01*
G01Y954741D02*
X1413307Y954971D01*
X1413048Y955163D01*
X1412738Y955240D01*
X1412428Y955163D01*
X1412170Y954971D01*
X1412015Y954626D01*
X1412067Y954281D01*
X1412273Y953936D01*
G01X1403282Y951423D02*
Y949473D01*
G01Y971423D02*
Y957523D01*
G01Y979473D02*
Y977523D01*
G01X1415669Y993907D02*
Y990707D01*
G01X1409469Y993907D02*
X1415669D01*
G01X1409469Y990707D02*
Y993907D01*
G01X1415669Y990707D02*
X1409469D01*
G01X1409468Y986803D02*
Y990003D01*
G01X1415668Y986803D02*
X1409468D01*
G01X1415668Y990003D02*
Y986803D01*
G01X1409468Y990003D02*
X1415668D01*
G01X1400665Y990666D02*
Y996866D01*
X1403865D01*
Y990666D01*
X1400665D01*
G01X1404665D02*
Y996866D01*
X1407865D01*
Y990666D01*
X1404665D01*
G01X1413665Y1006366D02*
X1419865D01*
G01X1413665Y1003166D02*
Y1006366D01*
G01X1419865Y1003166D02*
X1413665D01*
G01Y999166D02*
Y1002366D01*
G01X1419865Y999166D02*
X1413665D01*
G01Y1002366D02*
X1419865D01*
G01X1413665Y998366D02*
X1419865D01*
G01X1413665Y995166D02*
Y998366D01*
G01X1419865Y995166D02*
X1413665D01*
G01Y1007166D02*
Y1010366D01*
G01X1419865Y1007166D02*
X1413665D01*
G01X1403665Y1008213D02*
X1401165D01*
X1401665Y1007893D01*
G01X1403665D02*
Y1008533D01*
G01Y1010413D02*
X1401165D01*
X1401665Y1010093D01*
G01X1403665D02*
Y1010733D01*
G01X1413665Y1014666D02*
Y1017866D01*
G01X1419865Y1014666D02*
X1413665D01*
G01Y1017866D02*
X1419865D01*
G01X1413665Y1010366D02*
X1419865D01*
G01X1413665Y1010666D02*
Y1013866D01*
G01X1419865Y1010666D02*
X1413665D01*
G01Y1013866D02*
X1419865D01*
G01X1419869Y1018650D02*
X1413669D01*
Y1021850D01*
X1419869D01*
Y1018650D01*
G01X1409424Y1021184D02*
X1409174Y1021344D01*
X1409049Y1021531D01*
X1409007Y1021744D01*
X1409090Y1022011D01*
X1409299Y1022198D01*
X1409549Y1022251D01*
X1409799Y1022224D01*
X1410007Y1022118D01*
X1410424Y1021584D01*
X1410715Y1021344D01*
X1411132Y1021184D01*
X1411507Y1021131D01*
Y1022251D01*
G01X1409007Y1023891D02*
X1409090Y1023678D01*
X1409299Y1023518D01*
X1409549Y1023411D01*
X1409882Y1023331D01*
X1410257Y1023304D01*
X1410632Y1023331D01*
X1410965Y1023411D01*
X1411215Y1023518D01*
X1411424Y1023678D01*
X1411507Y1023891D01*
X1411424Y1024104D01*
X1411215Y1024264D01*
X1410965Y1024371D01*
X1410632Y1024451D01*
X1410257Y1024478D01*
X1409882Y1024451D01*
X1409549Y1024371D01*
X1409299Y1024264D01*
X1409090Y1024104D01*
X1409007Y1023891D01*
G01X1403969Y1024303D02*
X1400969D01*
G01X1401019Y1016503D02*
X1402519D01*
G01X1413665Y1032366D02*
X1419865D01*
G01X1413665Y1029166D02*
Y1032366D01*
G01X1419865Y1029166D02*
X1413665D01*
G01X1401059Y1033280D02*
Y1030080D01*
G01X1410059Y1030580D02*
X1403859D01*
Y1033780D01*
X1410059D01*
Y1030580D01*
G01X1407822Y1062632D02*
X1404414D01*
G01D02*
Y1080348D01*
G01D02*
X1407822D01*
G01X1406074Y1103442D02*
X1409274D01*
G01X1406074Y1097242D02*
Y1103442D01*
G01X1409274Y1097242D02*
X1406074D01*
G01X1409274Y1103442D02*
Y1097242D01*
G01X1403893Y1103442D02*
Y1097242D01*
X1400693D01*
Y1103442D01*
X1403893D01*
G01X1409446Y1114996D02*
X1412646D01*
G01X1409446Y1108796D02*
Y1114996D01*
G01X1412646Y1108796D02*
X1409446D01*
G01X1412646Y1114996D02*
Y1108796D01*
G01Y1119296D02*
X1409446D01*
G01X1412646Y1125496D02*
Y1119296D01*
G01X1409446D02*
Y1125496D01*
G01X1416648Y1118297D02*
X1413448D01*
G01D02*
Y1124497D01*
G01X1406815Y1124250D02*
Y1122552D01*
G01Y1109839D02*
X1405807D01*
G01X1406815Y1111693D02*
Y1109839D01*
G01X1409446Y1125496D02*
X1412646D01*
G01X1413448Y1124497D02*
X1416648D01*
G01X1406815Y1133461D02*
Y1130861D01*
G01X1406022Y1133461D02*
X1406815D01*
G01X1414052Y1136752D02*
Y1174548D01*
G01X1420050Y1136752D02*
X1414052D01*
G01X1411420D02*
X1405422D01*
G01X1411420Y1174548D02*
Y1136752D01*
G01X1412378Y1178147D02*
Y1180387D01*
G01X1410753Y1179174D02*
X1414003D01*
G01X1409311Y1176643D02*
X1409307Y1178152D01*
G01X1409310Y1213533D02*
Y1177793D01*
G01X1414052Y1174548D02*
X1420050D01*
G01X1405422D02*
X1411420D01*
G01X1411310Y1189471D02*
Y1201471D01*
G01X1417310Y1189471D02*
X1411310D01*
G01Y1201471D02*
X1417310D01*
G01X1417247Y1219424D02*
Y1209224D01*
X1412647D01*
Y1219424D01*
X1417247D01*
G01X1406054Y1215076D02*
Y1227324D01*
G01X1407346Y1239176D02*
Y1230276D01*
G01X1407354Y1266904D02*
Y1249202D01*
G01D02*
X1420380D01*
G01X1406054Y1241416D02*
Y1254376D01*
G01X1420120Y1266904D02*
X1407354D01*
G01X1401339Y1689331D02*
Y1425158D01*
G01X1418284Y1516249D02*
Y1510049D01*
X1415084D01*
Y1516249D01*
X1418284D01*
G01X1406147Y1541860D02*
Y1548060D01*
X1409347D01*
Y1541860D01*
X1406147D01*
G01X1413211Y1537957D02*
X1407011D01*
Y1541157D01*
X1413211D01*
Y1537957D01*
G01X1413186Y1548054D02*
Y1541854D01*
X1409986D01*
Y1548054D01*
X1413186D01*
G01X1412719Y1560635D02*
X1406519D01*
Y1563835D01*
X1412719D01*
Y1560635D01*
G01X1415064Y1549817D02*
X1421264D01*
Y1546617D01*
X1415064D01*
Y1549817D01*
G01X1405655Y1564538D02*
Y1570738D01*
X1408855D01*
Y1564538D01*
X1405655D01*
G01X1412694Y1570732D02*
Y1564532D01*
X1409494D01*
Y1570732D01*
X1412694D01*
G01X1414422Y1571086D02*
X1420622D01*
Y1567886D01*
X1414422D01*
Y1571086D01*
G01X1416535Y1624402D02*
Y1627502D01*
G01X1418145D02*
Y1624402D01*
G01Y1625952D02*
X1416535D01*
G01X1419597Y1624867D02*
X1419827Y1624609D01*
X1420095Y1624454D01*
X1420440Y1624402D01*
X1420785Y1624505D01*
X1421053Y1624712D01*
X1421245Y1625074D01*
X1421283Y1625487D01*
X1421207Y1625900D01*
X1421015Y1626159D01*
X1420747Y1626365D01*
X1420478Y1626417D01*
X1420210Y1626365D01*
X1419865Y1626159D01*
X1419980Y1627502D01*
X1421015D01*
G01X1422888Y1624764D02*
X1423157Y1624505D01*
X1423463Y1624402D01*
X1423770Y1624505D01*
X1424038Y1624815D01*
X1424230Y1625280D01*
X1424307Y1625745D01*
Y1626314D01*
X1424230Y1626779D01*
X1424038Y1627192D01*
X1423808Y1627399D01*
X1423540Y1627502D01*
X1423233Y1627399D01*
X1423003Y1627192D01*
X1422850Y1626882D01*
X1422773Y1626469D01*
X1422850Y1626107D01*
X1423042Y1625745D01*
X1423272Y1625539D01*
X1423540Y1625487D01*
X1423847Y1625590D01*
X1424077Y1625849D01*
X1424307Y1626314D01*
G01X1434705Y57756D02*
X1428324D01*
G01X1434409Y58150D02*
X1428729D01*
G01X1422855Y156615D02*
X1423602Y155990D01*
X1424442Y155615D01*
X1425188D01*
X1425935Y155990D01*
X1426495Y156615D01*
X1426775Y157490D01*
X1426588Y158365D01*
X1426122Y159115D01*
X1425282Y159615D01*
X1424162Y159865D01*
X1423508Y160365D01*
X1423228Y161240D01*
X1423415Y162115D01*
X1423882Y162740D01*
X1424535Y163115D01*
X1425188D01*
X1425842Y162865D01*
X1426402Y162240D01*
G01X1430355Y156615D02*
X1431102Y155990D01*
X1431942Y155615D01*
X1432688D01*
X1433435Y155990D01*
X1433995Y156615D01*
X1434275Y157490D01*
X1434088Y158365D01*
X1433622Y159115D01*
X1432782Y159615D01*
X1431662Y159865D01*
X1431008Y160365D01*
X1430728Y161240D01*
X1430915Y162115D01*
X1431382Y162740D01*
X1432035Y163115D01*
X1432688D01*
X1433342Y162865D01*
X1433902Y162240D01*
G01X1437762Y155615D02*
Y163115D01*
X1439628D01*
X1440375Y162740D01*
X1440935Y162240D01*
X1441402Y161490D01*
X1441775Y160615D01*
X1441868Y159365D01*
X1441775Y158115D01*
X1441402Y157240D01*
X1440935Y156490D01*
X1440375Y155990D01*
X1439628Y155615D01*
X1437762D01*
G01X1447315D02*
Y163115D01*
X1446195Y161615D01*
G01Y155615D02*
X1448435D01*
G01X1453042Y161865D02*
X1453602Y162615D01*
X1454255Y162990D01*
X1455002Y163115D01*
X1455935Y162865D01*
X1456588Y162240D01*
X1456775Y161490D01*
X1456682Y160740D01*
X1456308Y160115D01*
X1454442Y158865D01*
X1453602Y157990D01*
X1453042Y156740D01*
X1452855Y155615D01*
X1456775D01*
G01X1426805Y164436D02*
X1441605D01*
G01X1426805Y195440D02*
Y164436D01*
G01X1428324Y153150D02*
X1434705D01*
G01X1428729Y152756D02*
X1434409D01*
G01X1441605Y195440D02*
X1426805D01*
G01X1424000Y203983D02*
X1420900D01*
Y204903D01*
X1421055Y205210D01*
X1421417Y205440D01*
X1421830Y205517D01*
X1422243Y205440D01*
X1422553Y205248D01*
X1422708Y204903D01*
Y203983D01*
G01X1424000Y207007D02*
X1420900D01*
Y207773D01*
X1421055Y208080D01*
X1421262Y208310D01*
X1421572Y208502D01*
X1421933Y208655D01*
X1422450Y208693D01*
X1422967Y208655D01*
X1423328Y208502D01*
X1423638Y208310D01*
X1423845Y208080D01*
X1424000Y207773D01*
Y207007D01*
G01X1423380Y210107D02*
X1423742Y210337D01*
X1423948Y210643D01*
X1424000Y210988D01*
X1423948Y211295D01*
X1423690Y211602D01*
X1423380Y211793D01*
X1423070Y211832D01*
X1422708Y211755D01*
X1422450Y211487D01*
X1422347Y211218D01*
Y210873D01*
G01Y211218D02*
X1422192Y211448D01*
X1421933Y211640D01*
X1421623Y211717D01*
X1421313Y211640D01*
X1421055Y211448D01*
X1420900Y211103D01*
X1420952Y210758D01*
X1421158Y210413D01*
G01X1423638Y213398D02*
X1423897Y213667D01*
X1424000Y213973D01*
X1423897Y214280D01*
X1423587Y214548D01*
X1423122Y214740D01*
X1422657Y214817D01*
X1422088D01*
X1421623Y214740D01*
X1421210Y214548D01*
X1421003Y214318D01*
X1420900Y214050D01*
X1421003Y213743D01*
X1421210Y213513D01*
X1421520Y213360D01*
X1421933Y213283D01*
X1422295Y213360D01*
X1422657Y213552D01*
X1422863Y213782D01*
X1422915Y214050D01*
X1422812Y214357D01*
X1422553Y214587D01*
X1422088Y214817D01*
G01X1430808Y199912D02*
Y202338D01*
G01X1436856Y203452D02*
X1425360D01*
G01D02*
Y233011D01*
G01X1430708Y236652D02*
Y234412D01*
G01X1432333Y235625D02*
X1429083D01*
G01X1425360Y233011D02*
X1436856D01*
G01X1424000Y263183D02*
X1420900D01*
Y264103D01*
X1421055Y264410D01*
X1421417Y264640D01*
X1421830Y264717D01*
X1422243Y264640D01*
X1422553Y264448D01*
X1422708Y264103D01*
Y263183D01*
G01X1424000Y266207D02*
X1420900D01*
Y266973D01*
X1421055Y267280D01*
X1421262Y267510D01*
X1421572Y267702D01*
X1421933Y267855D01*
X1422450Y267893D01*
X1422967Y267855D01*
X1423328Y267702D01*
X1423638Y267510D01*
X1423845Y267280D01*
X1424000Y266973D01*
Y266207D01*
G01Y270150D02*
X1420900D01*
X1421520Y269690D01*
G01X1424000D02*
Y270610D01*
G01Y273250D02*
X1420900D01*
X1421520Y272790D01*
G01X1424000D02*
Y273710D01*
G01Y276350D02*
X1423948Y276618D01*
X1423793Y276925D01*
X1423535Y277117D01*
X1423173Y277193D01*
X1422812Y277117D01*
X1422502Y276887D01*
X1422347Y276542D01*
Y276158D01*
X1422243Y275928D01*
X1421985Y275737D01*
X1421623Y275660D01*
X1421262Y275775D01*
X1421003Y276043D01*
X1420900Y276350D01*
X1421003Y276657D01*
X1421262Y276925D01*
X1421623Y277040D01*
X1421985Y276963D01*
X1422243Y276772D01*
X1422347Y276542D01*
Y276158D01*
X1422502Y275813D01*
X1422812Y275583D01*
X1423173Y275507D01*
X1423535Y275583D01*
X1423793Y275775D01*
X1423948Y276082D01*
X1424000Y276350D01*
G01X1430577Y259204D02*
Y261630D01*
G01X1436625Y262744D02*
X1425129D01*
G01D02*
Y292303D01*
G01X1430679Y297484D02*
Y295244D01*
G01X1432304Y296457D02*
X1429054D01*
G01X1425129Y292303D02*
X1436625D01*
G01X1422686Y324961D02*
Y356063D01*
G01D02*
X1420437D01*
G01X1429419Y441594D02*
X1432619D01*
G01X1429419Y435394D02*
Y441594D01*
G01X1432619Y435394D02*
X1429419D01*
G01X1425419Y441594D02*
X1428619D01*
G01X1425419Y435394D02*
Y441594D01*
G01X1428619Y435394D02*
X1425419D01*
G01X1428619Y441594D02*
Y435394D01*
G01X1419503Y440819D02*
X1416303D01*
G01X1419503Y447019D02*
Y440819D01*
G01X1416303D02*
Y447019D01*
G01X1419627Y452919D02*
Y449501D01*
G01X1417903Y454919D02*
X1419627Y452919D01*
G01Y456919D02*
X1417903Y454919D01*
G01X1419627Y460337D02*
Y456919D01*
G01X1422596Y453438D02*
X1425796D01*
G01X1422596Y447238D02*
Y453438D01*
G01X1425796Y447238D02*
X1422596D01*
G01X1425796Y453438D02*
Y447238D01*
G01X1416303Y447019D02*
X1419503D01*
G01X1427533Y446607D02*
Y458381D01*
G01X1437295Y446607D02*
X1427533D01*
G01X1429084Y462959D02*
X1425884D01*
G01X1429084Y469159D02*
Y462959D01*
G01X1425884Y469159D02*
X1429084D01*
G01X1425884Y462959D02*
Y469159D01*
G01X1429884D02*
X1433084D01*
G01X1429884Y462959D02*
Y469159D01*
G01X1433084Y462959D02*
X1429884D01*
G01X1424503Y462819D02*
X1421303D01*
G01X1424503Y469019D02*
Y462819D01*
G01X1421303Y469019D02*
X1424503D01*
G01X1421303Y462819D02*
Y469019D01*
G01X1416503D02*
Y462819D01*
G01X1417303Y469019D02*
X1420503D01*
G01X1417303Y462819D02*
Y469019D01*
G01X1420503Y462819D02*
X1417303D01*
G01X1420503Y469019D02*
Y462819D01*
G01X1427533Y458381D02*
X1437295D01*
G01X1439963Y474988D02*
X1427963D01*
G01Y480988D02*
X1439963D01*
G01X1427963Y474988D02*
Y480988D01*
G01X1429963Y481788D02*
Y484988D01*
G01X1436163Y481788D02*
X1429963D01*
G01Y484988D02*
X1436163D01*
G01X1417668Y486594D02*
Y498798D01*
X1432972D01*
Y486594D01*
X1417668D01*
G01X1430153Y520969D02*
X1418153D01*
G01X1430153Y526969D02*
Y520969D01*
G01X1418153D02*
Y526969D01*
G01D02*
X1430153D01*
G01X1430993Y528555D02*
Y540555D01*
G01X1436993Y528555D02*
X1430993D01*
G01X1426174Y538508D02*
X1429374D01*
G01X1426174Y532308D02*
Y538508D01*
G01X1429374Y532308D02*
X1426174D01*
G01X1429374Y538508D02*
Y532308D01*
G01X1420153Y527669D02*
Y530869D01*
G01X1426353Y527669D02*
X1420153D01*
G01X1426353Y530869D02*
Y527669D01*
G01X1420153Y530869D02*
X1426353D01*
G01X1430993Y540555D02*
X1436993D01*
G01X1432169Y568248D02*
Y553448D01*
G01D02*
X1463173D01*
G01X1418719Y562194D02*
Y556194D01*
G01Y570194D02*
Y564194D01*
G01X1463173Y568248D02*
X1432169D01*
G01X1418719Y578194D02*
Y572194D01*
G01X1430933Y585813D02*
X1428507D01*
G01X1427393Y591861D02*
Y580365D01*
G01X1429344Y598125D02*
Y604325D01*
G01X1432544Y598125D02*
X1429344D01*
G01X1416459Y598993D02*
Y595793D01*
G01X1426852Y606711D02*
Y609911D01*
G01X1433052Y606711D02*
X1426852D01*
G01Y609911D02*
X1433052D01*
G01X1429344Y604325D02*
X1432544D01*
G01X1431075Y613103D02*
X1431235Y613353D01*
X1431422Y613478D01*
X1431635Y613520D01*
X1431902Y613437D01*
X1432089Y613228D01*
X1432142Y612978D01*
X1432115Y612728D01*
X1432009Y612520D01*
X1431475Y612103D01*
X1431235Y611812D01*
X1431075Y611395D01*
X1431022Y611020D01*
X1432142D01*
G01X1433782Y613520D02*
X1433569Y613437D01*
X1433409Y613228D01*
X1433302Y612978D01*
X1433222Y612645D01*
X1433195Y612270D01*
X1433222Y611895D01*
X1433302Y611562D01*
X1433409Y611312D01*
X1433569Y611103D01*
X1433782Y611020D01*
X1433995Y611103D01*
X1434155Y611312D01*
X1434262Y611562D01*
X1434342Y611895D01*
X1434369Y612270D01*
X1434342Y612645D01*
X1434262Y612978D01*
X1434155Y613228D01*
X1433995Y613437D01*
X1433782Y613520D01*
G01X1430491Y618361D02*
Y620261D01*
G01X1429326Y613209D02*
X1430491D01*
G01D02*
Y616350D01*
G01X1427052Y634711D02*
X1423852D01*
G01X1427052Y640911D02*
Y634711D01*
G01X1423852D02*
Y640911D01*
G01X1430852Y634711D02*
Y640911D01*
G01X1434052Y634711D02*
X1430852D01*
G01X1419052Y640911D02*
Y634711D01*
G01X1423052D02*
X1419852D01*
G01X1423052Y640911D02*
Y634711D01*
G01X1419852D02*
Y640911D01*
G01X1427352Y634711D02*
Y640911D01*
G01X1430552Y634711D02*
X1427352D01*
G01X1430552Y640911D02*
Y634711D01*
G01X1423114Y632812D02*
Y629612D01*
G01X1416914Y632812D02*
X1423114D01*
G01X1416914Y629612D02*
Y632812D01*
G01X1423114Y629612D02*
X1416914D01*
G01X1430491Y625413D02*
X1429318D01*
G01X1430491Y622272D02*
Y625413D01*
G01X1423852Y640911D02*
X1427052D01*
G01X1430852D02*
X1434052D01*
G01X1419852D02*
X1423052D01*
G01X1427352D02*
X1430552D01*
G01X1425100Y682600D02*
Y679400D01*
G01X1418900Y682600D02*
X1425100D01*
G01X1418900Y679400D02*
Y682600D01*
G01X1425100Y679400D02*
X1418900D01*
G01X1425100Y686600D02*
Y683400D01*
G01X1418900D02*
Y686600D01*
G01X1425100Y683400D02*
X1418900D01*
G01X1417100Y682600D02*
Y679400D01*
G01Y686600D02*
Y683400D01*
G01X1418900Y686600D02*
X1425100D01*
G01Y690600D02*
Y687400D01*
G01X1418900Y690600D02*
X1425100D01*
G01X1418900Y687400D02*
Y690600D01*
G01X1425100Y687400D02*
X1418900D01*
G01X1425100Y698600D02*
Y695400D01*
G01X1418900Y698600D02*
X1425100D01*
G01X1418900Y695400D02*
Y698600D01*
G01X1425100Y695400D02*
X1418900D01*
G01X1425100Y702600D02*
Y699400D01*
G01X1418900D02*
Y702600D01*
G01X1425100Y699400D02*
X1418900D01*
G01X1417100Y690600D02*
Y687400D01*
G01Y698600D02*
Y695400D01*
G01Y702600D02*
Y699400D01*
G01X1418900Y702600D02*
X1425100D01*
G01Y714600D02*
Y711400D01*
G01X1418900Y714600D02*
X1425100D01*
G01X1418900Y711400D02*
Y714600D01*
G01X1425100Y711400D02*
X1418900D01*
G01X1425100Y710600D02*
Y707400D01*
G01X1418900Y710600D02*
X1425100D01*
G01X1418900Y707400D02*
Y710600D01*
G01X1425100Y707400D02*
X1418900D01*
G01Y715400D02*
Y718600D01*
G01X1425100Y715400D02*
X1418900D01*
G01X1425100Y718600D02*
Y715400D01*
G01Y706600D02*
Y703400D01*
G01X1418900Y706600D02*
X1425100D01*
G01X1418900Y703400D02*
Y706600D01*
G01X1425100Y703400D02*
X1418900D01*
G01X1417100Y706600D02*
Y703400D01*
G01Y714600D02*
Y711400D01*
G01Y710600D02*
Y707400D01*
G01Y718600D02*
Y715400D01*
G01X1418900Y718600D02*
X1425100D01*
G01Y726600D02*
Y723400D01*
G01X1418900Y726600D02*
X1425100D01*
G01X1418900Y723400D02*
Y726600D01*
G01X1425100Y723400D02*
X1418900D01*
G01X1425100Y730600D02*
Y727400D01*
G01X1418900Y730600D02*
X1425100D01*
G01X1418900Y727400D02*
Y730600D01*
G01X1425100Y727400D02*
X1418900D01*
G01X1425100Y734600D02*
Y731400D01*
G01X1418900D02*
Y734600D01*
G01X1425100Y731400D02*
X1418900D01*
G01X1417100Y734600D02*
Y731400D01*
G01Y726600D02*
Y723400D01*
G01Y730600D02*
Y727400D01*
G01X1417069Y722494D02*
Y719294D01*
G01X1418900Y734600D02*
X1425100D01*
G01Y742600D02*
Y739400D01*
G01X1418900Y742600D02*
X1425100D01*
G01X1418900Y739400D02*
Y742600D01*
G01X1425100Y739400D02*
X1418900D01*
G01X1425100Y746600D02*
Y743400D01*
G01X1418900Y746600D02*
X1425100D01*
G01X1418900Y743400D02*
Y746600D01*
G01X1425100Y743400D02*
X1418900D01*
G01X1425100Y750600D02*
Y747400D01*
G01X1418900D02*
Y750600D01*
G01X1425100Y747400D02*
X1418900D01*
G01X1417100Y750600D02*
Y747400D01*
G01Y742600D02*
Y739400D01*
G01Y746600D02*
Y743400D01*
G01X1425100Y754600D02*
Y751400D01*
G01X1418900Y754600D02*
X1425100D01*
G01X1418900Y751400D02*
Y754600D01*
G01X1425100Y751400D02*
X1418900D01*
G01Y750600D02*
X1425100D01*
G01X1427900Y764900D02*
Y768100D01*
G01X1434100Y764900D02*
X1427900D01*
G01X1425100Y758600D02*
Y755400D01*
G01X1418900Y758600D02*
X1425100D01*
G01X1418900Y755400D02*
Y758600D01*
G01X1425100Y755400D02*
X1418900D01*
G01Y759400D02*
Y762600D01*
G01X1425100Y759400D02*
X1418900D01*
G01X1425100Y762600D02*
Y759400D01*
G01X1418900Y762600D02*
X1425100D01*
G01X1417100Y754600D02*
Y751400D01*
G01Y762600D02*
Y759400D01*
G01Y758600D02*
Y755400D01*
G01X1417123Y766943D02*
Y763743D01*
G01X1427900Y768100D02*
X1434100D01*
G01X1427900Y768900D02*
Y772100D01*
G01X1434100Y768900D02*
X1427900D01*
G01Y772100D02*
X1434100D01*
G01X1427900Y776100D02*
X1434100D01*
G01X1427900Y772900D02*
Y776100D01*
G01X1434100Y772900D02*
X1427900D01*
G01Y780900D02*
Y784100D01*
G01X1434100Y780900D02*
X1427900D01*
G01Y796900D02*
Y800100D01*
G01X1434100Y796900D02*
X1427900D01*
G01Y792100D02*
X1434100D01*
G01X1427900Y788900D02*
Y792100D01*
G01X1434100Y788900D02*
X1427900D01*
G01Y796100D02*
X1434100D01*
G01X1427900Y792900D02*
Y796100D01*
G01X1434100Y792900D02*
X1427900D01*
G01Y784900D02*
Y788100D01*
G01X1434100Y784900D02*
X1427900D01*
G01Y788100D02*
X1434100D01*
G01X1427900Y784100D02*
X1434100D01*
G01X1427900Y800100D02*
X1434100D01*
G01X1427900Y800900D02*
Y804100D01*
G01X1434100Y800900D02*
X1427900D01*
G01Y804100D02*
X1434100D01*
G01X1427900Y812900D02*
Y816100D01*
G01X1434100Y812900D02*
X1427900D01*
G01Y808900D02*
Y812100D01*
G01X1434100Y808900D02*
X1427900D01*
G01Y812100D02*
X1434100D01*
G01X1427900Y816100D02*
X1434100D01*
G01X1427900Y828900D02*
Y832100D01*
G01X1434100Y828900D02*
X1427900D01*
G01Y824900D02*
Y828100D01*
G01X1434100Y824900D02*
X1427900D01*
G01Y828100D02*
X1434100D01*
G01X1427900Y820100D02*
X1434100D01*
G01X1427900Y816900D02*
Y820100D01*
G01X1434100Y816900D02*
X1427900D01*
G01Y836100D02*
X1434100D01*
G01X1427900Y832900D02*
Y836100D01*
G01X1434100Y832900D02*
X1427900D01*
G01Y832100D02*
X1434100D01*
G01X1427900Y844900D02*
Y848100D01*
G01X1434100Y844900D02*
X1427900D01*
G01Y840100D02*
X1434100D01*
G01X1427900Y836900D02*
Y840100D01*
G01X1434100Y836900D02*
X1427900D01*
G01Y844100D02*
X1434100D01*
G01X1427900Y840900D02*
Y844100D01*
G01X1434100Y840900D02*
X1427900D01*
G01X1421802Y857677D02*
Y917913D01*
G01Y857677D02*
X1449145D01*
G01X1427900Y848100D02*
X1434100D01*
G01X1421045Y868345D02*
X1417945D01*
X1418565Y867885D01*
G01X1421045D02*
Y868805D01*
G01X1419753Y870717D02*
X1419392Y870985D01*
X1419185Y871215D01*
X1419082Y871522D01*
X1419185Y871790D01*
X1419392Y871982D01*
X1419702Y872135D01*
X1420063Y872173D01*
X1420373Y872135D01*
X1420683Y871982D01*
X1420942Y871752D01*
X1421045Y871483D01*
X1420942Y871177D01*
X1420632Y870908D01*
X1420167Y870755D01*
X1419650Y870717D01*
X1418978Y870793D01*
X1418617Y870908D01*
X1418255Y871100D01*
X1417997Y871368D01*
X1417945Y871637D01*
X1418048Y871905D01*
X1418307Y872097D01*
G01X1420583Y904693D02*
X1420842Y904962D01*
X1420945Y905268D01*
X1420842Y905575D01*
X1420532Y905843D01*
X1420067Y906035D01*
X1419602Y906112D01*
X1419033D01*
X1418568Y906035D01*
X1418155Y905843D01*
X1417948Y905613D01*
X1417845Y905345D01*
X1417948Y905038D01*
X1418155Y904808D01*
X1418465Y904655D01*
X1418878Y904578D01*
X1419240Y904655D01*
X1419602Y904847D01*
X1419808Y905077D01*
X1419860Y905345D01*
X1419757Y905652D01*
X1419498Y905882D01*
X1419033Y906112D01*
G01X1421802Y917913D02*
X1476488D01*
G01X1422814Y937692D02*
X1416614D01*
Y940892D01*
X1422814D01*
Y937692D01*
G01X1423433Y944990D02*
X1429633D01*
Y941790D01*
X1423433D01*
Y944990D01*
G01X1440922Y961075D02*
X1430922D01*
G01D02*
Y973025D01*
G01X1429681Y949963D02*
X1423481D01*
Y953163D01*
X1429681D01*
Y949963D01*
G01X1429621Y945995D02*
X1423421D01*
Y949195D01*
X1429621D01*
Y945995D01*
G01X1430705Y993262D02*
X1430897Y992952D01*
X1431127Y992745D01*
X1431395Y992642D01*
X1431702Y992745D01*
X1431932Y992952D01*
X1432162Y993262D01*
X1432239Y993675D01*
Y995742D01*
G01X1433729Y993107D02*
X1433959Y992849D01*
X1434227Y992694D01*
X1434572Y992642D01*
X1434917Y992745D01*
X1435185Y992952D01*
X1435377Y993314D01*
X1435415Y993727D01*
X1435339Y994140D01*
X1435147Y994399D01*
X1434879Y994605D01*
X1434610Y994657D01*
X1434342Y994605D01*
X1433997Y994399D01*
X1434112Y995742D01*
X1435147D01*
G01X1437595Y992642D02*
X1437672Y993314D01*
X1437787Y993882D01*
X1437940Y994399D01*
X1438132Y994967D01*
X1438439Y995742D01*
X1436905D01*
G01X1430922Y991075D02*
X1440922D01*
G01X1430922Y979125D02*
Y991075D01*
G01X1419865Y1006366D02*
Y1003166D01*
G01Y1002366D02*
Y999166D01*
G01X1430994Y999919D02*
Y1003119D01*
G01X1437194Y999919D02*
X1430994D01*
G01Y1003119D02*
X1437194D01*
G01X1427865Y1002366D02*
Y999166D01*
G01X1421665Y1002366D02*
X1427865D01*
G01X1421665Y999166D02*
Y1002366D01*
G01X1427865Y999166D02*
X1421665D01*
G01X1419865Y998366D02*
Y995166D01*
G01Y1010366D02*
Y1007166D01*
G01X1427865Y1003166D02*
X1421665D01*
Y1006366D01*
X1427865D01*
Y1003166D01*
G01Y995166D02*
X1421665D01*
Y998366D01*
X1427865D01*
Y995166D01*
G01X1432002Y1011940D02*
X1434224D01*
X1434689Y1012093D01*
X1434999Y1012400D01*
X1435102Y1012783D01*
X1434999Y1013166D01*
X1434689Y1013473D01*
X1434224Y1013626D01*
X1432002D01*
G01X1434482Y1015040D02*
X1434844Y1015270D01*
X1435050Y1015576D01*
X1435102Y1015921D01*
X1435050Y1016228D01*
X1434792Y1016535D01*
X1434482Y1016726D01*
X1434172Y1016765D01*
X1433810Y1016688D01*
X1433552Y1016420D01*
X1433449Y1016151D01*
Y1015806D01*
G01Y1016151D02*
X1433294Y1016381D01*
X1433035Y1016573D01*
X1432725Y1016650D01*
X1432415Y1016573D01*
X1432157Y1016381D01*
X1432002Y1016036D01*
X1432054Y1015691D01*
X1432260Y1015346D01*
G01X1435102Y1018906D02*
X1434430Y1018983D01*
X1433862Y1019098D01*
X1433345Y1019251D01*
X1432777Y1019443D01*
X1432002Y1019750D01*
Y1018216D01*
G01X1434740Y1021431D02*
X1434999Y1021700D01*
X1435102Y1022006D01*
X1434999Y1022313D01*
X1434689Y1022581D01*
X1434224Y1022773D01*
X1433759Y1022850D01*
X1433190D01*
X1432725Y1022773D01*
X1432312Y1022581D01*
X1432105Y1022351D01*
X1432002Y1022083D01*
X1432105Y1021776D01*
X1432312Y1021546D01*
X1432622Y1021393D01*
X1433035Y1021316D01*
X1433397Y1021393D01*
X1433759Y1021585D01*
X1433965Y1021815D01*
X1434017Y1022083D01*
X1433914Y1022390D01*
X1433655Y1022620D01*
X1433190Y1022850D01*
G01X1419865Y1017866D02*
Y1014666D01*
G01X1427865Y1017866D02*
Y1014666D01*
G01X1421665Y1017866D02*
X1427865D01*
G01X1421665Y1014666D02*
Y1017866D01*
G01X1427865Y1014666D02*
X1421665D01*
G01X1419865Y1013866D02*
Y1010666D01*
G01X1427865Y1018666D02*
X1421665D01*
Y1021866D01*
X1427865D01*
Y1018666D01*
G01X1419865Y1032366D02*
Y1029166D01*
G01X1427865D02*
X1421665D01*
Y1032366D01*
X1427865D01*
Y1029166D01*
G01X1421732Y1059606D02*
Y1053406D01*
G01D02*
X1418532D01*
G01D02*
Y1059606D01*
G01D02*
X1421732D01*
G01X1427497Y1065999D02*
X1424397D01*
Y1066919D01*
X1424552Y1067226D01*
X1424914Y1067456D01*
X1425327Y1067533D01*
X1425740Y1067456D01*
X1426050Y1067264D01*
X1426205Y1066919D01*
Y1065999D01*
G01X1424397Y1069099D02*
X1427497D01*
Y1070633D01*
G01Y1072966D02*
X1424397D01*
X1425017Y1072506D01*
G01X1427497D02*
Y1073426D01*
G01Y1076526D02*
X1424397D01*
X1426619Y1075108D01*
Y1077024D01*
G01X1422130Y1080348D02*
Y1062632D01*
G01D02*
X1418722D01*
G01X1417005Y1090088D02*
Y1096088D01*
G01X1429005Y1090088D02*
X1417005D01*
G01X1429005Y1096088D02*
Y1090088D01*
G01X1428863Y1088890D02*
Y1082890D01*
X1416863D01*
Y1088890D01*
X1428863D01*
G01X1418722Y1080348D02*
X1422130D01*
G01X1417005Y1096088D02*
X1429005D01*
G01X1420957Y1107230D02*
X1424157D01*
G01X1420957Y1101030D02*
Y1107230D01*
G01X1424157Y1101030D02*
X1420957D01*
G01X1424157Y1107230D02*
Y1101030D01*
G01X1419479Y1097226D02*
Y1100426D01*
G01X1425679Y1097226D02*
X1419479D01*
G01X1425679Y1100426D02*
Y1097226D01*
G01X1419479Y1100426D02*
X1425679D01*
G01X1424744Y1107230D02*
X1427944D01*
G01X1424744Y1101030D02*
Y1107230D01*
G01X1427944Y1101030D02*
X1424744D01*
G01X1427944Y1107230D02*
Y1101030D01*
G01X1416648Y1124497D02*
Y1118297D01*
G01X1419257Y1109839D02*
Y1112030D01*
G01X1419990Y1109839D02*
X1419257D01*
G01Y1133461D02*
X1420050D01*
G01X1419257Y1130861D02*
Y1133461D01*
G01X1419308Y1177793D02*
X1436248Y1177790D01*
G01X1419308Y1177193D02*
X1436283Y1177189D01*
G01X1419308Y1176593D02*
X1436291Y1176599D01*
G01X1419308Y1176593D02*
Y1177793D01*
G01X1436240D02*
X1419310D01*
G01D02*
Y1213533D01*
G01X1417310Y1201471D02*
Y1189471D01*
G01X1429011Y1215896D02*
Y1218322D01*
G01X1419310Y1213533D02*
X1436240D01*
G01X1431454Y1247418D02*
X1422554D01*
G01X1431454Y1267704D02*
Y1247418D01*
G01X1422554D02*
Y1267704D01*
G01D02*
X1431454D01*
G01X1430658Y1406215D02*
Y1412415D01*
X1433858D01*
Y1406215D01*
X1430658D01*
G01X1427853Y1412377D02*
Y1406177D01*
X1424653D01*
Y1412377D01*
X1427853D01*
G01X1428071Y1493106D02*
X1421871D01*
Y1496306D01*
X1428071D01*
Y1493106D01*
G01X1431974Y1500170D02*
Y1493970D01*
X1428774D01*
Y1500170D01*
X1431974D01*
G01X1421877Y1500145D02*
X1428077D01*
Y1496945D01*
X1421877D01*
Y1500145D01*
G01X1434270Y1506452D02*
X1424822D01*
Y1517288D01*
X1434270D01*
Y1513870D01*
X1432546Y1511870D01*
X1434270Y1509870D01*
Y1506452D01*
G01X1425389Y1530381D02*
X1425082Y1530433D01*
X1424814Y1530639D01*
X1424584Y1530949D01*
X1424431Y1531311D01*
X1424354Y1531724D01*
Y1532138D01*
X1424431Y1532551D01*
X1424584Y1532913D01*
X1424814Y1533223D01*
X1425082Y1533429D01*
X1425389Y1533481D01*
X1425696Y1533429D01*
X1425964Y1533223D01*
X1426194Y1532913D01*
X1426347Y1532551D01*
X1426424Y1532138D01*
Y1531724D01*
X1426347Y1531311D01*
X1426194Y1530949D01*
X1425964Y1530639D01*
X1425696Y1530433D01*
X1425389Y1530381D01*
G01X1425696Y1531208D02*
X1426156Y1530381D01*
G01X1427761Y1532964D02*
X1427991Y1533274D01*
X1428259Y1533429D01*
X1428566Y1533481D01*
X1428949Y1533378D01*
X1429217Y1533119D01*
X1429294Y1532809D01*
X1429256Y1532499D01*
X1429102Y1532241D01*
X1428336Y1531724D01*
X1427991Y1531363D01*
X1427761Y1530846D01*
X1427684Y1530381D01*
X1429294D01*
G01X1432049D02*
Y1533481D01*
X1430631Y1531259D01*
X1432547D01*
G01X1433846Y1530846D02*
X1434076Y1530588D01*
X1434344Y1530433D01*
X1434689Y1530381D01*
X1435034Y1530484D01*
X1435302Y1530691D01*
X1435494Y1531053D01*
X1435532Y1531466D01*
X1435456Y1531879D01*
X1435264Y1532138D01*
X1434996Y1532344D01*
X1434727Y1532396D01*
X1434459Y1532344D01*
X1434114Y1532138D01*
X1434229Y1533481D01*
X1435264D01*
G01X1431041Y1522652D02*
X1424841D01*
Y1525852D01*
X1431041D01*
Y1522652D01*
G01X1424839Y1521964D02*
X1431039D01*
Y1518764D01*
X1424839D01*
Y1521964D01*
G01X1419493Y1535661D02*
Y1545109D01*
X1430329D01*
Y1535661D01*
X1426911D01*
X1424911Y1537385D01*
X1422911Y1535661D01*
X1419493D01*
G01X1435005Y1545092D02*
Y1538892D01*
X1431805D01*
Y1545092D01*
X1435005D01*
G01X1423000Y1551853D02*
X1422693Y1551905D01*
X1422425Y1552111D01*
X1422195Y1552421D01*
X1422042Y1552783D01*
X1421965Y1553196D01*
Y1553610D01*
X1422042Y1554023D01*
X1422195Y1554385D01*
X1422425Y1554695D01*
X1422693Y1554901D01*
X1423000Y1554953D01*
X1423307Y1554901D01*
X1423575Y1554695D01*
X1423805Y1554385D01*
X1423958Y1554023D01*
X1424035Y1553610D01*
Y1553196D01*
X1423958Y1552783D01*
X1423805Y1552421D01*
X1423575Y1552111D01*
X1423307Y1551905D01*
X1423000Y1551853D01*
G01X1423307Y1552680D02*
X1423767Y1551853D01*
G01X1425372Y1554436D02*
X1425602Y1554746D01*
X1425870Y1554901D01*
X1426177Y1554953D01*
X1426560Y1554850D01*
X1426828Y1554591D01*
X1426905Y1554281D01*
X1426867Y1553971D01*
X1426713Y1553713D01*
X1425947Y1553196D01*
X1425602Y1552835D01*
X1425372Y1552318D01*
X1425295Y1551853D01*
X1426905D01*
G01X1429660D02*
Y1554953D01*
X1428242Y1552731D01*
X1430158D01*
G01X1431572Y1553145D02*
X1431840Y1553506D01*
X1432070Y1553713D01*
X1432377Y1553816D01*
X1432645Y1553713D01*
X1432837Y1553506D01*
X1432990Y1553196D01*
X1433028Y1552835D01*
X1432990Y1552525D01*
X1432837Y1552215D01*
X1432607Y1551956D01*
X1432338Y1551853D01*
X1432032Y1551956D01*
X1431763Y1552266D01*
X1431610Y1552731D01*
X1431572Y1553248D01*
X1431648Y1553920D01*
X1431763Y1554281D01*
X1431955Y1554643D01*
X1432223Y1554901D01*
X1432492Y1554953D01*
X1432760Y1554850D01*
X1432952Y1554591D01*
G01X1419120Y1556301D02*
Y1565749D01*
X1429956D01*
Y1556301D01*
X1426538D01*
X1424538Y1558025D01*
X1422538Y1556301D01*
X1419120D01*
G01X1434513Y1567770D02*
Y1561570D01*
X1431313D01*
Y1567770D01*
X1434513D01*
G01X1434409Y58150D02*
Y104590D01*
G01X1434705Y57756D02*
Y104590D01*
G01X1440237Y97026D02*
Y103226D01*
G01X1443437Y97026D02*
X1440237D01*
G01X1443437Y103226D02*
Y97026D01*
G01X1446241Y86929D02*
X1443041D01*
G01X1446241Y93129D02*
Y86929D01*
G01X1443041Y93129D02*
X1446241D01*
G01X1443041Y86929D02*
Y93129D01*
G01X1442241Y86929D02*
X1439041D01*
G01X1442241Y93129D02*
Y86929D01*
G01X1439041Y93129D02*
X1442241D01*
G01X1439041Y86929D02*
Y93129D01*
G01X1450241Y86929D02*
X1447041D01*
G01Y93129D02*
X1450241D01*
G01X1447041Y86929D02*
Y93129D01*
G01X1446320Y96673D02*
Y102873D01*
G01X1449520Y96673D02*
X1446320D01*
G01X1434705Y111507D02*
Y107060D01*
G01X1434409Y111507D02*
Y107060D01*
G01Y118680D02*
Y114087D01*
G01X1434705Y118680D02*
Y114087D01*
G01X1440237Y103226D02*
X1443437D01*
G01X1446320Y102873D02*
X1449520D01*
G01X1434409Y132859D02*
Y128325D01*
G01X1434705Y132859D02*
Y128325D01*
G01Y125844D02*
Y121329D01*
G01X1434409Y125844D02*
Y121329D01*
G01X1434705Y153150D02*
Y135560D01*
G01X1434409Y152756D02*
Y135560D01*
G01X1447905Y139647D02*
Y142847D01*
G01X1454105Y139647D02*
X1447905D01*
G01Y142847D02*
X1454105D01*
G01X1443935Y145940D02*
Y149140D01*
G01X1450135Y145940D02*
X1443935D01*
G01Y149140D02*
X1450135D01*
G01X1441605Y164436D02*
Y195440D01*
G01X1443935Y153140D02*
X1450135D01*
G01X1443935Y149940D02*
Y153140D01*
G01X1450135Y149940D02*
X1443935D01*
G01X1450571Y171473D02*
X1447371D01*
G01Y177673D02*
X1450571D01*
G01X1447371Y171473D02*
Y177673D01*
G01X1446571Y171473D02*
X1443371D01*
G01X1446571Y177673D02*
Y171473D01*
G01X1443371Y177673D02*
X1446571D01*
G01X1443371Y171473D02*
Y177673D01*
G01X1447394Y170297D02*
X1453594D01*
G01X1447394Y167097D02*
Y170297D01*
G01X1453594Y167097D02*
X1447394D01*
G01X1450798Y182730D02*
X1447598D01*
G01Y188930D02*
X1450798D01*
G01X1447598Y182730D02*
Y188930D01*
G01X1447589Y193541D02*
X1453789D01*
G01X1447589Y190341D02*
Y193541D01*
G01X1453789Y190341D02*
X1447589D01*
G01X1438918Y213035D02*
Y225035D01*
G01X1444918Y213035D02*
X1438918D01*
G01X1444918Y225035D02*
Y213035D01*
G01X1436856Y233011D02*
Y203452D01*
G01X1438918Y225035D02*
X1444918D01*
G01X1445758Y226621D02*
Y232621D01*
G01X1457758Y226621D02*
X1445758D01*
G01X1449737Y215082D02*
X1446537D01*
G01Y221282D02*
X1449737D01*
G01X1446537Y215082D02*
Y221282D01*
G01X1445758Y232621D02*
X1457758D01*
G01X1438201Y250325D02*
Y234813D01*
G01D02*
X1469293D01*
G01X1436625Y292303D02*
Y262744D01*
G01X1438380Y251936D02*
Y255036D01*
X1439300D01*
X1439607Y254881D01*
X1439837Y254519D01*
X1439914Y254106D01*
X1439837Y253693D01*
X1439645Y253383D01*
X1439300Y253228D01*
X1438380D01*
G01X1441404Y251936D02*
Y255036D01*
X1442170D01*
X1442477Y254881D01*
X1442707Y254674D01*
X1442899Y254364D01*
X1443052Y254003D01*
X1443090Y253486D01*
X1443052Y252969D01*
X1442899Y252608D01*
X1442707Y252298D01*
X1442477Y252091D01*
X1442170Y251936D01*
X1441404D01*
G01X1445807D02*
Y255036D01*
X1444389Y252814D01*
X1446305D01*
G01X1448447Y251936D02*
Y255036D01*
X1447987Y254416D01*
G01Y251936D02*
X1448907D01*
G01X1469293Y250325D02*
X1438201D01*
G01X1446426Y258010D02*
Y264210D01*
G01X1449626Y258010D02*
X1446426D01*
G01X1438496Y271655D02*
Y283655D01*
G01X1444496Y271655D02*
X1438496D01*
G01X1444496Y283655D02*
Y271655D01*
G01X1446426Y264210D02*
X1449626D01*
G01X1447385Y267653D02*
Y279427D01*
G01X1457147Y267653D02*
X1447385D01*
G01X1438496Y283655D02*
X1444496D01*
G01X1448679Y283383D02*
X1445479D01*
G01X1448679Y289583D02*
Y283383D01*
G01X1445479Y289583D02*
X1448679D01*
G01X1445479Y283383D02*
Y289583D01*
G01X1447385Y279427D02*
X1457147D01*
G01X1447807Y322461D02*
Y319261D01*
G01X1441607Y322461D02*
X1447807D01*
G01X1441607Y319261D02*
Y322461D01*
G01X1447807Y319261D02*
X1441607D01*
G01X1447807Y326961D02*
Y323761D01*
G01X1441607Y326961D02*
X1447807D01*
G01X1441607Y323761D02*
Y326961D01*
G01X1447807Y323761D02*
X1441607D01*
G01X1447807Y331461D02*
Y328261D01*
G01X1441607Y331461D02*
X1447807D01*
G01X1441607Y328261D02*
Y331461D01*
G01X1447807Y328261D02*
X1441607D01*
G01X1447807Y335961D02*
Y332761D01*
G01X1441607Y335961D02*
X1447807D01*
G01X1441607Y332761D02*
Y335961D01*
G01X1447807Y332761D02*
X1441607D01*
G01X1447807Y340461D02*
Y337261D01*
G01X1441607Y340461D02*
X1447807D01*
G01X1441607Y337261D02*
Y340461D01*
G01X1447807Y337261D02*
X1441607D01*
G01X1447807Y344961D02*
Y341761D01*
G01X1441607D02*
Y344961D01*
G01X1447807Y341761D02*
X1441607D01*
G01X1433083Y358073D02*
Y361273D01*
G01X1439283Y358073D02*
X1433083D01*
G01X1439283Y361273D02*
Y358073D01*
G01X1441607Y344961D02*
X1447807D01*
G01Y349461D02*
Y346261D01*
G01X1441607Y349461D02*
X1447807D01*
G01X1441607Y346261D02*
Y349461D01*
G01X1447807Y346261D02*
X1441607D01*
G01X1447807Y353961D02*
Y350761D01*
G01X1441607Y353961D02*
X1447807D01*
G01X1441607Y350761D02*
Y353961D01*
G01X1447807Y350761D02*
X1441607D01*
G01X1447807Y358461D02*
Y355261D01*
G01X1441607Y358461D02*
X1447807D01*
G01X1441607Y355261D02*
Y358461D01*
G01X1447807Y355261D02*
X1441607D01*
G01X1433083Y361273D02*
X1439283D01*
G01X1433419Y441594D02*
X1436619D01*
G01X1433419Y435394D02*
Y441594D01*
G01X1436619Y435394D02*
X1433419D01*
G01X1436619Y441594D02*
Y435394D01*
G01X1432619Y441594D02*
Y435394D01*
G01X1444903Y455419D02*
Y443419D01*
G01X1438903Y455419D02*
X1444903D01*
G01X1438903Y443419D02*
Y455419D01*
G01X1444903Y443419D02*
X1438903D01*
G01X1447597Y456513D02*
X1444497D01*
Y457433D01*
X1444652Y457740D01*
X1445014Y457970D01*
X1445427Y458047D01*
X1445840Y457970D01*
X1446150Y457778D01*
X1446305Y457433D01*
Y456513D01*
G01X1444497Y459537D02*
X1446719D01*
X1447184Y459690D01*
X1447494Y459997D01*
X1447597Y460380D01*
X1447494Y460763D01*
X1447184Y461070D01*
X1446719Y461223D01*
X1444497D01*
G01X1447597Y463480D02*
X1444497D01*
X1445117Y463020D01*
G01X1447597D02*
Y463940D01*
G01X1445014Y465852D02*
X1444704Y466082D01*
X1444549Y466350D01*
X1444497Y466657D01*
X1444600Y467040D01*
X1444859Y467308D01*
X1445169Y467385D01*
X1445479Y467347D01*
X1445737Y467193D01*
X1446254Y466427D01*
X1446615Y466082D01*
X1447132Y465852D01*
X1447597Y465775D01*
Y467385D01*
G01Y469680D02*
X1444497D01*
X1445117Y469220D01*
G01X1447597D02*
Y470140D01*
G01X1437295Y458381D02*
Y446607D01*
G01X1437084Y462959D02*
X1433884D01*
G01X1437084Y469159D02*
Y462959D01*
G01X1433884Y469159D02*
X1437084D01*
G01X1433884Y462959D02*
Y469159D01*
G01X1433084D02*
Y462959D01*
G01X1446824Y493811D02*
Y481811D01*
G01X1440824D02*
Y493811D01*
G01X1446824Y481811D02*
X1440824D01*
G01X1439963Y480988D02*
Y474988D01*
G01X1436005Y485564D02*
Y491764D01*
G01X1439205Y485564D02*
X1436005D01*
G01X1439205Y491764D02*
Y485564D01*
G01X1436163Y484988D02*
Y481788D01*
G01X1437710Y503265D02*
Y518777D01*
G01X1440824Y493811D02*
X1446824D01*
G01X1436005Y491764D02*
X1439205D01*
G01X1445203Y516938D02*
Y519178D01*
G01X1443578Y517965D02*
X1446828D01*
G01X1439055Y520579D02*
Y550138D01*
G01X1450551Y520579D02*
X1439055D01*
G01X1436993Y540555D02*
Y528555D01*
G01X1439055Y550138D02*
X1450551D01*
G01X1438853Y581942D02*
Y583895D01*
G01X1440806Y581942D02*
X1438853D01*
G01X1450665D02*
X1448712D01*
G01X1434068Y580432D02*
X1437268D01*
G01X1434068Y574232D02*
Y580432D01*
G01X1437268Y574232D02*
X1434068D01*
G01X1437268Y580432D02*
Y574232D01*
G01X1444879Y577441D02*
Y574241D01*
G01X1438679Y577441D02*
X1444879D01*
G01X1438679Y574241D02*
Y577441D01*
G01X1444879Y574241D02*
X1438679D01*
G01X1438853Y593754D02*
X1440806D01*
G01X1438853Y591801D02*
Y593754D01*
G01X1448712D02*
X1450665D01*
G01X1444544Y598125D02*
X1441344D01*
G01X1444544Y604325D02*
Y598125D01*
G01X1441344D02*
Y604325D01*
G01X1440544Y598125D02*
X1437344D01*
G01X1440544Y604325D02*
Y598125D01*
G01X1437344D02*
Y604325D01*
G01X1448544Y598125D02*
X1445344D01*
G01X1448544Y604325D02*
Y598125D01*
G01X1445344D02*
Y604325D01*
G01X1433344Y598125D02*
Y604325D01*
G01X1436544Y598125D02*
X1433344D01*
G01X1436544Y604325D02*
Y598125D01*
G01X1432544Y604325D02*
Y598125D01*
G01X1439196Y609615D02*
X1454708D01*
G01X1439196Y640707D02*
Y609615D01*
G01X1433052Y609911D02*
Y606711D01*
G01X1441344Y604325D02*
X1444544D01*
G01X1437344D02*
X1440544D01*
G01X1445344D02*
X1448544D01*
G01X1433344D02*
X1436544D01*
G01X1437107Y623006D02*
X1437357Y622846D01*
X1437482Y622659D01*
X1437524Y622446D01*
X1437441Y622179D01*
X1437232Y621992D01*
X1436982Y621939D01*
X1436732Y621966D01*
X1436524Y622072D01*
X1436107Y622606D01*
X1435816Y622846D01*
X1435399Y623006D01*
X1435024Y623059D01*
Y621939D01*
G01Y620299D02*
X1437524D01*
X1437024Y620619D01*
G01X1435024D02*
Y619979D01*
G01X1434191Y618899D02*
Y617299D01*
G01X1437107Y616406D02*
X1437357Y616246D01*
X1437482Y616059D01*
X1437524Y615846D01*
X1437441Y615579D01*
X1437232Y615392D01*
X1436982Y615339D01*
X1436732Y615366D01*
X1436524Y615472D01*
X1436107Y616006D01*
X1435816Y616246D01*
X1435399Y616406D01*
X1435024Y616459D01*
Y615339D01*
G01X1437107Y614206D02*
X1437357Y614046D01*
X1437482Y613859D01*
X1437524Y613646D01*
X1437441Y613379D01*
X1437232Y613192D01*
X1436982Y613139D01*
X1436732Y613166D01*
X1436524Y613272D01*
X1436107Y613806D01*
X1435816Y614046D01*
X1435399Y614206D01*
X1435024Y614259D01*
Y613139D01*
G01X1434052Y640911D02*
Y634711D01*
G01X1436848Y623567D02*
X1433648D01*
G01X1436848Y629767D02*
Y623567D01*
G01X1433648Y629767D02*
X1436848D01*
G01X1433648Y623567D02*
Y629767D01*
G01X1434352Y634711D02*
Y640911D01*
G01X1437552Y634711D02*
X1434352D01*
G01X1437552Y640911D02*
Y634711D01*
G01X1454708Y640707D02*
X1439196D01*
G01X1434352Y640911D02*
X1437552D01*
G01X1445242Y682449D02*
X1461758D01*
G01X1445242Y713551D02*
Y682449D01*
G01X1448507Y717867D02*
Y715645D01*
X1448660Y715180D01*
X1448967Y714870D01*
X1449350Y714767D01*
X1449733Y714870D01*
X1450040Y715180D01*
X1450193Y715645D01*
Y717867D01*
G01X1451607Y715387D02*
X1451837Y715025D01*
X1452143Y714819D01*
X1452488Y714767D01*
X1452795Y714819D01*
X1453102Y715077D01*
X1453293Y715387D01*
X1453332Y715697D01*
X1453255Y716059D01*
X1452987Y716317D01*
X1452718Y716420D01*
X1452373D01*
G01X1452718D02*
X1452948Y716575D01*
X1453140Y716834D01*
X1453217Y717144D01*
X1453140Y717454D01*
X1452948Y717712D01*
X1452603Y717867D01*
X1452258Y717815D01*
X1451913Y717609D01*
G01X1456010Y714767D02*
Y717867D01*
X1454592Y715645D01*
X1456508D01*
G01X1457922Y716059D02*
X1458190Y716420D01*
X1458420Y716627D01*
X1458727Y716730D01*
X1458995Y716627D01*
X1459187Y716420D01*
X1459340Y716110D01*
X1459378Y715749D01*
X1459340Y715439D01*
X1459187Y715129D01*
X1458957Y714870D01*
X1458688Y714767D01*
X1458382Y714870D01*
X1458113Y715180D01*
X1457960Y715645D01*
X1457922Y716162D01*
X1457998Y716834D01*
X1458113Y717195D01*
X1458305Y717557D01*
X1458573Y717815D01*
X1458842Y717867D01*
X1459110Y717764D01*
X1459302Y717505D01*
G01X1447949Y713551D02*
X1445242D01*
G01X1453500Y708000D02*
X1447949Y713551D01*
G01X1445242Y726449D02*
X1461758D01*
G01X1445242Y757551D02*
Y726449D01*
G01X1442100Y768100D02*
Y764900D01*
G01X1435900D02*
Y768100D01*
G01X1442100Y764900D02*
X1435900D01*
G01X1434100Y768100D02*
Y764900D01*
G01X1448507Y761867D02*
Y759645D01*
X1448660Y759180D01*
X1448967Y758870D01*
X1449350Y758767D01*
X1449733Y758870D01*
X1450040Y759180D01*
X1450193Y759645D01*
Y761867D01*
G01X1451607Y759387D02*
X1451837Y759025D01*
X1452143Y758819D01*
X1452488Y758767D01*
X1452795Y758819D01*
X1453102Y759077D01*
X1453293Y759387D01*
X1453332Y759697D01*
X1453255Y760059D01*
X1452987Y760317D01*
X1452718Y760420D01*
X1452373D01*
G01X1452718D02*
X1452948Y760575D01*
X1453140Y760834D01*
X1453217Y761144D01*
X1453140Y761454D01*
X1452948Y761712D01*
X1452603Y761867D01*
X1452258Y761815D01*
X1451913Y761609D01*
G01X1456010Y758767D02*
Y761867D01*
X1454592Y759645D01*
X1456508D01*
G01X1459110Y758767D02*
Y761867D01*
X1457692Y759645D01*
X1459608D01*
G01X1447949Y757551D02*
X1445242D01*
G01X1453500Y752000D02*
X1447949Y757551D01*
G01X1435900Y768100D02*
X1442100D01*
G01Y776100D02*
Y772900D01*
G01X1435900Y776100D02*
X1442100D01*
G01X1435900Y772900D02*
Y776100D01*
G01X1442100Y772900D02*
X1435900D01*
G01X1442100Y772100D02*
Y768900D01*
G01X1435900Y772100D02*
X1442100D01*
G01X1435900Y768900D02*
Y772100D01*
G01X1442100Y768900D02*
X1435900D01*
G01X1434100Y772100D02*
Y768900D01*
G01Y776100D02*
Y772900D01*
G01Y784100D02*
Y780900D01*
G01X1442100Y784100D02*
Y780900D01*
G01X1435900D02*
Y784100D01*
G01X1442100Y780900D02*
X1435900D01*
G01X1442100Y800100D02*
Y796900D01*
G01X1435900D02*
Y800100D01*
G01X1442100Y796900D02*
X1435900D01*
G01X1442100Y796100D02*
Y792900D01*
G01X1435900Y796100D02*
X1442100D01*
G01X1435900Y792900D02*
Y796100D01*
G01X1442100Y792900D02*
X1435900D01*
G01X1442100Y792100D02*
Y788900D01*
G01X1435900Y792100D02*
X1442100D01*
G01X1435900Y788900D02*
Y792100D01*
G01X1442100Y788900D02*
X1435900D01*
G01X1434100Y800100D02*
Y796900D01*
G01Y792100D02*
Y788900D01*
G01Y796100D02*
Y792900D01*
G01Y788100D02*
Y784900D01*
G01X1442100Y788100D02*
Y784900D01*
G01X1435900Y788100D02*
X1442100D01*
G01X1435900Y784900D02*
Y788100D01*
G01X1442100Y784900D02*
X1435900D01*
G01Y784100D02*
X1442100D01*
G01X1435900Y800100D02*
X1442100D01*
G01Y816100D02*
Y812900D01*
G01X1435900D02*
Y816100D01*
G01X1442100Y812900D02*
X1435900D01*
G01X1442100Y812100D02*
Y808900D01*
G01X1435900Y812100D02*
X1442100D01*
G01X1435900Y808900D02*
Y812100D01*
G01X1442100Y808900D02*
X1435900D01*
G01Y800900D02*
Y804100D01*
G01X1442100Y800900D02*
X1435900D01*
G01X1442100Y804100D02*
Y800900D01*
G01X1435900Y804100D02*
X1442100D01*
G01X1434100D02*
Y800900D01*
G01Y816100D02*
Y812900D01*
G01Y812100D02*
Y808900D01*
G01X1435900Y816100D02*
X1442100D01*
G01Y832100D02*
Y828900D01*
G01X1435900D02*
Y832100D01*
G01X1442100Y828900D02*
X1435900D01*
G01X1442100Y828100D02*
Y824900D01*
G01X1435900Y828100D02*
X1442100D01*
G01X1435900Y824900D02*
Y828100D01*
G01X1442100Y824900D02*
X1435900D01*
G01X1442100Y820100D02*
Y816900D01*
G01X1435900Y820100D02*
X1442100D01*
G01X1435900Y816900D02*
Y820100D01*
G01X1442100Y816900D02*
X1435900D01*
G01X1434100Y832100D02*
Y828900D01*
G01Y828100D02*
Y824900D01*
G01Y820100D02*
Y816900D01*
G01Y836100D02*
Y832900D01*
G01X1435900Y832100D02*
X1442100D01*
G01Y836100D02*
Y832900D01*
G01X1435900Y836100D02*
X1442100D01*
G01X1435900Y832900D02*
Y836100D01*
G01X1442100Y832900D02*
X1435900D01*
G01Y844900D02*
Y848100D01*
G01X1442100Y844900D02*
X1435900D01*
G01X1442100Y848100D02*
Y844900D01*
G01Y840100D02*
Y836900D01*
G01X1435900Y840100D02*
X1442100D01*
G01X1435900Y836900D02*
Y840100D01*
G01X1442100Y836900D02*
X1435900D01*
G01X1442100Y844100D02*
Y840900D01*
G01X1435900Y844100D02*
X1442100D01*
G01X1435900Y840900D02*
Y844100D01*
G01X1442100Y840900D02*
X1435900D01*
G01X1434100Y848100D02*
Y844900D01*
G01Y840100D02*
Y836900D01*
G01Y844100D02*
Y840900D01*
G01X1442983Y852420D02*
X1443175Y852110D01*
X1443405Y851903D01*
X1443673Y851800D01*
X1443980Y851903D01*
X1444210Y852110D01*
X1444440Y852420D01*
X1444517Y852833D01*
Y854900D01*
G01X1446083Y851800D02*
Y854900D01*
X1447003D01*
X1447310Y854745D01*
X1447540Y854383D01*
X1447617Y853970D01*
X1447540Y853557D01*
X1447348Y853247D01*
X1447003Y853092D01*
X1446083D01*
G01X1450717Y851800D02*
X1449183D01*
Y854900D01*
X1450717D01*
G01X1450103Y853402D02*
X1449183D01*
G01X1452245Y851800D02*
X1453855Y854900D01*
G01X1452245D02*
X1453855Y851800D01*
G01X1455307Y852420D02*
X1455537Y852058D01*
X1455843Y851852D01*
X1456188Y851800D01*
X1456495Y851852D01*
X1456802Y852110D01*
X1456993Y852420D01*
X1457032Y852730D01*
X1456955Y853092D01*
X1456687Y853350D01*
X1456418Y853453D01*
X1456073D01*
G01X1456418D02*
X1456648Y853608D01*
X1456840Y853867D01*
X1456917Y854177D01*
X1456840Y854487D01*
X1456648Y854745D01*
X1456303Y854900D01*
X1455958Y854848D01*
X1455613Y854642D01*
G01X1435900Y848100D02*
X1442100D01*
G01X1441180Y867145D02*
X1448830Y874795D01*
G01X1433889Y867145D02*
X1441180D01*
G01X1433889Y908445D02*
Y867145D01*
G01X1448830Y874795D02*
X1456480Y867145D01*
G01X1463771Y908445D02*
X1433889D01*
G01X1444019Y923673D02*
Y921451D01*
X1444172Y920986D01*
X1444479Y920676D01*
X1444862Y920573D01*
X1445245Y920676D01*
X1445552Y920986D01*
X1445705Y921451D01*
Y923673D01*
G01X1447119Y921193D02*
X1447349Y920831D01*
X1447655Y920625D01*
X1448000Y920573D01*
X1448307Y920625D01*
X1448614Y920883D01*
X1448805Y921193D01*
X1448844Y921503D01*
X1448767Y921865D01*
X1448499Y922123D01*
X1448230Y922226D01*
X1447885D01*
G01X1448230D02*
X1448460Y922381D01*
X1448652Y922640D01*
X1448729Y922950D01*
X1448652Y923260D01*
X1448460Y923518D01*
X1448115Y923673D01*
X1447770Y923621D01*
X1447425Y923415D01*
G01X1450334Y923156D02*
X1450564Y923466D01*
X1450832Y923621D01*
X1451139Y923673D01*
X1451522Y923570D01*
X1451790Y923311D01*
X1451867Y923001D01*
X1451829Y922691D01*
X1451675Y922433D01*
X1450909Y921916D01*
X1450564Y921555D01*
X1450334Y921038D01*
X1450257Y920573D01*
X1451867D01*
G01X1454162D02*
Y923673D01*
X1453702Y923053D01*
G01Y920573D02*
X1454622D01*
G01X1447517Y948331D02*
X1450617D01*
Y935929D01*
X1442417D01*
Y948331D01*
X1445517D01*
G01X1440922Y963025D02*
Y961075D01*
G01X1442524Y952397D02*
Y950175D01*
X1442677Y949710D01*
X1442984Y949400D01*
X1443367Y949297D01*
X1443750Y949400D01*
X1444057Y949710D01*
X1444210Y950175D01*
Y952397D01*
G01X1446927Y949297D02*
Y952397D01*
X1445509Y950175D01*
X1447425D01*
G01X1448839Y951880D02*
X1449069Y952190D01*
X1449337Y952345D01*
X1449644Y952397D01*
X1450027Y952294D01*
X1450295Y952035D01*
X1450372Y951725D01*
X1450334Y951415D01*
X1450180Y951157D01*
X1449414Y950640D01*
X1449069Y950279D01*
X1448839Y949762D01*
X1448762Y949297D01*
X1450372D01*
G01X1452015Y949659D02*
X1452284Y949400D01*
X1452590Y949297D01*
X1452897Y949400D01*
X1453165Y949710D01*
X1453357Y950175D01*
X1453434Y950640D01*
Y951209D01*
X1453357Y951674D01*
X1453165Y952087D01*
X1452935Y952294D01*
X1452667Y952397D01*
X1452360Y952294D01*
X1452130Y952087D01*
X1451977Y951777D01*
X1451900Y951364D01*
X1451977Y951002D01*
X1452169Y950640D01*
X1452399Y950434D01*
X1452667Y950382D01*
X1452974Y950485D01*
X1453204Y950744D01*
X1453434Y951209D01*
G01X1447417Y948331D02*
X1446517Y947138D01*
X1445517Y948331D01*
G01X1434356Y950302D02*
Y953502D01*
G01X1440556Y950302D02*
X1434356D01*
G01X1440556Y953502D02*
Y950302D01*
G01X1434356Y953502D02*
X1440556D01*
G01X1440922Y983025D02*
Y969125D01*
G01Y991075D02*
Y989125D01*
G01X1438512Y999918D02*
Y1003118D01*
G01X1444712Y999918D02*
X1438512D01*
G01X1444712Y1003118D02*
Y999918D01*
G01X1438512Y1003118D02*
X1444712D01*
G01X1437194Y1003119D02*
Y999919D01*
G01X1436637Y1017233D02*
X1438408Y1018733D01*
G01X1436637Y1012102D02*
Y1017233D01*
G01X1445101Y1012102D02*
X1436637D01*
G01X1445101Y1025364D02*
Y1012102D01*
G01X1436637Y1025364D02*
X1445101D01*
G01X1436637Y1020233D02*
Y1025364D01*
G01X1438408Y1018733D02*
X1436637Y1020233D01*
G01X1439580Y1026847D02*
X1436380D01*
G01X1439580Y1033047D02*
Y1026847D01*
G01X1436380Y1033047D02*
X1439580D01*
G01X1436380Y1026847D02*
Y1033047D01*
G01X1441859Y1039011D02*
X1445059D01*
G01X1441859Y1032811D02*
Y1039011D01*
G01X1445059Y1032811D02*
X1441859D01*
G01X1445059Y1039011D02*
Y1032811D01*
G01X1437754Y1102117D02*
Y1105317D01*
G01X1443954Y1102117D02*
X1437754D01*
G01X1443954Y1105317D02*
Y1102117D01*
G01X1437754Y1105317D02*
X1443954D01*
G01X1436021Y1103442D02*
Y1097242D01*
X1432821D01*
Y1103442D01*
X1436021D01*
G01X1448025Y1103513D02*
Y1106613D01*
G01X1449635D02*
Y1103513D01*
G01Y1105063D02*
X1448025D01*
G01X1451930Y1103513D02*
Y1106613D01*
X1451470Y1105993D01*
G01Y1103513D02*
X1452390D01*
G01X1454187Y1104133D02*
X1454417Y1103771D01*
X1454723Y1103565D01*
X1455068Y1103513D01*
X1455375Y1103565D01*
X1455682Y1103823D01*
X1455873Y1104133D01*
X1455912Y1104443D01*
X1455835Y1104805D01*
X1455567Y1105063D01*
X1455298Y1105166D01*
X1454953D01*
G01X1455298D02*
X1455528Y1105321D01*
X1455720Y1105580D01*
X1455797Y1105890D01*
X1455720Y1106200D01*
X1455528Y1106458D01*
X1455183Y1106613D01*
X1454838Y1106561D01*
X1454493Y1106355D01*
G01X1457478Y1103875D02*
X1457747Y1103616D01*
X1458053Y1103513D01*
X1458360Y1103616D01*
X1458628Y1103926D01*
X1458820Y1104391D01*
X1458897Y1104856D01*
Y1105425D01*
X1458820Y1105890D01*
X1458628Y1106303D01*
X1458398Y1106510D01*
X1458130Y1106613D01*
X1457823Y1106510D01*
X1457593Y1106303D01*
X1457440Y1105993D01*
X1457363Y1105580D01*
X1457440Y1105218D01*
X1457632Y1104856D01*
X1457862Y1104650D01*
X1458130Y1104598D01*
X1458437Y1104701D01*
X1458667Y1104960D01*
X1458897Y1105425D01*
G01X1441574Y1114996D02*
X1444774D01*
G01X1441574Y1108796D02*
Y1114996D01*
G01X1444774Y1108796D02*
X1441574D01*
G01X1444774Y1114996D02*
Y1108796D01*
G01Y1119296D02*
X1441574D01*
G01X1444774Y1125496D02*
Y1119296D01*
G01X1441574D02*
Y1125496D01*
G01X1438943Y1124250D02*
Y1122552D01*
G01Y1109839D02*
X1437935D01*
G01X1438943Y1111693D02*
Y1109839D01*
G01X1450033Y1111619D02*
X1446933D01*
Y1112539D01*
X1447088Y1112846D01*
X1447450Y1113076D01*
X1447863Y1113153D01*
X1448276Y1113076D01*
X1448586Y1112884D01*
X1448741Y1112539D01*
Y1111619D01*
G01X1446933Y1114643D02*
X1449155D01*
X1449620Y1114796D01*
X1449930Y1115103D01*
X1450033Y1115486D01*
X1449930Y1115869D01*
X1449620Y1116176D01*
X1449155Y1116329D01*
X1446933D01*
G01X1450033Y1118586D02*
X1446933D01*
X1447553Y1118126D01*
G01X1450033D02*
Y1119046D01*
G01X1447450Y1120958D02*
X1447140Y1121188D01*
X1446985Y1121456D01*
X1446933Y1121763D01*
X1447036Y1122146D01*
X1447295Y1122414D01*
X1447605Y1122491D01*
X1447915Y1122453D01*
X1448173Y1122299D01*
X1448690Y1121533D01*
X1449051Y1121188D01*
X1449568Y1120958D01*
X1450033Y1120881D01*
Y1122491D01*
G01X1441574Y1125496D02*
X1444774D01*
G01X1438943Y1133461D02*
Y1130861D01*
G01X1438150Y1133461D02*
X1438943D01*
G01X1439248Y1136752D02*
X1433250D01*
G01X1439248Y1174548D02*
Y1136752D01*
G01X1447375Y1136662D02*
X1444275D01*
Y1137582D01*
X1444430Y1137889D01*
X1444792Y1138119D01*
X1445205Y1138196D01*
X1445618Y1138119D01*
X1445928Y1137927D01*
X1446083Y1137582D01*
Y1136662D01*
G01X1444275Y1139762D02*
X1447375D01*
Y1141296D01*
G01Y1143629D02*
X1444275D01*
X1444895Y1143169D01*
G01X1447375D02*
Y1144089D01*
G01X1444792Y1146001D02*
X1444482Y1146231D01*
X1444327Y1146499D01*
X1444275Y1146806D01*
X1444378Y1147189D01*
X1444637Y1147457D01*
X1444947Y1147534D01*
X1445257Y1147496D01*
X1445515Y1147342D01*
X1446032Y1146576D01*
X1446393Y1146231D01*
X1446910Y1146001D01*
X1447375Y1145924D01*
Y1147534D01*
G01X1440848Y1153659D02*
Y1159859D01*
G01X1444048Y1153659D02*
X1440848D01*
G01X1444048Y1159859D02*
Y1153659D01*
G01X1440848Y1159859D02*
X1444048D01*
G01X1439239Y1178296D02*
Y1180536D01*
G01X1437614Y1179323D02*
X1440864D01*
G01X1436241Y1176643D02*
X1436237Y1178152D01*
G01X1436240Y1213533D02*
Y1177793D01*
G01X1433250Y1174548D02*
X1439248D01*
G01X1438240Y1189471D02*
Y1201471D01*
G01X1444240Y1189471D02*
X1438240D01*
G01X1444240Y1201471D02*
Y1189471D01*
G01X1438240Y1201471D02*
X1444240D01*
G01X1442960Y1219262D02*
Y1209062D01*
X1438360D01*
Y1219262D01*
X1442960D01*
G01X1446654Y1249202D02*
Y1266904D01*
G01X1434040Y1249202D02*
X1446654D01*
G01Y1266904D02*
X1433867D01*
G01X1434658Y1406215D02*
Y1412415D01*
X1437858D01*
Y1406215D01*
X1434658D01*
G01X1438538Y1511353D02*
X1438231Y1511405D01*
X1437963Y1511611D01*
X1437733Y1511921D01*
X1437580Y1512283D01*
X1437503Y1512696D01*
Y1513110D01*
X1437580Y1513523D01*
X1437733Y1513885D01*
X1437963Y1514195D01*
X1438231Y1514401D01*
X1438538Y1514453D01*
X1438845Y1514401D01*
X1439113Y1514195D01*
X1439343Y1513885D01*
X1439496Y1513523D01*
X1439573Y1513110D01*
Y1512696D01*
X1439496Y1512283D01*
X1439343Y1511921D01*
X1439113Y1511611D01*
X1438845Y1511405D01*
X1438538Y1511353D01*
G01X1438845Y1512180D02*
X1439305Y1511353D01*
G01X1440910Y1513936D02*
X1441140Y1514246D01*
X1441408Y1514401D01*
X1441715Y1514453D01*
X1442098Y1514350D01*
X1442366Y1514091D01*
X1442443Y1513781D01*
X1442405Y1513471D01*
X1442251Y1513213D01*
X1441485Y1512696D01*
X1441140Y1512335D01*
X1440910Y1511818D01*
X1440833Y1511353D01*
X1442443D01*
G01X1445198D02*
Y1514453D01*
X1443780Y1512231D01*
X1445696D01*
G01X1447761Y1511353D02*
X1447838Y1512025D01*
X1447953Y1512593D01*
X1448106Y1513110D01*
X1448298Y1513678D01*
X1448605Y1514453D01*
X1447071D01*
G01X1435693Y1538890D02*
Y1545090D01*
X1438893D01*
Y1538890D01*
X1435693D01*
G01X1435201Y1561568D02*
Y1567768D01*
X1438401D01*
Y1561568D01*
X1435201D01*
G01X1438392Y1560041D02*
Y1553841D01*
X1435192D01*
Y1560041D01*
X1438392D01*
G01X1459534Y15302D02*
X1486682D01*
G01X1459534Y34988D02*
Y15302D01*
G01X1449985Y24793D02*
Y27993D01*
G01X1456185Y24793D02*
X1449985D01*
G01X1456185Y27993D02*
Y24793D01*
G01X1449985Y27993D02*
X1456185D01*
G01X1449985Y28793D02*
Y31993D01*
G01X1456185Y28793D02*
X1449985D01*
G01X1456185Y31993D02*
Y28793D01*
G01X1449985Y31993D02*
X1456185D01*
G01X1467265Y34988D02*
X1459534D01*
G01X1449701Y37593D02*
Y40793D01*
G01X1455901Y37593D02*
X1449701D01*
G01X1455901Y40793D02*
Y37593D01*
G01X1449701Y40793D02*
X1455901D01*
G01X1461296Y66981D02*
Y70181D01*
G01X1467496Y66981D02*
X1461296D01*
G01X1450630Y82540D02*
Y85740D01*
G01X1456830Y82540D02*
X1450630D01*
G01X1456830Y85740D02*
Y82540D01*
G01X1450630Y74540D02*
Y77740D01*
G01X1456830Y74540D02*
X1450630D01*
G01X1456830Y77740D02*
Y74540D01*
G01X1450630Y77740D02*
X1456830D01*
G01X1450630Y78540D02*
Y81740D01*
G01X1456830Y78540D02*
X1450630D01*
G01X1456830Y81740D02*
Y78540D01*
G01X1450630Y81740D02*
X1456830D01*
G01X1461296Y70181D02*
X1467496D01*
G01X1461341Y70987D02*
Y74187D01*
G01X1467541Y70987D02*
X1461341D01*
G01Y74187D02*
X1467541D01*
G01X1461341Y74987D02*
Y78187D01*
G01X1467541Y74987D02*
X1461341D01*
G01Y78187D02*
X1467541D01*
G01X1461296Y82181D02*
X1467496D01*
G01X1461296Y78981D02*
Y82181D01*
G01X1467496Y78981D02*
X1461296D01*
G01X1450241Y93129D02*
Y86929D01*
G01X1450630Y85740D02*
X1456830D01*
G01X1454250Y86929D02*
X1451050D01*
G01X1454250Y93129D02*
Y86929D01*
G01X1451050Y93129D02*
X1454250D01*
G01X1451050Y86929D02*
Y93129D01*
G01X1449520Y102873D02*
Y96673D01*
G01X1455824Y95950D02*
Y102150D01*
G01X1459024Y95950D02*
X1455824D01*
G01X1459024Y102150D02*
Y95950D01*
G01X1450320Y96673D02*
Y102873D01*
G01X1453520Y96673D02*
X1450320D01*
G01X1453520Y102873D02*
Y96673D01*
G01X1460488Y95913D02*
Y111267D01*
G01X1472969Y95913D02*
X1460488D01*
G01X1455824Y102150D02*
X1459024D01*
G01X1450320Y102873D02*
X1453520D01*
G01X1455824Y109762D02*
X1459024D01*
G01X1455824Y103562D02*
Y109762D01*
G01X1459024Y103562D02*
X1455824D01*
G01X1459024Y109762D02*
Y103562D01*
G01X1460488Y111267D02*
X1473166D01*
G01X1452303Y144690D02*
Y154138D01*
G01X1463139Y144690D02*
X1452303D01*
G01X1463139Y154138D02*
Y144690D01*
G01X1454105Y142847D02*
Y139647D01*
G01X1450135Y149140D02*
Y145940D01*
G01X1464546Y148168D02*
Y151368D01*
G01X1470746Y148168D02*
X1464546D01*
G01Y144168D02*
Y147368D01*
G01X1470746Y144168D02*
X1464546D01*
G01Y147368D02*
X1470746D01*
G01X1454884Y139647D02*
Y142847D01*
G01X1461084Y139647D02*
X1454884D01*
G01X1461084Y142847D02*
Y139647D01*
G01X1454884Y142847D02*
X1461084D01*
G01X1461468Y155128D02*
X1461161Y155180D01*
X1460893Y155386D01*
X1460663Y155696D01*
X1460510Y156058D01*
X1460433Y156471D01*
Y156885D01*
X1460510Y157298D01*
X1460663Y157660D01*
X1460893Y157970D01*
X1461161Y158176D01*
X1461468Y158228D01*
X1461775Y158176D01*
X1462043Y157970D01*
X1462273Y157660D01*
X1462426Y157298D01*
X1462503Y156885D01*
Y156471D01*
X1462426Y156058D01*
X1462273Y155696D01*
X1462043Y155386D01*
X1461775Y155180D01*
X1461468Y155128D01*
G01X1461775Y155955D02*
X1462235Y155128D01*
G01X1463840Y157711D02*
X1464070Y158021D01*
X1464338Y158176D01*
X1464645Y158228D01*
X1465028Y158125D01*
X1465296Y157866D01*
X1465373Y157556D01*
X1465335Y157246D01*
X1465181Y156988D01*
X1464415Y156471D01*
X1464070Y156110D01*
X1463840Y155593D01*
X1463763Y155128D01*
X1465373D01*
G01X1466940Y157711D02*
X1467170Y158021D01*
X1467438Y158176D01*
X1467745Y158228D01*
X1468128Y158125D01*
X1468396Y157866D01*
X1468473Y157556D01*
X1468435Y157246D01*
X1468281Y156988D01*
X1467515Y156471D01*
X1467170Y156110D01*
X1466940Y155593D01*
X1466863Y155128D01*
X1468473D01*
G01X1470116Y155490D02*
X1470385Y155231D01*
X1470691Y155128D01*
X1470998Y155231D01*
X1471266Y155541D01*
X1471458Y156006D01*
X1471535Y156471D01*
Y157040D01*
X1471458Y157505D01*
X1471266Y157918D01*
X1471036Y158125D01*
X1470768Y158228D01*
X1470461Y158125D01*
X1470231Y157918D01*
X1470078Y157608D01*
X1470001Y157195D01*
X1470078Y156833D01*
X1470270Y156471D01*
X1470500Y156265D01*
X1470768Y156213D01*
X1471075Y156316D01*
X1471305Y156575D01*
X1471535Y157040D01*
G01X1459721Y154138D02*
X1463139D01*
G01X1457721Y152414D02*
X1459721Y154138D01*
G01X1455721D02*
X1457721Y152414D01*
G01X1452303Y154138D02*
X1455721D01*
G01X1450135Y153140D02*
Y149940D01*
G01X1464546Y151368D02*
X1470746D01*
G01X1455657Y174900D02*
Y172678D01*
X1455810Y172213D01*
X1456117Y171903D01*
X1456500Y171800D01*
X1456883Y171903D01*
X1457190Y172213D01*
X1457343Y172678D01*
Y174900D01*
G01X1459523Y171800D02*
X1459600Y172472D01*
X1459715Y173040D01*
X1459868Y173557D01*
X1460060Y174125D01*
X1460367Y174900D01*
X1458833D01*
G01X1461857Y172265D02*
X1462087Y172007D01*
X1462355Y171852D01*
X1462700Y171800D01*
X1463045Y171903D01*
X1463313Y172110D01*
X1463505Y172472D01*
X1463543Y172885D01*
X1463467Y173298D01*
X1463275Y173557D01*
X1463007Y173763D01*
X1462738Y173815D01*
X1462470Y173763D01*
X1462125Y173557D01*
X1462240Y174900D01*
X1463275D01*
G01X1455299Y176944D02*
Y178897D01*
G01X1457252Y176944D02*
X1455299D01*
G01X1450571Y177673D02*
Y171473D01*
G01X1463103Y170313D02*
X1469303D01*
G01X1463103Y167113D02*
Y170313D01*
G01X1469303Y167113D02*
X1463103D01*
G01X1453594Y170297D02*
Y167097D01*
G01X1455299Y188756D02*
X1457252D01*
G01X1455299Y186803D02*
Y188756D01*
G01X1450798Y188930D02*
Y182730D01*
G01X1453789Y193541D02*
Y190341D01*
G01X1454661Y201185D02*
Y204285D01*
X1455581D01*
X1455888Y204130D01*
X1456118Y203768D01*
X1456195Y203355D01*
X1456118Y202942D01*
X1455926Y202632D01*
X1455581Y202477D01*
X1454661D01*
G01X1457685Y204285D02*
Y202063D01*
X1457838Y201598D01*
X1458145Y201288D01*
X1458528Y201185D01*
X1458911Y201288D01*
X1459218Y201598D01*
X1459371Y202063D01*
Y204285D01*
G01X1460785Y201805D02*
X1461015Y201443D01*
X1461321Y201237D01*
X1461666Y201185D01*
X1461973Y201237D01*
X1462280Y201495D01*
X1462471Y201805D01*
X1462510Y202115D01*
X1462433Y202477D01*
X1462165Y202735D01*
X1461896Y202838D01*
X1461551D01*
G01X1461896D02*
X1462126Y202993D01*
X1462318Y203252D01*
X1462395Y203562D01*
X1462318Y203872D01*
X1462126Y204130D01*
X1461781Y204285D01*
X1461436Y204233D01*
X1461091Y204027D01*
G01X1464076Y201547D02*
X1464345Y201288D01*
X1464651Y201185D01*
X1464958Y201288D01*
X1465226Y201598D01*
X1465418Y202063D01*
X1465495Y202528D01*
Y203097D01*
X1465418Y203562D01*
X1465226Y203975D01*
X1464996Y204182D01*
X1464728Y204285D01*
X1464421Y204182D01*
X1464191Y203975D01*
X1464038Y203665D01*
X1463961Y203252D01*
X1464038Y202890D01*
X1464230Y202528D01*
X1464460Y202322D01*
X1464728Y202270D01*
X1465035Y202373D01*
X1465265Y202632D01*
X1465495Y203097D01*
G01X1468074Y220252D02*
Y208048D01*
X1452770D01*
Y220252D01*
X1468074D01*
G01X1457758Y232621D02*
Y226621D01*
G01X1449737Y221282D02*
Y215082D01*
G01X1455758Y225921D02*
Y222721D01*
G01X1449558Y225921D02*
X1455758D01*
G01X1449558Y222721D02*
Y225921D01*
G01X1455758Y222721D02*
X1449558D01*
G01X1454426Y258010D02*
Y264210D01*
G01X1457626Y258010D02*
X1454426D01*
G01X1457626Y264210D02*
Y258010D01*
G01X1449626Y264210D02*
Y258010D01*
G01X1453626D02*
X1450426D01*
G01X1453626Y264210D02*
Y258010D01*
G01X1450426D02*
Y264210D01*
G01X1464337Y264635D02*
X1479849D01*
G01X1464337Y295727D02*
Y264635D01*
G01X1454426Y264210D02*
X1457626D01*
G01X1462705Y273701D02*
X1459505D01*
G01X1462705Y279901D02*
Y273701D01*
G01X1459505D02*
Y279901D01*
G01X1450426Y264210D02*
X1453626D01*
G01X1457147Y279427D02*
Y267653D01*
G01X1459505Y279901D02*
X1462705D01*
G01X1452679Y283383D02*
X1449479D01*
G01X1452679Y289583D02*
Y283383D01*
G01X1449479Y289583D02*
X1452679D01*
G01X1449479Y283383D02*
Y289583D01*
G01X1453479Y283383D02*
Y289583D01*
X1456679D01*
Y283383D01*
X1453479D01*
G01X1460800Y282833D02*
X1457700D01*
Y283753D01*
X1457855Y284060D01*
X1458217Y284290D01*
X1458630Y284367D01*
X1459043Y284290D01*
X1459353Y284098D01*
X1459508Y283753D01*
Y282833D01*
G01X1457700Y285857D02*
X1459922D01*
X1460387Y286010D01*
X1460697Y286317D01*
X1460800Y286700D01*
X1460697Y287083D01*
X1460387Y287390D01*
X1459922Y287543D01*
X1457700D01*
G01X1460800Y289800D02*
X1457700D01*
X1458320Y289340D01*
G01X1460800D02*
Y290260D01*
G01Y292900D02*
X1457700D01*
X1458320Y292440D01*
G01X1460800D02*
Y293360D01*
G01X1460335Y295157D02*
X1460593Y295387D01*
X1460748Y295655D01*
X1460800Y296000D01*
X1460697Y296345D01*
X1460490Y296613D01*
X1460128Y296805D01*
X1459715Y296843D01*
X1459302Y296767D01*
X1459043Y296575D01*
X1458837Y296307D01*
X1458785Y296038D01*
X1458837Y295770D01*
X1459043Y295425D01*
X1457700Y295540D01*
Y296575D01*
G01X1479849Y295727D02*
X1464337D01*
G01X1457807Y322461D02*
Y319261D01*
G01X1451607Y322461D02*
X1457807D01*
G01X1451607Y319261D02*
Y322461D01*
G01X1457807Y319261D02*
X1451607D01*
G01X1457807Y326961D02*
Y323761D01*
G01X1451607Y326961D02*
X1457807D01*
G01X1451607Y323761D02*
Y326961D01*
G01X1457807Y323761D02*
X1451607D01*
G01X1457807Y331461D02*
Y328261D01*
G01X1451607Y331461D02*
X1457807D01*
G01X1451607Y328261D02*
Y331461D01*
G01X1457807Y328261D02*
X1451607D01*
G01X1457807Y335961D02*
Y332761D01*
G01X1451607Y335961D02*
X1457807D01*
G01X1451607Y332761D02*
Y335961D01*
G01X1457807Y332761D02*
X1451607D01*
G01X1457807Y340461D02*
Y337261D01*
G01X1451607Y340461D02*
X1457807D01*
G01X1451607Y337261D02*
Y340461D01*
G01X1457807Y337261D02*
X1451607D01*
G01X1457807Y344961D02*
Y341761D01*
G01X1451607D02*
Y344961D01*
G01X1457807Y341761D02*
X1451607D01*
G01Y344961D02*
X1457807D01*
G01X1451607Y355261D02*
Y358461D01*
G01X1457807Y355261D02*
X1451607D01*
G01X1457807Y358461D02*
Y355261D01*
G01X1451607Y358461D02*
X1457807D01*
G01Y349461D02*
Y346261D01*
G01X1451607Y349461D02*
X1457807D01*
G01X1451607Y346261D02*
Y349461D01*
G01X1457807Y346261D02*
X1451607D01*
G01X1457807Y353961D02*
Y350761D01*
G01X1451607Y353961D02*
X1457807D01*
G01X1451607Y350761D02*
Y353961D01*
G01X1457807Y350761D02*
X1451607D01*
G01X1455034Y471194D02*
Y473434D01*
G01X1453409Y472221D02*
X1456659D01*
G01X1465000Y474983D02*
X1461900D01*
Y475903D01*
X1462055Y476210D01*
X1462417Y476440D01*
X1462830Y476517D01*
X1463243Y476440D01*
X1463553Y476248D01*
X1463708Y475903D01*
Y474983D01*
G01X1465000Y478007D02*
X1461900D01*
Y478773D01*
X1462055Y479080D01*
X1462262Y479310D01*
X1462572Y479502D01*
X1462933Y479655D01*
X1463450Y479693D01*
X1463967Y479655D01*
X1464328Y479502D01*
X1464638Y479310D01*
X1464845Y479080D01*
X1465000Y478773D01*
Y478007D01*
G01X1464535Y481107D02*
X1464793Y481337D01*
X1464948Y481605D01*
X1465000Y481950D01*
X1464897Y482295D01*
X1464690Y482563D01*
X1464328Y482755D01*
X1463915Y482793D01*
X1463502Y482717D01*
X1463243Y482525D01*
X1463037Y482257D01*
X1462985Y481988D01*
X1463037Y481720D01*
X1463243Y481375D01*
X1461900Y481490D01*
Y482525D01*
G01X1465000Y484973D02*
X1464328Y485050D01*
X1463760Y485165D01*
X1463243Y485318D01*
X1462675Y485510D01*
X1461900Y485817D01*
Y484283D01*
G01X1448886Y474835D02*
Y504394D01*
G01X1460382Y474835D02*
X1448886D01*
G01X1460382Y504394D02*
Y474835D01*
G01X1454934Y507934D02*
Y505508D01*
G01X1448886Y504394D02*
X1460382D01*
G01X1454800Y520583D02*
X1451700D01*
Y521503D01*
X1451855Y521810D01*
X1452217Y522040D01*
X1452630Y522117D01*
X1453043Y522040D01*
X1453353Y521848D01*
X1453508Y521503D01*
Y520583D01*
G01X1454800Y523607D02*
X1451700D01*
Y524373D01*
X1451855Y524680D01*
X1452062Y524910D01*
X1452372Y525102D01*
X1452733Y525255D01*
X1453250Y525293D01*
X1453767Y525255D01*
X1454128Y525102D01*
X1454438Y524910D01*
X1454645Y524680D01*
X1454800Y524373D01*
Y523607D01*
G01X1454438Y526898D02*
X1454697Y527167D01*
X1454800Y527473D01*
X1454697Y527780D01*
X1454387Y528048D01*
X1453922Y528240D01*
X1453457Y528317D01*
X1452888D01*
X1452423Y528240D01*
X1452010Y528048D01*
X1451803Y527818D01*
X1451700Y527550D01*
X1451803Y527243D01*
X1452010Y527013D01*
X1452320Y526860D01*
X1452733Y526783D01*
X1453095Y526860D01*
X1453457Y527052D01*
X1453663Y527282D01*
X1453715Y527550D01*
X1453612Y527857D01*
X1453353Y528087D01*
X1452888Y528317D01*
G01X1454800Y530650D02*
X1454748Y530918D01*
X1454593Y531225D01*
X1454335Y531417D01*
X1453973Y531493D01*
X1453612Y531417D01*
X1453302Y531187D01*
X1453147Y530842D01*
Y530458D01*
X1453043Y530228D01*
X1452785Y530037D01*
X1452423Y529960D01*
X1452062Y530075D01*
X1451803Y530343D01*
X1451700Y530650D01*
X1451803Y530957D01*
X1452062Y531225D01*
X1452423Y531340D01*
X1452785Y531263D01*
X1453043Y531072D01*
X1453147Y530842D01*
Y530458D01*
X1453302Y530113D01*
X1453612Y529883D01*
X1453973Y529807D01*
X1454335Y529883D01*
X1454593Y530075D01*
X1454748Y530382D01*
X1454800Y530650D01*
G01X1450551Y550138D02*
Y520579D01*
G01X1463173Y553448D02*
Y568248D01*
G01X1454008Y546675D02*
Y544249D01*
G01X1456136Y573214D02*
Y570014D01*
G01X1449936D02*
Y573214D01*
G01X1456136Y570014D02*
X1449936D01*
G01X1452900Y584257D02*
X1455122D01*
X1455587Y584410D01*
X1455897Y584717D01*
X1456000Y585100D01*
X1455897Y585483D01*
X1455587Y585790D01*
X1455122Y585943D01*
X1452900D01*
G01X1456000Y588200D02*
X1455948Y588468D01*
X1455793Y588775D01*
X1455535Y588967D01*
X1455173Y589043D01*
X1454812Y588967D01*
X1454502Y588737D01*
X1454347Y588392D01*
Y588008D01*
X1454243Y587778D01*
X1453985Y587587D01*
X1453623Y587510D01*
X1453262Y587625D01*
X1453003Y587893D01*
X1452900Y588200D01*
X1453003Y588507D01*
X1453262Y588775D01*
X1453623Y588890D01*
X1453985Y588813D01*
X1454243Y588622D01*
X1454347Y588392D01*
Y588008D01*
X1454502Y587663D01*
X1454812Y587433D01*
X1455173Y587357D01*
X1455535Y587433D01*
X1455793Y587625D01*
X1455948Y587932D01*
X1456000Y588200D01*
G01X1455535Y590457D02*
X1455793Y590687D01*
X1455948Y590955D01*
X1456000Y591300D01*
X1455897Y591645D01*
X1455690Y591913D01*
X1455328Y592105D01*
X1454915Y592143D01*
X1454502Y592067D01*
X1454243Y591875D01*
X1454037Y591607D01*
X1453985Y591338D01*
X1454037Y591070D01*
X1454243Y590725D01*
X1452900Y590840D01*
Y591875D01*
G01X1450665Y583895D02*
Y581942D01*
G01X1456136Y577214D02*
Y574014D01*
G01X1449936Y577214D02*
X1456136D01*
G01X1449936Y574014D02*
Y577214D01*
G01X1456136Y574014D02*
X1449936D01*
G01X1457312Y580237D02*
X1460512D01*
G01X1457312Y574037D02*
Y580237D01*
G01X1460512Y574037D02*
X1457312D01*
G01X1460512Y580237D02*
Y574037D01*
G01X1449936Y573214D02*
X1456136D01*
G01X1450665Y593754D02*
Y591801D01*
G01X1456544Y598125D02*
X1453344D01*
G01X1456544Y604325D02*
Y598125D01*
G01X1453344D02*
Y604325D01*
G01X1460544Y598125D02*
X1457344D01*
G01X1460544Y604325D02*
Y598125D01*
G01X1457344D02*
Y604325D01*
G01X1452544Y598125D02*
X1449344D01*
G01X1452544Y604325D02*
Y598125D01*
G01X1449344D02*
Y604325D01*
G01X1459200Y609983D02*
X1456100D01*
Y610903D01*
X1456255Y611210D01*
X1456617Y611440D01*
X1457030Y611517D01*
X1457443Y611440D01*
X1457753Y611248D01*
X1457908Y610903D01*
Y609983D01*
G01X1459200Y613007D02*
X1456100D01*
Y613773D01*
X1456255Y614080D01*
X1456462Y614310D01*
X1456772Y614502D01*
X1457133Y614655D01*
X1457650Y614693D01*
X1458167Y614655D01*
X1458528Y614502D01*
X1458838Y614310D01*
X1459045Y614080D01*
X1459200Y613773D01*
Y613007D01*
G01X1458735Y616107D02*
X1458993Y616337D01*
X1459148Y616605D01*
X1459200Y616950D01*
X1459097Y617295D01*
X1458890Y617563D01*
X1458528Y617755D01*
X1458115Y617793D01*
X1457702Y617717D01*
X1457443Y617525D01*
X1457237Y617257D01*
X1457185Y616988D01*
X1457237Y616720D01*
X1457443Y616375D01*
X1456100Y616490D01*
Y617525D01*
G01X1454708Y609615D02*
Y640707D01*
G01X1453344Y604325D02*
X1456544D01*
G01X1457344D02*
X1460544D01*
G01X1449344D02*
X1452544D01*
G01X1461758Y682449D02*
Y713551D01*
G01X1459051D02*
X1453500Y708000D01*
G01X1461758Y713551D02*
X1459051D01*
G01X1461758Y726449D02*
Y757551D01*
G01X1459051D02*
X1453500Y752000D01*
G01X1461758Y757551D02*
X1459051D01*
G01X1462242Y767949D02*
X1478758D01*
G01X1462242Y799051D02*
Y767949D01*
G01X1464949Y799051D02*
X1462242D01*
G01X1470500Y793500D02*
X1464949Y799051D01*
G01X1462242Y811949D02*
X1478758D01*
G01X1462242Y843051D02*
Y811949D01*
G01X1464949Y843051D02*
X1462242D01*
G01X1470500Y837500D02*
X1464949Y843051D01*
G01X1476488Y857677D02*
X1449145D01*
G01X1498220D02*
X1449145D01*
G01X1463771Y867145D02*
Y908445D01*
G01X1456480Y867145D02*
X1463771D01*
G01X1457096Y929777D02*
X1463296D01*
Y926577D01*
X1457096D01*
Y929777D01*
G01X1460248Y934487D02*
X1466448D01*
Y931287D01*
X1460248D01*
Y934487D01*
G01X1461218Y949380D02*
X1455018D01*
Y952580D01*
X1461218D01*
Y949380D01*
G01X1452135Y965232D02*
X1452497Y965462D01*
X1452703Y965768D01*
X1452755Y966113D01*
X1452703Y966420D01*
X1452445Y966727D01*
X1452135Y966918D01*
X1451825Y966957D01*
X1451463Y966880D01*
X1451205Y966612D01*
X1451102Y966343D01*
Y965998D01*
G01Y966343D02*
X1450947Y966573D01*
X1450688Y966765D01*
X1450378Y966842D01*
X1450068Y966765D01*
X1449810Y966573D01*
X1449655Y966228D01*
X1449707Y965883D01*
X1449913Y965538D01*
G01X1452043Y1005738D02*
X1451991Y1005431D01*
X1451785Y1005163D01*
X1451475Y1004933D01*
X1451113Y1004780D01*
X1450700Y1004703D01*
X1450286D01*
X1449873Y1004780D01*
X1449511Y1004933D01*
X1449201Y1005163D01*
X1448995Y1005431D01*
X1448943Y1005738D01*
X1448995Y1006045D01*
X1449201Y1006313D01*
X1449511Y1006543D01*
X1449873Y1006696D01*
X1450286Y1006773D01*
X1450700D01*
X1451113Y1006696D01*
X1451475Y1006543D01*
X1451785Y1006313D01*
X1451991Y1006045D01*
X1452043Y1005738D01*
G01X1451216Y1006045D02*
X1452043Y1006505D01*
G01X1449460Y1008110D02*
X1449150Y1008340D01*
X1448995Y1008608D01*
X1448943Y1008915D01*
X1449046Y1009298D01*
X1449305Y1009566D01*
X1449615Y1009643D01*
X1449925Y1009605D01*
X1450183Y1009451D01*
X1450700Y1008685D01*
X1451061Y1008340D01*
X1451578Y1008110D01*
X1452043Y1008033D01*
Y1009643D01*
G01X1448943Y1011938D02*
X1449046Y1011631D01*
X1449305Y1011401D01*
X1449615Y1011248D01*
X1450028Y1011133D01*
X1450493Y1011095D01*
X1450958Y1011133D01*
X1451371Y1011248D01*
X1451681Y1011401D01*
X1451940Y1011631D01*
X1452043Y1011938D01*
X1451940Y1012245D01*
X1451681Y1012475D01*
X1451371Y1012628D01*
X1450958Y1012743D01*
X1450493Y1012781D01*
X1450028Y1012743D01*
X1449615Y1012628D01*
X1449305Y1012475D01*
X1449046Y1012245D01*
X1448943Y1011938D01*
G01X1454064Y1007489D02*
Y1016937D01*
G01X1464900Y1007489D02*
X1454064D01*
G01X1464900Y1016937D02*
Y1007489D01*
G01X1459712Y996653D02*
Y999753D01*
X1460478D01*
X1460785Y999598D01*
X1461015Y999391D01*
X1461207Y999081D01*
X1461360Y998720D01*
X1461398Y998203D01*
X1461360Y997686D01*
X1461207Y997325D01*
X1461015Y997015D01*
X1460785Y996808D01*
X1460478Y996653D01*
X1459712D01*
G01X1464115D02*
Y999753D01*
X1462697Y997531D01*
X1464613D01*
G01X1459218Y1005249D02*
X1466308D01*
G01X1459218Y1001449D02*
Y1005249D01*
G01X1466308Y1001449D02*
X1459218D01*
G01X1459718Y1005249D02*
X1466908D01*
G01X1459718Y1001449D02*
Y1005249D01*
G01X1466908Y1001449D02*
X1459718D01*
G01X1460218Y1005249D02*
X1467358D01*
G01X1460218Y1001449D02*
Y1005249D01*
G01X1467308Y1001449D02*
X1460218D01*
G01X1454359Y1006066D02*
X1457559D01*
G01X1454359Y999866D02*
Y1006066D01*
G01X1457559Y999866D02*
X1454359D01*
G01X1457559Y1006066D02*
Y999866D01*
G01X1461482Y1016937D02*
X1464900D01*
G01X1459482Y1015213D02*
X1461482Y1016937D01*
G01X1457482D02*
X1459482Y1015213D01*
G01X1454064Y1016937D02*
X1457482D01*
G01X1453876Y1019448D02*
Y1022648D01*
G01X1460076Y1019448D02*
X1453876D01*
G01X1460076Y1022648D02*
Y1019448D01*
G01X1453876Y1022648D02*
X1460076D01*
G01X1461171Y1019577D02*
Y1022777D01*
G01X1467371Y1019577D02*
X1461171D01*
G01Y1022777D02*
X1467371D01*
G01X1463917Y1023702D02*
X1460717D01*
G01X1463917Y1029902D02*
Y1023702D01*
G01X1460717D02*
Y1029902D01*
G01D02*
X1463917D01*
G01X1454548Y1043355D02*
Y1046455D01*
G01X1456158D02*
Y1043355D01*
G01Y1044905D02*
X1454548D01*
G01X1457801Y1043717D02*
X1458070Y1043458D01*
X1458376Y1043355D01*
X1458683Y1043458D01*
X1458951Y1043768D01*
X1459143Y1044233D01*
X1459220Y1044698D01*
Y1045267D01*
X1459143Y1045732D01*
X1458951Y1046145D01*
X1458721Y1046352D01*
X1458453Y1046455D01*
X1458146Y1046352D01*
X1457916Y1046145D01*
X1457763Y1045835D01*
X1457686Y1045422D01*
X1457763Y1045060D01*
X1457955Y1044698D01*
X1458185Y1044492D01*
X1458453Y1044440D01*
X1458760Y1044543D01*
X1458990Y1044802D01*
X1459220Y1045267D01*
G01X1461476Y1043355D02*
X1461553Y1044027D01*
X1461668Y1044595D01*
X1461821Y1045112D01*
X1462013Y1045680D01*
X1462320Y1046455D01*
X1460786D01*
G01X1457629Y1074905D02*
G03X1519487Y1066535I30363J-8369D01*
G01X1510085Y1088982D02*
G03X1463851Y1086764I-22093J-22446D01*
G01X1463643Y1111496D02*
X1460543D01*
Y1112416D01*
X1460698Y1112723D01*
X1461060Y1112953D01*
X1461473Y1113030D01*
X1461886Y1112953D01*
X1462196Y1112761D01*
X1462351Y1112416D01*
Y1111496D01*
G01X1460543Y1114520D02*
X1462765D01*
X1463230Y1114673D01*
X1463540Y1114980D01*
X1463643Y1115363D01*
X1463540Y1115746D01*
X1463230Y1116053D01*
X1462765Y1116206D01*
X1460543D01*
G01X1463643Y1118463D02*
X1460543D01*
X1461163Y1118003D01*
G01X1463643D02*
Y1118923D01*
G01X1463178Y1120720D02*
X1463436Y1120950D01*
X1463591Y1121218D01*
X1463643Y1121563D01*
X1463540Y1121908D01*
X1463333Y1122176D01*
X1462971Y1122368D01*
X1462558Y1122406D01*
X1462145Y1122330D01*
X1461886Y1122138D01*
X1461680Y1121870D01*
X1461628Y1121601D01*
X1461680Y1121333D01*
X1461886Y1120988D01*
X1460543Y1121103D01*
Y1122138D01*
G01X1459194Y1111426D02*
X1456094D01*
Y1112346D01*
X1456249Y1112653D01*
X1456611Y1112883D01*
X1457024Y1112960D01*
X1457437Y1112883D01*
X1457747Y1112691D01*
X1457902Y1112346D01*
Y1111426D01*
G01X1456094Y1114450D02*
X1458316D01*
X1458781Y1114603D01*
X1459091Y1114910D01*
X1459194Y1115293D01*
X1459091Y1115676D01*
X1458781Y1115983D01*
X1458316Y1116136D01*
X1456094D01*
G01X1459194Y1118393D02*
X1456094D01*
X1456714Y1117933D01*
G01X1459194D02*
Y1118853D01*
G01Y1121953D02*
X1456094D01*
X1458316Y1120535D01*
Y1122451D01*
G01X1454595Y1111649D02*
X1451495D01*
Y1112569D01*
X1451650Y1112876D01*
X1452012Y1113106D01*
X1452425Y1113183D01*
X1452838Y1113106D01*
X1453148Y1112914D01*
X1453303Y1112569D01*
Y1111649D01*
G01X1451495Y1114673D02*
X1453717D01*
X1454182Y1114826D01*
X1454492Y1115133D01*
X1454595Y1115516D01*
X1454492Y1115899D01*
X1454182Y1116206D01*
X1453717Y1116359D01*
X1451495D01*
G01X1454595Y1118616D02*
X1451495D01*
X1452115Y1118156D01*
G01X1454595D02*
Y1119076D01*
G01X1453975Y1120873D02*
X1454337Y1121103D01*
X1454543Y1121409D01*
X1454595Y1121754D01*
X1454543Y1122061D01*
X1454285Y1122368D01*
X1453975Y1122559D01*
X1453665Y1122598D01*
X1453303Y1122521D01*
X1453045Y1122253D01*
X1452942Y1121984D01*
Y1121639D01*
G01Y1121984D02*
X1452787Y1122214D01*
X1452528Y1122406D01*
X1452218Y1122483D01*
X1451908Y1122406D01*
X1451650Y1122214D01*
X1451495Y1121869D01*
X1451547Y1121524D01*
X1451753Y1121179D01*
G01X1462082Y1136291D02*
X1458982D01*
Y1137211D01*
X1459137Y1137518D01*
X1459499Y1137748D01*
X1459912Y1137825D01*
X1460325Y1137748D01*
X1460635Y1137556D01*
X1460790Y1137211D01*
Y1136291D01*
G01X1458982Y1139391D02*
X1462082D01*
Y1140925D01*
G01Y1143258D02*
X1458982D01*
X1459602Y1142798D01*
G01X1462082D02*
Y1143718D01*
G01X1460790Y1145630D02*
X1460429Y1145898D01*
X1460222Y1146128D01*
X1460119Y1146435D01*
X1460222Y1146703D01*
X1460429Y1146895D01*
X1460739Y1147048D01*
X1461100Y1147086D01*
X1461410Y1147048D01*
X1461720Y1146895D01*
X1461979Y1146665D01*
X1462082Y1146396D01*
X1461979Y1146090D01*
X1461669Y1145821D01*
X1461204Y1145668D01*
X1460687Y1145630D01*
X1460015Y1145706D01*
X1459654Y1145821D01*
X1459292Y1146013D01*
X1459034Y1146281D01*
X1458982Y1146550D01*
X1459085Y1146818D01*
X1459344Y1147010D01*
G01X1457547Y1136439D02*
X1454447D01*
Y1137359D01*
X1454602Y1137666D01*
X1454964Y1137896D01*
X1455377Y1137973D01*
X1455790Y1137896D01*
X1456100Y1137704D01*
X1456255Y1137359D01*
Y1136439D01*
G01X1454447Y1139539D02*
X1457547D01*
Y1141073D01*
G01Y1143406D02*
X1454447D01*
X1455067Y1142946D01*
G01X1457547D02*
Y1143866D01*
G01X1457082Y1145663D02*
X1457340Y1145893D01*
X1457495Y1146161D01*
X1457547Y1146506D01*
X1457444Y1146851D01*
X1457237Y1147119D01*
X1456875Y1147311D01*
X1456462Y1147349D01*
X1456049Y1147273D01*
X1455790Y1147081D01*
X1455584Y1146813D01*
X1455532Y1146544D01*
X1455584Y1146276D01*
X1455790Y1145931D01*
X1454447Y1146046D01*
Y1147081D01*
G01X1452726Y1136662D02*
X1449626D01*
Y1137582D01*
X1449781Y1137889D01*
X1450143Y1138119D01*
X1450556Y1138196D01*
X1450969Y1138119D01*
X1451279Y1137927D01*
X1451434Y1137582D01*
Y1136662D01*
G01X1449626Y1139762D02*
X1452726D01*
Y1141296D01*
G01Y1143629D02*
X1449626D01*
X1450246Y1143169D01*
G01X1452726D02*
Y1144089D01*
G01X1452106Y1145886D02*
X1452468Y1146116D01*
X1452674Y1146422D01*
X1452726Y1146767D01*
X1452674Y1147074D01*
X1452416Y1147381D01*
X1452106Y1147572D01*
X1451796Y1147611D01*
X1451434Y1147534D01*
X1451176Y1147266D01*
X1451073Y1146997D01*
Y1146652D01*
G01Y1146997D02*
X1450918Y1147227D01*
X1450659Y1147419D01*
X1450349Y1147496D01*
X1450039Y1147419D01*
X1449781Y1147227D01*
X1449626Y1146882D01*
X1449678Y1146537D01*
X1449884Y1146192D01*
G01X1519487Y1263386D02*
G03X1509987Y1240843I-31497J0D01*
G01X1462559Y1291243D02*
Y1294343D01*
G01X1464169D02*
Y1291243D01*
G01Y1292793D02*
X1462559D01*
G01X1465812Y1291605D02*
X1466081Y1291346D01*
X1466387Y1291243D01*
X1466694Y1291346D01*
X1466962Y1291656D01*
X1467154Y1292121D01*
X1467231Y1292586D01*
Y1293155D01*
X1467154Y1293620D01*
X1466962Y1294033D01*
X1466732Y1294240D01*
X1466464Y1294343D01*
X1466157Y1294240D01*
X1465927Y1294033D01*
X1465774Y1293723D01*
X1465697Y1293310D01*
X1465774Y1292948D01*
X1465966Y1292586D01*
X1466196Y1292380D01*
X1466464Y1292328D01*
X1466771Y1292431D01*
X1467001Y1292690D01*
X1467231Y1293155D01*
G01X1468721Y1291708D02*
X1468951Y1291450D01*
X1469219Y1291295D01*
X1469564Y1291243D01*
X1469909Y1291346D01*
X1470177Y1291553D01*
X1470369Y1291915D01*
X1470407Y1292328D01*
X1470331Y1292741D01*
X1470139Y1293000D01*
X1469871Y1293206D01*
X1469602Y1293258D01*
X1469334Y1293206D01*
X1468989Y1293000D01*
X1469104Y1294343D01*
X1470139D01*
G01X1461575Y1425158D02*
Y1689331D01*
G01X1574567Y1425158D02*
X1461575D01*
G01Y1689331D02*
X1574567D01*
G01X1478407Y-60300D02*
Y-57200D01*
X1479173D01*
X1479480Y-57355D01*
X1479710Y-57562D01*
X1479902Y-57872D01*
X1480055Y-58233D01*
X1480093Y-58750D01*
X1480055Y-59267D01*
X1479902Y-59628D01*
X1479710Y-59938D01*
X1479480Y-60145D01*
X1479173Y-60300D01*
X1478407D01*
G01X1483117D02*
X1481583D01*
Y-57200D01*
X1483117D01*
G01X1482503Y-58698D02*
X1481583D01*
G01X1485450Y-57200D02*
X1485143Y-57303D01*
X1484913Y-57562D01*
X1484760Y-57872D01*
X1484645Y-58285D01*
X1484607Y-58750D01*
X1484645Y-59215D01*
X1484760Y-59628D01*
X1484913Y-59938D01*
X1485143Y-60197D01*
X1485450Y-60300D01*
X1485757Y-60197D01*
X1485987Y-59938D01*
X1486140Y-59628D01*
X1486255Y-59215D01*
X1486293Y-58750D01*
X1486255Y-58285D01*
X1486140Y-57872D01*
X1485987Y-57562D01*
X1485757Y-57303D01*
X1485450Y-57200D01*
G01X1489010Y-60300D02*
Y-57200D01*
X1487592Y-59422D01*
X1489508D01*
G01X1490922Y-60300D02*
Y-57200D01*
X1492378D01*
G01X1491842Y-58698D02*
X1490922D01*
G01X1493600Y-61333D02*
X1495900D01*
G01X1497850Y-60300D02*
Y-57200D01*
X1497390Y-57820D01*
G01Y-60300D02*
X1498310D01*
G01X1468507Y13700D02*
Y11478D01*
X1468660Y11013D01*
X1468967Y10703D01*
X1469350Y10600D01*
X1469733Y10703D01*
X1470040Y11013D01*
X1470193Y11478D01*
Y13700D01*
G01X1472910Y10600D02*
Y13700D01*
X1471492Y11478D01*
X1473408D01*
G01X1475550Y10600D02*
Y13700D01*
X1475090Y13080D01*
G01Y10600D02*
X1476010D01*
G01X1478573D02*
X1478650Y11272D01*
X1478765Y11840D01*
X1478918Y12357D01*
X1479110Y12925D01*
X1479417Y13700D01*
X1477883D01*
G01X1478951Y34988D02*
X1473108Y29145D01*
G01X1486682Y34988D02*
X1478951D01*
G01X1473108Y29145D02*
X1467265Y34988D01*
G01X1475297Y39844D02*
X1481497D01*
G01X1475297Y36644D02*
Y39844D01*
G01X1481497Y36644D02*
X1475297D01*
G01X1482128Y67523D02*
X1469924D01*
G01D02*
Y70183D01*
G01X1476821Y59613D02*
Y56413D01*
G01X1470621Y59613D02*
X1476821D01*
G01X1470621Y56413D02*
Y59613D01*
G01X1476821Y56413D02*
X1470621D01*
G01X1467496Y70181D02*
Y66981D01*
G01X1469924Y79047D02*
X1482128D01*
G01X1469924Y76285D02*
Y79047D01*
G01X1473026Y73285D02*
X1469924Y76285D01*
G01Y70183D02*
X1473026Y73285D01*
G01X1467541Y74187D02*
Y70987D01*
G01Y78187D02*
Y74987D01*
G01X1467496Y82181D02*
Y78981D01*
G01X1468331Y93476D02*
X1471531D01*
G01X1468331Y87276D02*
Y93476D01*
G01X1471531Y87276D02*
X1468331D01*
G01X1471531Y93476D02*
Y87276D01*
G01X1480980Y87204D02*
X1477780D01*
G01X1480980Y93404D02*
Y87204D01*
G01X1477780Y93404D02*
X1480980D01*
G01X1477780Y87204D02*
Y93404D01*
G01X1477031Y87276D02*
X1473831D01*
G01X1477031Y93476D02*
Y87276D01*
G01X1473831Y93476D02*
X1477031D01*
G01X1473831Y87276D02*
Y93476D01*
G01X1474300Y97707D02*
X1476522D01*
X1476987Y97860D01*
X1477297Y98167D01*
X1477400Y98550D01*
X1477297Y98933D01*
X1476987Y99240D01*
X1476522Y99393D01*
X1474300D01*
G01X1477400Y102110D02*
X1474300D01*
X1476522Y100692D01*
Y102608D01*
G01X1474300Y104750D02*
X1474403Y104443D01*
X1474662Y104213D01*
X1474972Y104060D01*
X1475385Y103945D01*
X1475850Y103907D01*
X1476315Y103945D01*
X1476728Y104060D01*
X1477038Y104213D01*
X1477297Y104443D01*
X1477400Y104750D01*
X1477297Y105057D01*
X1477038Y105287D01*
X1476728Y105440D01*
X1476315Y105555D01*
X1475850Y105593D01*
X1475385Y105555D01*
X1474972Y105440D01*
X1474662Y105287D01*
X1474403Y105057D01*
X1474300Y104750D01*
G01X1477400Y107850D02*
X1477348Y108118D01*
X1477193Y108425D01*
X1476935Y108617D01*
X1476573Y108693D01*
X1476212Y108617D01*
X1475902Y108387D01*
X1475747Y108042D01*
Y107658D01*
X1475643Y107428D01*
X1475385Y107237D01*
X1475023Y107160D01*
X1474662Y107275D01*
X1474403Y107543D01*
X1474300Y107850D01*
X1474403Y108157D01*
X1474662Y108425D01*
X1475023Y108540D01*
X1475385Y108463D01*
X1475643Y108272D01*
X1475747Y108042D01*
Y107658D01*
X1475902Y107313D01*
X1476212Y107083D01*
X1476573Y107007D01*
X1476935Y107083D01*
X1477193Y107275D01*
X1477348Y107582D01*
X1477400Y107850D01*
G01X1473166Y111267D02*
Y95913D01*
G01X1474322Y111951D02*
Y118151D01*
G01X1477522Y111951D02*
X1474322D01*
G01X1477522Y118151D02*
Y111951D01*
G01X1481242Y109424D02*
X1484442D01*
G01X1481242Y103224D02*
Y109424D01*
G01X1484442Y103224D02*
X1481242D01*
G01X1473039Y116088D02*
Y112888D01*
G01X1466839Y116088D02*
X1473039D01*
G01X1466839Y112888D02*
Y116088D01*
G01X1473039Y112888D02*
X1466839D01*
G01X1479696Y111734D02*
Y123508D01*
G01X1489458Y111734D02*
X1479696D01*
G01X1474322Y118151D02*
X1477522D01*
G01X1480467Y126223D02*
X1477267D01*
G01X1480467Y132423D02*
Y126223D01*
G01X1477267Y132423D02*
X1480467D01*
G01X1477267Y126223D02*
Y132423D01*
G01X1472702Y118514D02*
X1469602D01*
Y119434D01*
X1469757Y119741D01*
X1470119Y119971D01*
X1470532Y120048D01*
X1470945Y119971D01*
X1471255Y119779D01*
X1471410Y119434D01*
Y118514D01*
G01X1469602Y121538D02*
X1471824D01*
X1472289Y121691D01*
X1472599Y121998D01*
X1472702Y122381D01*
X1472599Y122764D01*
X1472289Y123071D01*
X1471824Y123224D01*
X1469602D01*
G01X1472702Y125481D02*
X1469602D01*
X1470222Y125021D01*
G01X1472702D02*
Y125941D01*
G01X1472082Y127738D02*
X1472444Y127968D01*
X1472650Y128274D01*
X1472702Y128619D01*
X1472650Y128926D01*
X1472392Y129233D01*
X1472082Y129424D01*
X1471772Y129463D01*
X1471410Y129386D01*
X1471152Y129118D01*
X1471049Y128849D01*
Y128504D01*
G01Y128849D02*
X1470894Y129079D01*
X1470635Y129271D01*
X1470325Y129348D01*
X1470015Y129271D01*
X1469757Y129079D01*
X1469602Y128734D01*
X1469654Y128389D01*
X1469860Y128044D01*
G01X1470119Y130953D02*
X1469809Y131183D01*
X1469654Y131451D01*
X1469602Y131758D01*
X1469705Y132141D01*
X1469964Y132409D01*
X1470274Y132486D01*
X1470584Y132448D01*
X1470842Y132294D01*
X1471359Y131528D01*
X1471720Y131183D01*
X1472237Y130953D01*
X1472702Y130876D01*
Y132486D01*
G01X1479696Y123508D02*
X1489458D01*
G01X1479656Y146229D02*
X1476456D01*
G01X1479656Y152429D02*
Y146229D01*
G01X1476456D02*
Y152429D01*
G01X1470746Y151368D02*
Y148168D01*
G01Y147368D02*
Y144168D01*
G01X1471700Y136707D02*
X1473922D01*
X1474387Y136860D01*
X1474697Y137167D01*
X1474800Y137550D01*
X1474697Y137933D01*
X1474387Y138240D01*
X1473922Y138393D01*
X1471700D01*
G01X1474180Y139807D02*
X1474542Y140037D01*
X1474748Y140343D01*
X1474800Y140688D01*
X1474748Y140995D01*
X1474490Y141302D01*
X1474180Y141493D01*
X1473870Y141532D01*
X1473508Y141455D01*
X1473250Y141187D01*
X1473147Y140918D01*
Y140573D01*
G01Y140918D02*
X1472992Y141148D01*
X1472733Y141340D01*
X1472423Y141417D01*
X1472113Y141340D01*
X1471855Y141148D01*
X1471700Y140803D01*
X1471752Y140458D01*
X1471958Y140113D01*
G01X1474438Y143098D02*
X1474697Y143367D01*
X1474800Y143673D01*
X1474697Y143980D01*
X1474387Y144248D01*
X1473922Y144440D01*
X1473457Y144517D01*
X1472888D01*
X1472423Y144440D01*
X1472010Y144248D01*
X1471803Y144018D01*
X1471700Y143750D01*
X1471803Y143443D01*
X1472010Y143213D01*
X1472320Y143060D01*
X1472733Y142983D01*
X1473095Y143060D01*
X1473457Y143252D01*
X1473663Y143482D01*
X1473715Y143750D01*
X1473612Y144057D01*
X1473353Y144287D01*
X1472888Y144517D01*
G01X1474800Y147310D02*
X1471700D01*
X1473922Y145892D01*
Y147808D01*
G01X1478146Y144395D02*
Y135095D01*
G01X1488746Y144395D02*
X1478146D01*
G01Y134995D02*
X1488746D01*
G01X1476456Y152429D02*
X1479656D01*
G01X1476456Y159540D02*
X1479656D01*
G01X1476456Y153340D02*
Y159540D01*
G01X1479656Y153340D02*
X1476456D01*
G01X1479656Y159540D02*
Y153340D01*
G01X1467111Y176944D02*
X1465158D01*
G01X1467111Y178897D02*
Y176944D01*
G01X1469303Y170313D02*
Y167113D01*
G01X1471482Y167065D02*
Y170265D01*
G01X1477682Y167065D02*
X1471482D01*
G01X1477682Y170265D02*
Y167065D01*
G01X1471482Y170265D02*
X1477682D01*
G01X1471482Y175065D02*
Y178265D01*
G01X1477682Y175065D02*
X1471482D01*
G01X1477682Y178265D02*
Y175065D01*
G01X1471482Y178265D02*
X1477682D01*
G01X1471482Y171065D02*
Y174265D01*
G01X1477682Y171065D02*
X1471482D01*
G01X1477682Y174265D02*
Y171065D01*
G01X1471482Y174265D02*
X1477682D01*
G01X1471482Y179065D02*
Y182265D01*
G01X1477682Y179065D02*
X1471482D01*
G01X1477682Y182265D02*
Y179065D01*
G01X1467111Y188756D02*
Y186803D01*
G01X1465158Y188756D02*
X1467111D01*
G01X1479250Y189435D02*
X1481490D01*
G01X1480277Y191060D02*
Y187810D01*
G01X1471482Y182265D02*
X1477682D01*
G01X1471482Y183065D02*
Y186265D01*
G01X1477682Y183065D02*
X1471482D01*
G01X1477682Y186265D02*
Y183065D01*
G01X1471482Y186265D02*
X1477682D01*
G01Y198265D02*
Y195065D01*
G01X1471482D02*
Y198265D01*
G01X1477682Y195065D02*
X1471482D01*
G01X1477682Y194265D02*
Y191065D01*
G01X1471482Y194265D02*
X1477682D01*
G01X1471482Y191065D02*
Y194265D01*
G01X1477682Y191065D02*
X1471482D01*
G01Y187065D02*
Y190265D01*
G01X1477682Y187065D02*
X1471482D01*
G01X1477682Y190265D02*
Y187065D01*
G01X1471482Y190265D02*
X1477682D01*
G01X1471577Y202464D02*
X1477777D01*
Y199264D01*
X1471577D01*
Y202464D01*
G01X1471482Y198265D02*
X1477682D01*
G01X1471577Y207264D02*
Y210464D01*
G01X1477777Y207264D02*
X1471577D01*
G01X1477777Y210464D02*
Y207264D01*
G01X1471577Y210464D02*
X1477777D01*
G01Y206464D02*
Y203264D01*
G01X1471577Y206464D02*
X1477777D01*
G01X1471577Y203264D02*
Y206464D01*
G01X1477777Y203264D02*
X1471577D01*
G01Y214464D02*
X1477777D01*
Y211264D01*
X1471577D01*
Y214464D01*
G01Y215264D02*
Y218464D01*
G01X1477777Y215264D02*
X1471577D01*
G01X1477777Y218464D02*
Y215264D01*
G01X1471577Y218464D02*
X1477777D01*
G01X1471577Y220264D02*
Y223464D01*
G01X1477777Y220264D02*
X1471577D01*
G01X1477777Y223464D02*
Y220264D01*
G01X1471577Y223464D02*
X1477777D01*
G01X1471574Y227319D02*
X1477774D01*
Y224119D01*
X1471574D01*
Y227319D01*
G01X1469293Y234813D02*
Y250325D01*
G01X1484200Y265183D02*
X1481100D01*
Y266103D01*
X1481255Y266410D01*
X1481617Y266640D01*
X1482030Y266717D01*
X1482443Y266640D01*
X1482753Y266448D01*
X1482908Y266103D01*
Y265183D01*
G01X1484200Y268207D02*
X1481100D01*
Y268973D01*
X1481255Y269280D01*
X1481462Y269510D01*
X1481772Y269702D01*
X1482133Y269855D01*
X1482650Y269893D01*
X1483167Y269855D01*
X1483528Y269702D01*
X1483838Y269510D01*
X1484045Y269280D01*
X1484200Y268973D01*
Y268207D01*
G01Y272150D02*
X1481100D01*
X1481720Y271690D01*
G01X1484200D02*
Y272610D01*
G01Y275250D02*
X1481100D01*
X1481720Y274790D01*
G01X1484200D02*
Y275710D01*
G01X1482908Y277622D02*
X1482547Y277890D01*
X1482340Y278120D01*
X1482237Y278427D01*
X1482340Y278695D01*
X1482547Y278887D01*
X1482857Y279040D01*
X1483218Y279078D01*
X1483528Y279040D01*
X1483838Y278887D01*
X1484097Y278657D01*
X1484200Y278388D01*
X1484097Y278082D01*
X1483787Y277813D01*
X1483322Y277660D01*
X1482805Y277622D01*
X1482133Y277698D01*
X1481772Y277813D01*
X1481410Y278005D01*
X1481152Y278273D01*
X1481100Y278542D01*
X1481203Y278810D01*
X1481462Y279002D01*
G01X1479849Y264635D02*
Y295727D01*
G01X1478446Y325600D02*
Y328800D01*
G01X1484646Y325600D02*
X1478446D01*
G01Y321100D02*
Y324300D01*
G01X1484646Y321100D02*
X1478446D01*
G01Y324300D02*
X1484646D01*
G01X1478446Y328800D02*
X1484646D01*
G01X1478446Y343600D02*
Y346800D01*
G01X1484646Y343600D02*
X1478446D01*
G01Y339100D02*
Y342300D01*
G01X1484646Y339100D02*
X1478446D01*
G01Y342300D02*
X1484646D01*
G01X1478446Y330100D02*
Y333300D01*
G01X1484646Y330100D02*
X1478446D01*
G01Y333300D02*
X1484646D01*
G01X1478446Y346800D02*
X1484646D01*
G01X1478446Y357100D02*
Y360300D01*
G01X1484646Y357100D02*
X1478446D01*
G01Y360300D02*
X1484646D01*
G01X1478446Y352600D02*
Y355800D01*
G01X1484646Y352600D02*
X1478446D01*
G01Y355800D02*
X1484646D01*
G01X1478446Y348100D02*
Y351300D01*
G01X1484646Y348100D02*
X1478446D01*
G01Y351300D02*
X1484646D01*
G01X1480400Y684030D02*
Y687230D01*
G01X1486600Y684030D02*
X1480400D01*
G01Y680030D02*
Y683230D01*
G01X1486600Y680030D02*
X1480400D01*
G01Y683230D02*
X1486600D01*
G01X1480400Y676030D02*
Y679230D01*
G01X1486600Y676030D02*
X1480400D01*
G01Y679230D02*
X1486600D01*
G01X1480400Y687230D02*
X1486600D01*
G01X1480400Y696030D02*
Y699230D01*
G01X1486600Y696030D02*
X1480400D01*
G01Y699230D02*
X1486600D01*
G01X1480400Y688030D02*
Y691230D01*
G01X1486600Y688030D02*
X1480400D01*
G01Y691230D02*
X1486600D01*
G01X1480400Y692030D02*
Y695230D01*
G01X1486600Y692030D02*
X1480400D01*
G01Y695230D02*
X1486600D01*
G01X1473100Y711400D02*
X1469900D01*
G01X1473100Y717600D02*
Y711400D01*
G01X1469900Y717600D02*
X1473100D01*
G01X1469900Y711400D02*
Y717600D01*
G01X1480400Y704900D02*
Y708100D01*
G01X1486600Y704900D02*
X1480400D01*
G01Y708100D02*
X1486600D01*
G01X1480900Y729100D02*
X1487100D01*
G01X1480900Y725900D02*
Y729100D01*
G01X1487100Y725900D02*
X1480900D01*
G01Y733900D02*
Y737100D01*
G01X1487100Y733900D02*
X1480900D01*
G01Y729900D02*
Y733100D01*
G01X1487100Y729900D02*
X1480900D01*
G01Y733100D02*
X1487100D01*
G01X1480900Y721900D02*
Y725100D01*
G01X1487100Y721900D02*
X1480900D01*
G01Y725100D02*
X1487100D01*
G01X1480900Y737100D02*
X1487100D01*
G01X1480400Y748900D02*
Y752100D01*
G01X1486600Y748900D02*
X1480400D01*
G01X1480900Y741900D02*
Y745100D01*
G01X1487100Y741900D02*
X1480900D01*
G01Y745100D02*
X1487100D01*
G01X1480900Y737900D02*
Y741100D01*
G01X1487100Y737900D02*
X1480900D01*
G01Y741100D02*
X1487100D01*
G01X1473100Y755400D02*
X1469900D01*
G01X1473100Y761600D02*
Y755400D01*
G01X1469900Y761600D02*
X1473100D01*
G01X1469900Y755400D02*
Y761600D01*
G01X1480400Y752100D02*
X1486600D01*
G01X1478758Y767949D02*
Y799051D01*
G01X1476051D02*
X1470500Y793500D01*
G01X1465507Y803367D02*
Y801145D01*
X1465660Y800680D01*
X1465967Y800370D01*
X1466350Y800267D01*
X1466733Y800370D01*
X1467040Y800680D01*
X1467193Y801145D01*
Y803367D01*
G01X1468607Y800887D02*
X1468837Y800525D01*
X1469143Y800319D01*
X1469488Y800267D01*
X1469795Y800319D01*
X1470102Y800577D01*
X1470293Y800887D01*
X1470332Y801197D01*
X1470255Y801559D01*
X1469987Y801817D01*
X1469718Y801920D01*
X1469373D01*
G01X1469718D02*
X1469948Y802075D01*
X1470140Y802334D01*
X1470217Y802644D01*
X1470140Y802954D01*
X1469948Y803212D01*
X1469603Y803367D01*
X1469258Y803315D01*
X1468913Y803109D01*
G01X1473010Y800267D02*
Y803367D01*
X1471592Y801145D01*
X1473508D01*
G01X1474807Y800732D02*
X1475037Y800474D01*
X1475305Y800319D01*
X1475650Y800267D01*
X1475995Y800370D01*
X1476263Y800577D01*
X1476455Y800939D01*
X1476493Y801352D01*
X1476417Y801765D01*
X1476225Y802024D01*
X1475957Y802230D01*
X1475688Y802282D01*
X1475420Y802230D01*
X1475075Y802024D01*
X1475190Y803367D01*
X1476225D01*
G01X1478758Y799051D02*
X1476051D01*
G01X1478758Y811949D02*
Y843051D01*
G01X1465507Y847367D02*
Y845145D01*
X1465660Y844680D01*
X1465967Y844370D01*
X1466350Y844267D01*
X1466733Y844370D01*
X1467040Y844680D01*
X1467193Y845145D01*
Y847367D01*
G01X1468607Y844887D02*
X1468837Y844525D01*
X1469143Y844319D01*
X1469488Y844267D01*
X1469795Y844319D01*
X1470102Y844577D01*
X1470293Y844887D01*
X1470332Y845197D01*
X1470255Y845559D01*
X1469987Y845817D01*
X1469718Y845920D01*
X1469373D01*
G01X1469718D02*
X1469948Y846075D01*
X1470140Y846334D01*
X1470217Y846644D01*
X1470140Y846954D01*
X1469948Y847212D01*
X1469603Y847367D01*
X1469258Y847315D01*
X1468913Y847109D01*
G01X1473010Y844267D02*
Y847367D01*
X1471592Y845145D01*
X1473508D01*
G01X1474807Y844887D02*
X1475037Y844525D01*
X1475343Y844319D01*
X1475688Y844267D01*
X1475995Y844319D01*
X1476302Y844577D01*
X1476493Y844887D01*
X1476532Y845197D01*
X1476455Y845559D01*
X1476187Y845817D01*
X1475918Y845920D01*
X1475573D01*
G01X1475918D02*
X1476148Y846075D01*
X1476340Y846334D01*
X1476417Y846644D01*
X1476340Y846954D01*
X1476148Y847212D01*
X1475803Y847367D01*
X1475458Y847315D01*
X1475113Y847109D01*
G01X1476051Y843051D02*
X1470500Y837500D01*
G01X1478758Y843051D02*
X1476051D01*
G01X1476488Y857677D02*
Y917913D01*
G01X1481145Y905545D02*
X1481093Y905813D01*
X1480938Y906120D01*
X1480680Y906312D01*
X1480318Y906388D01*
X1479957Y906312D01*
X1479647Y906082D01*
X1479492Y905737D01*
Y905353D01*
X1479388Y905123D01*
X1479130Y904932D01*
X1478768Y904855D01*
X1478407Y904970D01*
X1478148Y905238D01*
X1478045Y905545D01*
X1478148Y905852D01*
X1478407Y906120D01*
X1478768Y906235D01*
X1479130Y906158D01*
X1479388Y905967D01*
X1479492Y905737D01*
Y905353D01*
X1479647Y905008D01*
X1479957Y904778D01*
X1480318Y904702D01*
X1480680Y904778D01*
X1480938Y904970D01*
X1481093Y905277D01*
X1481145Y905545D01*
G01X1465100Y941143D02*
X1471300D01*
Y937943D01*
X1465100D01*
Y941143D01*
G01X1465064Y945096D02*
X1471264D01*
Y941896D01*
X1465064D01*
Y945096D01*
G01X1471217Y946000D02*
X1465017D01*
Y949200D01*
X1471217D01*
Y946000D01*
G01X1469400Y970400D02*
Y973600D01*
G01X1475600Y970400D02*
X1469400D01*
G01X1475600Y973600D02*
Y970400D01*
G01X1469400Y973600D02*
X1475600D01*
G01X1473496Y987631D02*
X1476696D01*
G01X1473496Y981431D02*
Y987631D01*
G01X1476696Y981431D02*
X1473496D01*
G01X1476696Y987631D02*
Y981431D01*
G01X1477496Y987631D02*
X1480696D01*
G01X1477496Y981431D02*
Y987631D01*
G01X1480696Y981431D02*
X1477496D01*
G01X1480696Y987631D02*
Y981431D01*
G01X1469496Y987631D02*
X1472696D01*
G01X1469496Y981431D02*
Y987631D01*
G01X1472696Y981431D02*
X1469496D01*
G01X1472696Y987631D02*
Y981431D01*
G01X1473496Y990431D02*
Y996631D01*
G01X1476696Y990431D02*
X1473496D01*
G01X1476696Y996631D02*
Y990431D01*
G01X1477496D02*
Y996631D01*
G01X1480696Y990431D02*
X1477496D01*
G01X1480696Y996631D02*
Y990431D01*
G01X1469496D02*
Y996631D01*
G01X1472696Y990431D02*
X1469496D01*
G01X1472696Y996631D02*
Y990431D01*
G01X1465496Y987631D02*
X1468696D01*
G01X1465496Y981431D02*
Y987631D01*
G01X1468696Y981431D02*
X1465496D01*
G01X1468696Y987631D02*
Y981431D01*
G01X1465496Y990431D02*
Y996631D01*
G01X1468696Y990431D02*
X1465496D01*
G01X1468696Y996631D02*
Y990431D01*
G01X1472424Y1003053D02*
Y1007653D01*
G01X1482624Y1003053D02*
X1472424D01*
G01Y1007653D02*
X1482624D01*
G01X1467358Y1005249D02*
Y1001499D01*
G01X1473496Y996631D02*
X1476696D01*
G01X1477496D02*
X1480696D01*
G01X1469496D02*
X1472696D01*
G01X1467269Y1009297D02*
Y1015497D01*
G01X1470469Y1009297D02*
X1467269D01*
G01X1470469Y1015497D02*
Y1009297D01*
G01X1465496Y996631D02*
X1468696D01*
G01X1479218Y1022862D02*
X1483818D01*
G01X1479218Y1012662D02*
Y1022862D01*
G01X1483818Y1012662D02*
X1479218D01*
G01X1476131Y1029963D02*
Y1025363D01*
G01X1465931D02*
Y1029963D01*
G01X1476131Y1025363D02*
X1465931D01*
G01X1472018Y1011603D02*
Y1024483D01*
G01X1478418D02*
Y1011603D01*
G01X1472018Y1024483D02*
X1478418D01*
G01X1472018Y1011603D02*
X1478418D01*
G01X1477418Y1025333D02*
Y1028533D01*
G01X1483618Y1025333D02*
X1477418D01*
G01X1467269Y1015497D02*
X1470469D01*
G01X1467371Y1022777D02*
Y1019577D01*
G01X1465931Y1029963D02*
X1476131D01*
G01X1477418Y1028533D02*
X1483618D01*
G01X1474984Y1102002D02*
Y1112202D01*
G01X1479584Y1102002D02*
X1474984D01*
G01X1479584Y1112202D02*
Y1102002D01*
G01X1474984Y1114602D02*
Y1124802D01*
G01X1479584Y1114602D02*
X1474984D01*
G01X1479584Y1124802D02*
Y1114602D01*
G01X1474984Y1112202D02*
X1479584D01*
G01X1474984Y1124802D02*
X1479584D01*
G01X1474984Y1137402D02*
X1479584D01*
G01X1474984Y1127202D02*
Y1137402D01*
G01X1479584Y1127202D02*
X1474984D01*
G01X1479584Y1137402D02*
Y1127202D01*
G01X1474984Y1139802D02*
Y1150002D01*
G01X1479584Y1139802D02*
X1474984D01*
G01X1479584Y1150002D02*
Y1139802D01*
G01X1474984Y1150002D02*
X1479584D01*
G01X1474984Y1152402D02*
Y1162602D01*
G01X1479584Y1152402D02*
X1474984D01*
G01X1479584Y1162602D02*
Y1152402D01*
G01X1474984Y1165002D02*
Y1175202D01*
G01X1479584Y1165002D02*
X1474984D01*
G01X1479584Y1175202D02*
Y1165002D01*
G01X1474984Y1162602D02*
X1479584D01*
G01X1474984Y1175202D02*
X1479584D01*
G01X1474984Y1187802D02*
X1479584D01*
G01X1474984Y1177602D02*
Y1187802D01*
G01X1479584Y1177602D02*
X1474984D01*
G01X1479584Y1187802D02*
Y1177602D01*
G01X1480849Y1205673D02*
X1478587Y1207935D01*
G01X1485233Y1210057D02*
X1480849Y1205673D01*
G01X1478587Y1207935D02*
X1482971Y1212319D01*
G01X1480143Y1215147D02*
X1482405Y1212885D01*
G01X1475759Y1210763D02*
X1480143Y1215147D01*
G01X1478021Y1208501D02*
X1475759Y1210763D01*
G01X1482405Y1212885D02*
X1478021Y1208501D01*
G01X1474839Y1211683D02*
X1472577Y1213945D01*
G01X1479223Y1216067D02*
X1474839Y1211683D01*
G01X1476961Y1218329D02*
X1479223Y1216067D01*
G01X1472577Y1213945D02*
X1476961Y1218329D01*
G01X1479261Y1228126D02*
X1482461D01*
G01X1479261Y1221926D02*
Y1228126D01*
G01X1482461Y1221926D02*
X1479261D01*
G01X1475261Y1228126D02*
X1478461D01*
G01X1475261Y1221926D02*
Y1228126D01*
G01X1478461Y1221926D02*
X1475261D01*
G01X1478461Y1228126D02*
Y1221926D01*
G01X1478921Y1422407D02*
X1478361Y1422782D01*
X1477708Y1423032D01*
X1476961D01*
X1476121Y1422657D01*
X1475468Y1422032D01*
X1475001Y1421282D01*
X1474628Y1420032D01*
X1474535Y1418907D01*
X1474721Y1417782D01*
X1475001Y1417032D01*
X1475561Y1416282D01*
X1476215Y1415782D01*
X1476868Y1415532D01*
X1477521D01*
X1478175Y1415782D01*
X1478735Y1416157D01*
X1479201Y1416657D01*
G01X1482501Y1415532D02*
Y1423032D01*
X1484741D01*
X1485488Y1422657D01*
X1486048Y1421782D01*
X1486235Y1420782D01*
X1486048Y1419782D01*
X1485581Y1419032D01*
X1484741Y1418657D01*
X1482501D01*
G01X1489815Y1423032D02*
Y1417657D01*
X1490188Y1416532D01*
X1490935Y1415782D01*
X1491868Y1415532D01*
X1492801Y1415782D01*
X1493548Y1416532D01*
X1493921Y1417657D01*
Y1423032D01*
G01X1496568Y1413032D02*
X1502168D01*
G01X1507615Y1419532D02*
X1507988Y1419907D01*
X1508268Y1420532D01*
X1508455Y1421407D01*
X1508268Y1422157D01*
X1507895Y1422657D01*
X1507241Y1423032D01*
X1504721D01*
Y1415532D01*
X1507801D01*
X1508455Y1416032D01*
X1508828Y1416782D01*
X1509015Y1417657D01*
X1508828Y1418532D01*
X1508268Y1419282D01*
X1507615Y1419532D01*
X1504721D01*
G01X1473386Y1677520D02*
Y1436969D01*
G01D02*
X1562756D01*
G01X1473386Y1647993D02*
X1562756D01*
G01Y1677520D02*
X1473386D01*
G01X1483036Y-79278D02*
Y-62678D01*
X1492636D01*
Y-79278D01*
X1483036D01*
G01X1491522Y17443D02*
Y20643D01*
G01X1497722Y17443D02*
X1491522D01*
G01Y13443D02*
Y16643D01*
G01X1497722Y13443D02*
X1491522D01*
G01Y16643D02*
X1497722D01*
G01X1486682Y15302D02*
Y34988D01*
G01X1491522Y20643D02*
X1497722D01*
G01X1491522Y21443D02*
Y24643D01*
G01X1497722Y21443D02*
X1491522D01*
G01Y24643D02*
X1497722D01*
G01X1491522Y29443D02*
Y32643D01*
G01X1497722Y29443D02*
X1491522D01*
G01Y32643D02*
X1497722D01*
G01X1491522Y25443D02*
Y28643D01*
G01X1497722Y25443D02*
X1491522D01*
G01Y28643D02*
X1497722D01*
G01X1491522Y33443D02*
Y36643D01*
G01X1497722Y33443D02*
X1491522D01*
G01X1481497Y39844D02*
Y36644D01*
G01X1491522Y36643D02*
X1497722D01*
G01X1483300Y68107D02*
X1485522D01*
X1485987Y68260D01*
X1486297Y68567D01*
X1486400Y68950D01*
X1486297Y69333D01*
X1485987Y69640D01*
X1485522Y69793D01*
X1483300D01*
G01X1486400Y72050D02*
X1483300D01*
X1483920Y71590D01*
G01X1486400D02*
Y72510D01*
G01X1485780Y74307D02*
X1486142Y74537D01*
X1486348Y74843D01*
X1486400Y75188D01*
X1486348Y75495D01*
X1486090Y75802D01*
X1485780Y75993D01*
X1485470Y76032D01*
X1485108Y75955D01*
X1484850Y75687D01*
X1484747Y75418D01*
Y75073D01*
G01Y75418D02*
X1484592Y75648D01*
X1484333Y75840D01*
X1484023Y75917D01*
X1483713Y75840D01*
X1483455Y75648D01*
X1483300Y75303D01*
X1483352Y74958D01*
X1483558Y74613D01*
G01X1486400Y78250D02*
X1486348Y78518D01*
X1486193Y78825D01*
X1485935Y79017D01*
X1485573Y79093D01*
X1485212Y79017D01*
X1484902Y78787D01*
X1484747Y78442D01*
Y78058D01*
X1484643Y77828D01*
X1484385Y77637D01*
X1484023Y77560D01*
X1483662Y77675D01*
X1483403Y77943D01*
X1483300Y78250D01*
X1483403Y78557D01*
X1483662Y78825D01*
X1484023Y78940D01*
X1484385Y78863D01*
X1484643Y78672D01*
X1484747Y78442D01*
Y78058D01*
X1484902Y77713D01*
X1485212Y77483D01*
X1485573Y77407D01*
X1485935Y77483D01*
X1486193Y77675D01*
X1486348Y77982D01*
X1486400Y78250D01*
G01X1482128Y79047D02*
Y67523D01*
G01X1484887Y87299D02*
X1481687D01*
G01X1484887Y93499D02*
Y87299D01*
G01X1481687Y93499D02*
X1484887D01*
G01X1481687Y87299D02*
Y93499D01*
G01X1491859Y110172D02*
Y122172D01*
G01X1497859Y110172D02*
X1491859D01*
G01X1489242Y109424D02*
X1492442D01*
G01X1489242Y103224D02*
Y109424D01*
G01X1492442Y103224D02*
X1489242D01*
G01X1492442Y109424D02*
Y103224D01*
G01X1496936Y108095D02*
X1503136D01*
G01X1496936Y104895D02*
Y108095D01*
G01X1503136Y104895D02*
X1496936D01*
G01X1484442Y109424D02*
Y103224D01*
G01X1496936Y100895D02*
Y104095D01*
G01X1503136Y100895D02*
X1496936D01*
G01Y104095D02*
X1503136D01*
G01X1485242Y109424D02*
X1488442D01*
G01X1485242Y103224D02*
Y109424D01*
G01X1488442Y103224D02*
X1485242D01*
G01X1488442Y109424D02*
Y103224D01*
G01X1489458Y123508D02*
Y111734D01*
G01X1491859Y122172D02*
X1497859D01*
G01X1490467Y126223D02*
X1487267D01*
G01X1490467Y132423D02*
Y126223D01*
G01X1487267Y132423D02*
X1490467D01*
G01X1487267Y126223D02*
Y132423D01*
G01X1483267D02*
X1486467D01*
G01X1483267Y126223D02*
Y132423D01*
G01X1486467Y126223D02*
X1483267D01*
G01X1486467Y132423D02*
Y126223D01*
G01X1494521Y126228D02*
X1491321D01*
G01X1494521Y132428D02*
Y126228D01*
G01X1491321Y132428D02*
X1494521D01*
G01X1491321Y126228D02*
Y132428D01*
G01X1494700Y141337D02*
X1491500D01*
G01X1494700Y147537D02*
Y141337D01*
G01X1491500Y147537D02*
X1494700D01*
G01X1491500Y141337D02*
Y147537D01*
G01X1491365Y137238D02*
Y140438D01*
G01X1497565Y137238D02*
X1491365D01*
G01Y140438D02*
X1497565D01*
G01X1491365Y133238D02*
Y136438D01*
G01X1497565Y133238D02*
X1491365D01*
G01Y136438D02*
X1497565D01*
G01X1488746Y134995D02*
Y144395D01*
G01X1486369Y149950D02*
Y165304D01*
G01X1499047Y149950D02*
X1486369D01*
G01X1486566Y165304D02*
X1499047D01*
G01X1483183Y179600D02*
Y182700D01*
X1484103D01*
X1484410Y182545D01*
X1484640Y182183D01*
X1484717Y181770D01*
X1484640Y181357D01*
X1484448Y181047D01*
X1484103Y180892D01*
X1483183D01*
G01X1486207Y179600D02*
Y182700D01*
X1486973D01*
X1487280Y182545D01*
X1487510Y182338D01*
X1487702Y182028D01*
X1487855Y181667D01*
X1487893Y181150D01*
X1487855Y180633D01*
X1487702Y180272D01*
X1487510Y179962D01*
X1487280Y179755D01*
X1486973Y179600D01*
X1486207D01*
G01X1490073D02*
X1490150Y180272D01*
X1490265Y180840D01*
X1490418Y181357D01*
X1490610Y181925D01*
X1490917Y182700D01*
X1489383D01*
G01X1493250Y179600D02*
Y182700D01*
X1492790Y182080D01*
G01Y179600D02*
X1493710D01*
G01X1482891Y195583D02*
X1512450D01*
G01X1482891Y184087D02*
Y195583D01*
G01X1512450Y184087D02*
X1482891D01*
G01X1501867Y197645D02*
X1489867D01*
G01D02*
Y203645D01*
G01D02*
X1501867D01*
G01X1483044Y204506D02*
Y216506D01*
G01X1489044Y204506D02*
X1483044D01*
G01X1489044Y216506D02*
Y204506D01*
G01X1489844Y208306D02*
Y214506D01*
G01X1493044Y208306D02*
X1489844D01*
G01X1493044Y214506D02*
Y208306D01*
G01X1493620Y208464D02*
X1499820D01*
G01X1493620Y205264D02*
Y208464D01*
G01X1499820Y205264D02*
X1493620D01*
G01X1494650Y226801D02*
X1506854D01*
Y211497D01*
X1494650D01*
Y226801D01*
G01X1483044Y216506D02*
X1489044D01*
G01X1489844Y214506D02*
X1493044D01*
G01X1490210Y245521D02*
Y254969D01*
G01X1501046Y245521D02*
X1490210D01*
G01X1493786Y231334D02*
X1490586D01*
G01X1493786Y237534D02*
Y231334D01*
G01X1490586Y237534D02*
X1493786D01*
G01X1490586Y231334D02*
Y237534D01*
G01X1499313Y231446D02*
X1496113D01*
G01Y237646D02*
X1499313D01*
G01X1496113Y231446D02*
Y237646D01*
G01X1492012Y243678D02*
Y240478D01*
G01X1485812Y243678D02*
X1492012D01*
G01X1485812Y240478D02*
Y243678D01*
G01X1492012Y240478D02*
X1485812D01*
G01X1492791Y243678D02*
X1498991D01*
G01X1492791Y240478D02*
Y243678D01*
G01X1498991Y240478D02*
X1492791D01*
G01X1481842Y246771D02*
Y249971D01*
G01X1488042Y246771D02*
X1481842D01*
G01X1488042Y249971D02*
Y246771D01*
G01X1490904Y258227D02*
X1490597Y258279D01*
X1490329Y258485D01*
X1490099Y258795D01*
X1489946Y259157D01*
X1489869Y259570D01*
Y259984D01*
X1489946Y260397D01*
X1490099Y260759D01*
X1490329Y261069D01*
X1490597Y261275D01*
X1490904Y261327D01*
X1491211Y261275D01*
X1491479Y261069D01*
X1491709Y260759D01*
X1491862Y260397D01*
X1491939Y259984D01*
Y259570D01*
X1491862Y259157D01*
X1491709Y258795D01*
X1491479Y258485D01*
X1491211Y258279D01*
X1490904Y258227D01*
G01X1491211Y259054D02*
X1491671Y258227D01*
G01X1493276Y260810D02*
X1493506Y261120D01*
X1493774Y261275D01*
X1494081Y261327D01*
X1494464Y261224D01*
X1494732Y260965D01*
X1494809Y260655D01*
X1494771Y260345D01*
X1494617Y260087D01*
X1493851Y259570D01*
X1493506Y259209D01*
X1493276Y258692D01*
X1493199Y258227D01*
X1494809D01*
G01X1497104Y261327D02*
X1496797Y261224D01*
X1496567Y260965D01*
X1496414Y260655D01*
X1496299Y260242D01*
X1496261Y259777D01*
X1496299Y259312D01*
X1496414Y258899D01*
X1496567Y258589D01*
X1496797Y258330D01*
X1497104Y258227D01*
X1497411Y258330D01*
X1497641Y258589D01*
X1497794Y258899D01*
X1497909Y259312D01*
X1497947Y259777D01*
X1497909Y260242D01*
X1497794Y260655D01*
X1497641Y260965D01*
X1497411Y261224D01*
X1497104Y261327D01*
G01X1499552Y258589D02*
X1499821Y258330D01*
X1500127Y258227D01*
X1500434Y258330D01*
X1500702Y258640D01*
X1500894Y259105D01*
X1500971Y259570D01*
Y260139D01*
X1500894Y260604D01*
X1500702Y261017D01*
X1500472Y261224D01*
X1500204Y261327D01*
X1499897Y261224D01*
X1499667Y261017D01*
X1499514Y260707D01*
X1499437Y260294D01*
X1499514Y259932D01*
X1499706Y259570D01*
X1499936Y259364D01*
X1500204Y259312D01*
X1500511Y259415D01*
X1500741Y259674D01*
X1500971Y260139D01*
G01X1495628Y253245D02*
X1497628Y254969D01*
G01X1493628D02*
X1495628Y253245D01*
G01X1490210Y254969D02*
X1493628D01*
G01X1481842Y249971D02*
X1488042D01*
G01Y253971D02*
Y250771D01*
G01X1481842Y253971D02*
X1488042D01*
G01X1481842Y250771D02*
Y253971D01*
G01X1488042Y250771D02*
X1481842D01*
G01X1488446Y321100D02*
Y324300D01*
G01X1494646Y321100D02*
X1488446D01*
G01X1494646Y324300D02*
Y321100D01*
G01X1488446Y324300D02*
X1494646D01*
G01X1484646Y328800D02*
Y325600D01*
G01Y324300D02*
Y321100D01*
G01X1488446Y325600D02*
Y328800D01*
G01X1494646Y325600D02*
X1488446D01*
G01X1494646Y328800D02*
Y325600D01*
G01X1488446Y330100D02*
Y333300D01*
G01X1494646Y330100D02*
X1488446D01*
G01X1494646Y333300D02*
Y330100D01*
G01X1488446Y333300D02*
X1494646D01*
G01X1488446Y339100D02*
Y342300D01*
G01X1494646Y339100D02*
X1488446D01*
G01X1494646Y342300D02*
Y339100D01*
G01X1488446Y342300D02*
X1494646D01*
G01X1484646Y346800D02*
Y343600D01*
G01Y342300D02*
Y339100D01*
G01Y333300D02*
Y330100D01*
G01X1488446Y328800D02*
X1494646D01*
G01X1488446Y343600D02*
Y346800D01*
G01X1494646Y343600D02*
X1488446D01*
G01X1494646Y346800D02*
Y343600D01*
G01X1488446Y348100D02*
Y351300D01*
G01X1494646Y348100D02*
X1488446D01*
G01X1494646Y351300D02*
Y348100D01*
G01X1488446Y351300D02*
X1494646D01*
G01Y360300D02*
Y357100D01*
G01X1488446Y360300D02*
X1494646D01*
G01X1488446Y357100D02*
Y360300D01*
G01X1494646Y357100D02*
X1488446D01*
G01X1494646Y355800D02*
Y352600D01*
G01X1488446Y355800D02*
X1494646D01*
G01X1488446Y352600D02*
Y355800D01*
G01X1494646Y352600D02*
X1488446D01*
G01X1484646Y360300D02*
Y357100D01*
G01Y355800D02*
Y352600D01*
G01Y351300D02*
Y348100D01*
G01X1488446Y346800D02*
X1494646D01*
G01X1488413Y366976D02*
Y370176D01*
G01X1494613Y366976D02*
X1488413D01*
G01X1494613Y370176D02*
Y366976D01*
G01X1488413Y370176D02*
X1494613D01*
G01X1496895Y450181D02*
X1500095D01*
G01X1496895Y443981D02*
Y450181D01*
G01X1500095Y443981D02*
X1496895D01*
G01X1500095Y450981D02*
X1496895D01*
G01Y457181D02*
X1500095D01*
G01X1496895Y450981D02*
Y457181D01*
G01X1486600Y687230D02*
Y684030D01*
G01Y683230D02*
Y680030D01*
G01Y679230D02*
Y676030D01*
G01Y699230D02*
Y696030D01*
G01Y691230D02*
Y688030D01*
G01Y695230D02*
Y692030D01*
G01X1488400Y704900D02*
Y708100D01*
G01X1494600Y704900D02*
X1488400D01*
G01X1494600Y708100D02*
Y704900D01*
G01X1488400Y708100D02*
X1494600D01*
G01X1486600D02*
Y704900D01*
G01X1487100Y729100D02*
Y725900D01*
G01Y737100D02*
Y733900D01*
G01Y733100D02*
Y729900D01*
G01Y725100D02*
Y721900D01*
G01X1486600Y752100D02*
Y748900D01*
G01X1487100Y745100D02*
Y741900D01*
G01Y741100D02*
Y737900D01*
G01X1488400Y748900D02*
Y752100D01*
G01X1494600Y748900D02*
X1488400D01*
G01X1494600Y752100D02*
Y748900D01*
G01X1488400Y752100D02*
X1494600D01*
G01X1490100Y796900D02*
X1486900D01*
G01X1490100Y803100D02*
Y796900D01*
G01X1486900D02*
Y803100D01*
G01X1497400Y790400D02*
Y793600D01*
G01X1503600Y790400D02*
X1497400D01*
G01Y793600D02*
X1503600D01*
G01X1486900Y803100D02*
X1490100D01*
G01Y840900D02*
X1486900D01*
G01X1490100Y847100D02*
Y840900D01*
G01X1486900Y847100D02*
X1490100D01*
G01X1486900Y840900D02*
Y847100D01*
G01X1497400Y834400D02*
Y837600D01*
G01X1503600Y834400D02*
X1497400D01*
G01Y837600D02*
X1503600D01*
G01X1497183Y904540D02*
X1507383D01*
G01X1497183Y899940D02*
Y904540D01*
G01X1507383Y899940D02*
X1497183D01*
G01X1495683Y908840D02*
X1501883D01*
G01X1495683Y905640D02*
Y908840D01*
G01X1501883Y905640D02*
X1495683D01*
G01X1494313Y919335D02*
X1498295D01*
G01X1494313Y923317D02*
Y919335D01*
G01Y959099D02*
Y955117D01*
G01X1498295Y959099D02*
X1494313D01*
G01X1497496Y990431D02*
Y996631D01*
G01X1500696Y990431D02*
X1497496D01*
G01X1489496Y987631D02*
X1492696D01*
G01X1489496Y981431D02*
Y987631D01*
G01X1492696Y981431D02*
X1489496D01*
G01X1492696Y987631D02*
Y981431D01*
G01X1485496Y987631D02*
X1488696D01*
G01X1485496Y981431D02*
Y987631D01*
G01X1488696Y981431D02*
X1485496D01*
G01X1488696Y987631D02*
Y981431D01*
G01X1493496Y987631D02*
X1496696D01*
G01X1493496Y981431D02*
Y987631D01*
G01X1496696Y981431D02*
X1493496D01*
G01X1496696Y987631D02*
Y981431D01*
G01X1497496Y987631D02*
X1500696D01*
G01X1497496Y981431D02*
Y987631D01*
G01X1500696Y981431D02*
X1497496D01*
G01X1489496Y990431D02*
Y996631D01*
G01X1492696Y990431D02*
X1489496D01*
G01X1492696Y996631D02*
Y990431D01*
G01X1485496D02*
Y996631D01*
G01X1488696Y990431D02*
X1485496D01*
G01X1488696Y996631D02*
Y990431D01*
G01X1493496D02*
Y996631D01*
G01X1496696Y990431D02*
X1493496D01*
G01X1496696Y996631D02*
Y990431D01*
G01X1481496Y987631D02*
X1484696D01*
G01X1481496Y981431D02*
Y987631D01*
G01X1484696Y981431D02*
X1481496D01*
G01X1484696Y987631D02*
Y981431D01*
G01X1481496Y990431D02*
Y996631D01*
G01X1484696Y990431D02*
X1481496D01*
G01X1484696Y996631D02*
Y990431D01*
G01X1496239Y1008071D02*
Y1012671D01*
G01X1506439Y1008071D02*
X1496239D01*
G01X1482624Y1007653D02*
Y1003053D01*
G01X1486630Y1009265D02*
Y1019465D01*
G01X1491230Y1009265D02*
X1486630D01*
G01X1491230Y1019465D02*
Y1009265D01*
G01X1497496Y996631D02*
X1500696D01*
G01X1489496D02*
X1492696D01*
G01X1485496D02*
X1488696D01*
G01X1493496D02*
X1496696D01*
G01X1481496D02*
X1484696D01*
G01X1483818Y1022862D02*
Y1012662D01*
G01X1496239Y1025271D02*
X1506439D01*
G01X1496239Y1020671D02*
Y1025271D01*
G01X1506439Y1020671D02*
X1496239D01*
G01Y1012671D02*
X1506439D01*
G01X1508060Y1026071D02*
X1495180D01*
G01Y1032471D02*
Y1026071D01*
G01Y1019871D02*
X1508060D01*
G01Y1013471D02*
X1495180D01*
G01Y1019871D02*
Y1013471D01*
G01X1486630Y1021865D02*
Y1032065D01*
G01X1491230Y1021865D02*
X1486630D01*
G01X1491230Y1032065D02*
Y1021865D01*
G01X1486630Y1019465D02*
X1491230D01*
G01X1483618Y1028533D02*
Y1025333D01*
G01X1495180Y1032471D02*
X1508060D01*
G01X1486630Y1032065D02*
X1491230D01*
G01X1494793Y1105408D02*
Y1100808D01*
G01X1484593Y1105408D02*
X1494793D01*
G01X1484593Y1100808D02*
Y1105408D01*
G01X1494793Y1100808D02*
X1484593D01*
G01X1496414Y1106208D02*
X1483534D01*
G01X1496414Y1112608D02*
Y1106208D01*
G01X1483534Y1112608D02*
Y1106208D01*
G01X1497264Y1107208D02*
X1500464D01*
G01X1497264Y1101008D02*
Y1107208D01*
G01X1500464Y1101008D02*
X1497264D01*
G01X1494793Y1118008D02*
Y1113408D01*
G01X1484593Y1118008D02*
X1494793D01*
G01X1484593Y1113408D02*
Y1118008D01*
G01X1494793Y1113408D02*
X1484593D01*
G01X1497214Y1120608D02*
Y1125208D01*
G01X1507414Y1120608D02*
X1497214D01*
G01Y1108008D02*
Y1112608D01*
G01X1507414Y1108008D02*
X1497214D01*
G01Y1112608D02*
X1507414D01*
G01X1496414Y1118808D02*
X1483534D01*
G01X1496414Y1125208D02*
Y1118808D01*
G01X1483534Y1125208D02*
Y1118808D01*
G01Y1112608D02*
X1496414D01*
G01X1497264Y1119808D02*
X1500464D01*
G01X1497264Y1113608D02*
Y1119808D01*
G01X1500464Y1113608D02*
X1497264D01*
G01X1497214Y1125208D02*
X1507414D01*
G01X1494793Y1130608D02*
Y1126008D01*
G01X1484593Y1130608D02*
X1494793D01*
G01X1484593Y1126008D02*
Y1130608D01*
G01X1494793Y1126008D02*
X1484593D01*
G01X1497214Y1133208D02*
Y1137808D01*
G01X1507414Y1133208D02*
X1497214D01*
G01Y1137808D02*
X1507414D01*
G01X1494793Y1143208D02*
Y1138608D01*
G01X1484593D02*
Y1143208D01*
G01X1494793Y1138608D02*
X1484593D01*
G01X1483534Y1125208D02*
X1496414D01*
G01X1483534Y1137808D02*
X1496414D01*
G01Y1131408D02*
X1483534D01*
G01X1496414Y1137808D02*
Y1131408D01*
G01X1483534Y1137808D02*
Y1131408D01*
G01X1497264Y1132408D02*
X1500464D01*
G01X1497264Y1126208D02*
Y1132408D01*
G01X1500464Y1126208D02*
X1497264D01*
G01Y1138808D02*
Y1145008D01*
G01X1500464Y1138808D02*
X1497264D01*
G01X1484593Y1143208D02*
X1494793D01*
G01X1497214Y1145808D02*
Y1150408D01*
G01X1507414Y1145808D02*
X1497214D01*
G01Y1150408D02*
X1507414D01*
G01X1494793Y1155808D02*
Y1151208D01*
G01X1484593Y1155808D02*
X1494793D01*
G01X1484593Y1151208D02*
Y1155808D01*
G01X1494793Y1151208D02*
X1484593D01*
G01X1483534Y1150408D02*
X1496414D01*
G01Y1144008D02*
X1483534D01*
G01X1496414Y1150408D02*
Y1144008D01*
G01X1483534Y1150408D02*
Y1144008D01*
G01X1497264Y1145008D02*
X1500464D01*
G01X1497264Y1151408D02*
Y1157608D01*
G01X1500464Y1151408D02*
X1497264D01*
G01X1494793Y1168408D02*
Y1163808D01*
G01X1484593Y1168408D02*
X1494793D01*
G01X1484593Y1163808D02*
Y1168408D01*
G01X1494793Y1163808D02*
X1484593D01*
G01X1497214Y1171008D02*
Y1175608D01*
G01X1507414Y1171008D02*
X1497214D01*
G01Y1158408D02*
Y1163008D01*
G01X1507414Y1158408D02*
X1497214D01*
G01Y1163008D02*
X1507414D01*
G01X1483534Y1175608D02*
Y1169208D01*
G01X1496414Y1175608D02*
Y1169208D01*
G01D02*
X1483534D01*
G01Y1163008D02*
Y1156608D01*
G01X1496414Y1163008D02*
Y1156608D01*
G01D02*
X1483534D01*
G01Y1163008D02*
X1496414D01*
G01X1497264Y1170208D02*
X1500464D01*
G01X1497264Y1164008D02*
Y1170208D01*
G01X1500464Y1164008D02*
X1497264D01*
G01Y1157608D02*
X1500464D01*
G01X1497214Y1175608D02*
X1507414D01*
G01X1494793Y1181008D02*
Y1176408D01*
G01X1484593Y1181008D02*
X1494793D01*
G01X1484593Y1176408D02*
Y1181008D01*
G01X1494793Y1176408D02*
X1484593D01*
G01X1497214Y1183608D02*
Y1188208D01*
G01X1507414Y1183608D02*
X1497214D01*
G01Y1188208D02*
X1507414D01*
G01X1483534Y1175608D02*
X1496414D01*
G01X1483534Y1188208D02*
Y1181808D01*
G01X1496414Y1188208D02*
Y1181808D01*
G01D02*
X1483534D01*
G01Y1188208D02*
X1496414D01*
G01X1497264Y1182808D02*
X1500464D01*
G01X1497264Y1176608D02*
Y1182808D01*
G01X1500464Y1176608D02*
X1497264D01*
G01X1488628Y1206662D02*
X1490890Y1204400D01*
G01X1484244Y1202278D02*
X1488628Y1206662D01*
G01X1486506Y1200016D02*
X1484244Y1202278D01*
G01X1490890Y1204400D02*
X1486506Y1200016D01*
G01X1483678Y1202844D02*
X1481416Y1205106D01*
G01X1488062Y1207228D02*
X1483678Y1202844D01*
G01X1481416Y1205106D02*
X1485800Y1209490D01*
G01X1489905Y1220549D02*
X1494289Y1224933D01*
G01X1492167Y1218287D02*
X1489905Y1220549D01*
G01X1496551Y1222671D02*
X1492167Y1218287D01*
G01X1494997Y1215459D02*
X1492735Y1217721D01*
G01X1499381Y1219843D02*
X1494997Y1215459D01*
G01X1492735Y1217721D02*
X1497119Y1222105D01*
G01X1495563Y1214892D02*
X1499947Y1219276D01*
G01X1497825Y1212630D02*
X1495563Y1214892D01*
G01X1489340Y1221115D02*
X1487078Y1223377D01*
G01X1493724Y1225499D02*
X1489340Y1221115D01*
G01X1482971Y1212319D02*
X1485233Y1210057D01*
G01X1485800Y1209490D02*
X1488062Y1207228D01*
G01X1494289Y1224933D02*
X1496551Y1222671D01*
G01X1497119Y1222105D02*
X1499381Y1219843D01*
G01X1491462Y1227761D02*
X1493724Y1225499D01*
G01X1487078Y1223377D02*
X1491462Y1227761D01*
G01X1486513Y1223943D02*
X1484251Y1226205D01*
G01X1490897Y1228327D02*
X1486513Y1223943D01*
G01X1488635Y1230589D02*
X1490897Y1228327D01*
G01X1484251Y1226205D02*
X1488635Y1230589D01*
G01X1482461Y1228126D02*
Y1221926D01*
G01X1512807Y-21400D02*
Y-18300D01*
X1513573D01*
X1513880Y-18455D01*
X1514110Y-18662D01*
X1514302Y-18972D01*
X1514455Y-19333D01*
X1514493Y-19850D01*
X1514455Y-20367D01*
X1514302Y-20728D01*
X1514110Y-21038D01*
X1513880Y-21245D01*
X1513573Y-21400D01*
X1512807D01*
G01X1517517D02*
X1515983D01*
Y-18300D01*
X1517517D01*
G01X1516903Y-19798D02*
X1515983D01*
G01X1519850Y-21400D02*
Y-18300D01*
X1519390Y-18920D01*
G01Y-21400D02*
X1520310D01*
G01X1523410D02*
Y-18300D01*
X1521992Y-20522D01*
X1523908D01*
G01X1526050Y-18300D02*
Y-21400D01*
G01X1525168Y-18300D02*
X1526932D01*
G01X1528000Y-22433D02*
X1530300D01*
G01X1532250Y-21400D02*
Y-18300D01*
X1531790Y-18920D01*
G01Y-21400D02*
X1532710D01*
G01X1497722Y20643D02*
Y17443D01*
G01Y16643D02*
Y13443D01*
G01Y24643D02*
Y21443D01*
G01Y32643D02*
Y29443D01*
G01Y28643D02*
Y25443D01*
G01Y36643D02*
Y33443D01*
G01X1512263Y57756D02*
Y111665D01*
G01X1512559Y58150D02*
Y111665D01*
G01X1507816Y57972D02*
X1508126Y58164D01*
X1508333Y58394D01*
X1508436Y58662D01*
X1508333Y58969D01*
X1508126Y59199D01*
X1507816Y59429D01*
X1507403Y59506D01*
X1505336D01*
G01X1508436Y62299D02*
X1505336D01*
X1507558Y60881D01*
Y62797D01*
G01X1507816Y64096D02*
X1508178Y64326D01*
X1508384Y64632D01*
X1508436Y64977D01*
X1508384Y65284D01*
X1508126Y65591D01*
X1507816Y65782D01*
X1507506Y65821D01*
X1507144Y65744D01*
X1506886Y65476D01*
X1506783Y65207D01*
Y64862D01*
G01Y65207D02*
X1506628Y65437D01*
X1506369Y65629D01*
X1506059Y65706D01*
X1505749Y65629D01*
X1505491Y65437D01*
X1505336Y65092D01*
X1505388Y64747D01*
X1505594Y64402D01*
G01X1518644Y57756D02*
X1512263D01*
G01X1518239Y58150D02*
X1512559D01*
G01X1501120Y96067D02*
Y99267D01*
G01X1507320Y96067D02*
X1501120D01*
G01X1507320Y99267D02*
Y96067D01*
G01X1501120Y99267D02*
X1507320D01*
G01X1512559Y118848D02*
Y114048D01*
G01X1512263Y118848D02*
Y114048D01*
G01X1497859Y122172D02*
Y110172D01*
G01X1503136Y108095D02*
Y104895D01*
G01X1503993Y108086D02*
X1507193D01*
G01X1503993Y101886D02*
Y108086D01*
G01X1507193Y101886D02*
X1503993D01*
G01X1507193Y108086D02*
Y101886D01*
G01X1503136Y104095D02*
Y100895D01*
G01X1512559Y132607D02*
Y128340D01*
G01X1512263Y132607D02*
Y128340D01*
G01Y125781D02*
Y121219D01*
G01X1512559Y125781D02*
Y121219D01*
G01Y152756D02*
Y135549D01*
G01X1512263Y153150D02*
Y135549D01*
G01X1497565Y140438D02*
Y137238D01*
G01Y136438D02*
Y133238D01*
G01X1497911Y148437D02*
X1501111D01*
G01X1497911Y142237D02*
Y148437D01*
G01X1501111Y142237D02*
X1497911D01*
G01X1501111Y148437D02*
Y142237D01*
G01X1500100Y152907D02*
X1502322D01*
X1502787Y153060D01*
X1503097Y153367D01*
X1503200Y153750D01*
X1503097Y154133D01*
X1502787Y154440D01*
X1502322Y154593D01*
X1500100D01*
G01X1502580Y156007D02*
X1502942Y156237D01*
X1503148Y156543D01*
X1503200Y156888D01*
X1503148Y157195D01*
X1502890Y157502D01*
X1502580Y157693D01*
X1502270Y157732D01*
X1501908Y157655D01*
X1501650Y157387D01*
X1501547Y157118D01*
Y156773D01*
G01Y157118D02*
X1501392Y157348D01*
X1501133Y157540D01*
X1500823Y157617D01*
X1500513Y157540D01*
X1500255Y157348D01*
X1500100Y157003D01*
X1500152Y156658D01*
X1500358Y156313D01*
G01X1503200Y159873D02*
X1502528Y159950D01*
X1501960Y160065D01*
X1501443Y160218D01*
X1500875Y160410D01*
X1500100Y160717D01*
Y159183D01*
G01X1503200Y163510D02*
X1500100D01*
X1502322Y162092D01*
Y164008D01*
G01X1499047Y165304D02*
Y149950D01*
G01X1512263Y153150D02*
X1518644D01*
G01X1512559Y152756D02*
X1518239D01*
G01X1515990Y189535D02*
X1513564D01*
G01X1512450Y195583D02*
Y184087D01*
G01X1501867Y203645D02*
Y197645D01*
G01X1499820Y208464D02*
Y205264D01*
G01X1512995Y214832D02*
X1509895D01*
Y215752D01*
X1510050Y216059D01*
X1510412Y216289D01*
X1510825Y216366D01*
X1511238Y216289D01*
X1511548Y216097D01*
X1511703Y215752D01*
Y214832D01*
G01X1509895Y217856D02*
X1512117D01*
X1512582Y218009D01*
X1512892Y218316D01*
X1512995Y218699D01*
X1512892Y219082D01*
X1512582Y219389D01*
X1512117Y219542D01*
X1509895D01*
G01X1511703Y221071D02*
X1511342Y221339D01*
X1511135Y221569D01*
X1511032Y221876D01*
X1511135Y222144D01*
X1511342Y222336D01*
X1511652Y222489D01*
X1512013Y222527D01*
X1512323Y222489D01*
X1512633Y222336D01*
X1512892Y222106D01*
X1512995Y221837D01*
X1512892Y221531D01*
X1512582Y221262D01*
X1512117Y221109D01*
X1511600Y221071D01*
X1510928Y221147D01*
X1510567Y221262D01*
X1510205Y221454D01*
X1509947Y221722D01*
X1509895Y221991D01*
X1509998Y222259D01*
X1510257Y222451D01*
G01X1512530Y224056D02*
X1512788Y224286D01*
X1512943Y224554D01*
X1512995Y224899D01*
X1512892Y225244D01*
X1512685Y225512D01*
X1512323Y225704D01*
X1511910Y225742D01*
X1511497Y225666D01*
X1511238Y225474D01*
X1511032Y225206D01*
X1510980Y224937D01*
X1511032Y224669D01*
X1511238Y224324D01*
X1509895Y224439D01*
Y225474D01*
G01X1501046Y254969D02*
Y245521D01*
G01X1499313Y237646D02*
Y231446D01*
G01X1511423Y231459D02*
X1508223D01*
G01X1511423Y237659D02*
Y231459D01*
G01X1508223Y237659D02*
X1511423D01*
G01X1508223Y231459D02*
Y237659D01*
G01X1498991Y243678D02*
Y240478D01*
G01X1503188Y231434D02*
X1499988D01*
G01X1503188Y237634D02*
Y231434D01*
G01X1499988Y237634D02*
X1503188D01*
G01X1499988Y231434D02*
Y237634D01*
G01X1504223Y237659D02*
X1507423D01*
G01X1504223Y231459D02*
Y237659D01*
G01X1507423Y231459D02*
X1504223D01*
G01X1507423Y237659D02*
Y231459D01*
G01X1502849Y240081D02*
Y243281D01*
G01X1509049Y240081D02*
X1502849D01*
G01X1509049Y243281D02*
Y240081D01*
G01X1502849Y243281D02*
X1509049D01*
G01X1497628Y254969D02*
X1501046D01*
G01X1508653Y252199D02*
Y248999D01*
G01X1502453Y252199D02*
X1508653D01*
G01X1502453Y248999D02*
Y252199D01*
G01X1508653Y248999D02*
X1502453D01*
G01X1510181Y322290D02*
X1524781D01*
G01X1510181Y353392D02*
Y322290D01*
G01X1510107Y358300D02*
Y356078D01*
X1510260Y355613D01*
X1510567Y355303D01*
X1510950Y355200D01*
X1511333Y355303D01*
X1511640Y355613D01*
X1511793Y356078D01*
Y358300D01*
G01X1514050Y355200D02*
Y358300D01*
X1513590Y357680D01*
G01Y355200D02*
X1514510D01*
G01X1517610D02*
Y358300D01*
X1516192Y356078D01*
X1518108D01*
G01X1519522Y357783D02*
X1519752Y358093D01*
X1520020Y358248D01*
X1520327Y358300D01*
X1520710Y358197D01*
X1520978Y357938D01*
X1521055Y357628D01*
X1521017Y357318D01*
X1520863Y357060D01*
X1520097Y356543D01*
X1519752Y356182D01*
X1519522Y355665D01*
X1519445Y355200D01*
X1521055D01*
G01X1512430Y353392D02*
X1510181D01*
G01X1517481Y348341D02*
X1512430Y353392D01*
G01X1500095Y450181D02*
Y443981D01*
G01Y457181D02*
Y450981D01*
G01X1501756Y447404D02*
Y462758D01*
G01X1514434Y447404D02*
X1501756D01*
G01X1501548Y466795D02*
Y464573D01*
X1501701Y464108D01*
X1502008Y463798D01*
X1502391Y463695D01*
X1502774Y463798D01*
X1503081Y464108D01*
X1503234Y464573D01*
Y466795D01*
G01X1504648Y464315D02*
X1504878Y463953D01*
X1505184Y463747D01*
X1505529Y463695D01*
X1505836Y463747D01*
X1506143Y464005D01*
X1506334Y464315D01*
X1506373Y464625D01*
X1506296Y464987D01*
X1506028Y465245D01*
X1505759Y465348D01*
X1505414D01*
G01X1505759D02*
X1505989Y465503D01*
X1506181Y465762D01*
X1506258Y466072D01*
X1506181Y466382D01*
X1505989Y466640D01*
X1505644Y466795D01*
X1505299Y466743D01*
X1504954Y466537D01*
G01X1507939Y464057D02*
X1508208Y463798D01*
X1508514Y463695D01*
X1508821Y463798D01*
X1509089Y464108D01*
X1509281Y464573D01*
X1509358Y465038D01*
Y465607D01*
X1509281Y466072D01*
X1509089Y466485D01*
X1508859Y466692D01*
X1508591Y466795D01*
X1508284Y466692D01*
X1508054Y466485D01*
X1507901Y466175D01*
X1507824Y465762D01*
X1507901Y465400D01*
X1508093Y465038D01*
X1508323Y464832D01*
X1508591Y464780D01*
X1508898Y464883D01*
X1509128Y465142D01*
X1509358Y465607D01*
G01X1501953Y462758D02*
X1514434D01*
G01X1512621Y537250D02*
Y543450D01*
G01X1515821Y537250D02*
X1512621D01*
G01X1508631Y537291D02*
Y543491D01*
G01X1511831Y537291D02*
X1508631D01*
G01X1511831Y543491D02*
Y537291D01*
G01X1512621Y543450D02*
X1515821D01*
G01X1508631Y543491D02*
X1511831D01*
G01X1524312Y645047D02*
X1508712D01*
X1524312Y654017D01*
X1508712D01*
G01Y665092D02*
Y669772D01*
G01Y667432D02*
X1524312D01*
G01Y665092D02*
Y669772D01*
G01X1510012Y689622D02*
X1509232Y688452D01*
X1508712Y687087D01*
Y685527D01*
X1509492Y683772D01*
X1510792Y682407D01*
X1512352Y681432D01*
X1514952Y680652D01*
X1517292Y680457D01*
X1519632Y680847D01*
X1521192Y681432D01*
X1522752Y682602D01*
X1523792Y683967D01*
X1524312Y685332D01*
Y686697D01*
X1523792Y688062D01*
X1523012Y689232D01*
X1521972Y690207D01*
G01X1517812Y699527D02*
X1515992Y700892D01*
X1514952Y702062D01*
X1514432Y703622D01*
X1514952Y704987D01*
X1515992Y705962D01*
X1517552Y706742D01*
X1519372Y706937D01*
X1520932Y706742D01*
X1522492Y705962D01*
X1523792Y704792D01*
X1524312Y703427D01*
X1523792Y701867D01*
X1522232Y700502D01*
X1519892Y699722D01*
X1517292Y699527D01*
X1513912Y699917D01*
X1512092Y700502D01*
X1510272Y701477D01*
X1508972Y702842D01*
X1508712Y704207D01*
X1509232Y705572D01*
X1510532Y706547D01*
G01X1497900Y763400D02*
Y766600D01*
G01X1504100Y763400D02*
X1497900D01*
G01X1504100Y766600D02*
Y763400D01*
G01X1497900Y779400D02*
Y782600D01*
G01X1504100Y779400D02*
X1497900D01*
G01X1504100Y782600D02*
Y779400D01*
G01X1497900Y782600D02*
X1504100D01*
G01Y770600D02*
Y767400D01*
G01X1497900Y770600D02*
X1504100D01*
G01X1497900Y767400D02*
Y770600D01*
G01X1504100Y767400D02*
X1497900D01*
G01Y766600D02*
X1504100D01*
G01X1497900Y771400D02*
Y774600D01*
G01X1504100Y771400D02*
X1497900D01*
G01X1504100Y774600D02*
Y771400D01*
G01X1497900Y774600D02*
X1504100D01*
G01X1497900Y775400D02*
Y778600D01*
G01X1504100Y775400D02*
X1497900D01*
G01X1504100Y778600D02*
Y775400D01*
G01X1497900Y778600D02*
X1504100D01*
G01X1505400Y790400D02*
Y793600D01*
G01X1511600Y790400D02*
X1505400D01*
G01X1511600Y793600D02*
Y790400D01*
G01X1505400Y793600D02*
X1511600D01*
G01X1503600D02*
Y790400D01*
G01X1497900Y783400D02*
Y786600D01*
G01X1504100Y783400D02*
X1497900D01*
G01X1504100Y786600D02*
Y783400D01*
G01X1497900Y786600D02*
X1504100D01*
G01X1497900Y807400D02*
Y810600D01*
G01X1504100Y807400D02*
X1497900D01*
G01X1504100Y810600D02*
Y807400D01*
G01X1497900Y810600D02*
X1504100D01*
G01Y814600D02*
Y811400D01*
G01X1497900Y814600D02*
X1504100D01*
G01X1497900Y811400D02*
Y814600D01*
G01X1504100Y811400D02*
X1497900D01*
G01Y815400D02*
Y818600D01*
G01X1504100Y815400D02*
X1497900D01*
G01X1504100Y818600D02*
Y815400D01*
G01X1497900Y818600D02*
X1504100D01*
G01X1497900Y823400D02*
Y826600D01*
G01X1504100Y823400D02*
X1497900D01*
G01X1504100Y826600D02*
Y823400D01*
G01X1497900Y826600D02*
X1504100D01*
G01X1497900Y819400D02*
Y822600D01*
G01X1504100Y819400D02*
X1497900D01*
G01X1504100Y822600D02*
Y819400D01*
G01X1497900Y822600D02*
X1504100D01*
G01X1497900Y827400D02*
Y830600D01*
G01X1504100Y827400D02*
X1497900D01*
G01X1504100Y830600D02*
Y827400D01*
G01X1497900Y830600D02*
X1504100D01*
G01X1505400Y834400D02*
Y837600D01*
G01X1511600Y834400D02*
X1505400D01*
G01X1511600Y837600D02*
Y834400D01*
G01X1505400Y837600D02*
X1511600D01*
G01X1503600D02*
Y834400D01*
G01X1498220Y899780D02*
Y857677D01*
G01X1507150Y880200D02*
Y881595D01*
X1506383Y883300D01*
G01X1507917D02*
X1507150Y881595D01*
G01X1509407Y880820D02*
X1509637Y880458D01*
X1509943Y880252D01*
X1510288Y880200D01*
X1510595Y880252D01*
X1510902Y880510D01*
X1511093Y880820D01*
X1511132Y881130D01*
X1511055Y881492D01*
X1510787Y881750D01*
X1510518Y881853D01*
X1510173D01*
G01X1510518D02*
X1510748Y882008D01*
X1510940Y882267D01*
X1511017Y882577D01*
X1510940Y882887D01*
X1510748Y883145D01*
X1510403Y883300D01*
X1510058Y883248D01*
X1509713Y883042D01*
G01X1499334Y885179D02*
Y897779D01*
G01X1514734Y885179D02*
X1499334D01*
G01X1507383Y904540D02*
Y899940D01*
G01X1498220Y917913D02*
Y910006D01*
G01Y905325D02*
Y904029D01*
G01X1502683Y905640D02*
Y908840D01*
G01X1508883Y905640D02*
X1502683D01*
G01X1508883Y908840D02*
Y905640D01*
G01X1502683Y908840D02*
X1508883D01*
G01X1501883D02*
Y905640D01*
G01X1499334Y897779D02*
X1514734D01*
G01X1511863Y976040D02*
X1522063D01*
G01X1511863Y971440D02*
Y976040D01*
G01X1522063Y971440D02*
X1511863D01*
G01X1501496Y987631D02*
X1504696D01*
G01X1501496Y981431D02*
Y987631D01*
G01X1504696Y981431D02*
X1501496D01*
G01X1504696Y987631D02*
Y981431D01*
G01X1513496Y987631D02*
X1516696D01*
G01X1513496Y981431D02*
Y987631D01*
G01X1516696Y981431D02*
X1513496D01*
G01X1505496Y987631D02*
X1508696D01*
G01X1505496Y981431D02*
Y987631D01*
G01X1508696Y981431D02*
X1505496D01*
G01X1508696Y987631D02*
Y981431D01*
G01X1509496Y987631D02*
X1512696D01*
G01X1509496Y981431D02*
Y987631D01*
G01X1512696Y981431D02*
X1509496D01*
G01X1512696Y987631D02*
Y981431D01*
G01X1501496Y990431D02*
Y996631D01*
G01X1504696Y990431D02*
X1501496D01*
G01X1504696Y996631D02*
Y990431D01*
G01X1513496D02*
Y996631D01*
G01X1516696Y990431D02*
X1513496D01*
G01X1505496D02*
Y996631D01*
G01X1508696Y990431D02*
X1505496D01*
G01X1508696Y996631D02*
Y990431D01*
G01X1509496D02*
Y996631D01*
G01X1512696Y990431D02*
X1509496D01*
G01X1512696Y996631D02*
Y990431D01*
G01X1500696Y996631D02*
Y990431D01*
G01Y987631D02*
Y981431D01*
G01X1506439Y1012671D02*
Y1008071D01*
G01X1508910Y1008271D02*
Y1014471D01*
G01X1512110Y1008271D02*
X1508910D01*
G01X1512110Y1014471D02*
Y1008271D01*
G01X1501496Y996631D02*
X1504696D01*
G01X1513496D02*
X1516696D01*
G01X1505496D02*
X1508696D01*
G01X1509496D02*
X1512696D01*
G01X1506439Y1025271D02*
Y1020671D01*
G01X1508860Y1015271D02*
Y1019871D01*
G01X1519060Y1015271D02*
X1508860D01*
G01Y1019871D02*
X1519060D01*
G01X1508060Y1032471D02*
Y1026071D01*
G01Y1019871D02*
Y1013471D01*
G01X1508910Y1020871D02*
Y1027071D01*
G01X1512110Y1020871D02*
X1508910D01*
G01X1512110Y1027071D02*
Y1020871D01*
G01X1508910Y1014471D02*
X1512110D01*
G01X1508860Y1027871D02*
Y1032471D01*
G01X1519060Y1027871D02*
X1508860D01*
G01Y1032471D02*
X1519060D01*
G01X1508910Y1027071D02*
X1512110D01*
G01X1512598Y1071456D02*
X1699606D01*
G01X1512598Y1258464D02*
Y1071456D01*
G01X1500464Y1107208D02*
Y1101008D01*
G01X1507414Y1125208D02*
Y1120608D01*
G01Y1112608D02*
Y1108008D01*
G01X1500464Y1119808D02*
Y1113608D01*
G01X1507414Y1137808D02*
Y1133208D01*
G01X1500464Y1132408D02*
Y1126208D01*
G01Y1145008D02*
Y1138808D01*
G01X1507414Y1150408D02*
Y1145808D01*
G01X1500464Y1157608D02*
Y1151408D01*
G01X1507414Y1175608D02*
Y1171008D01*
G01Y1163008D02*
Y1158408D01*
G01X1500464Y1170208D02*
Y1164008D01*
G01X1507414Y1188208D02*
Y1183608D01*
G01X1500464Y1182808D02*
Y1176608D01*
G01X1503483Y1206974D02*
X1501221Y1209236D01*
G01X1507867Y1211358D02*
X1503483Y1206974D01*
G01X1505605Y1213620D02*
X1507867Y1211358D01*
G01X1501221Y1209236D02*
X1505605Y1213620D01*
G01X1502776Y1216448D02*
X1505038Y1214186D01*
G01X1498392Y1212064D02*
X1502776Y1216448D01*
G01X1500654Y1209802D02*
X1498392Y1212064D01*
G01X1505038Y1214186D02*
X1500654Y1209802D01*
G01X1499947Y1219276D02*
X1502209Y1217014D01*
G01D02*
X1497825Y1212630D01*
G01X1699606Y1258464D02*
X1512598D01*
G01X1518392Y-40358D02*
Y-23758D01*
X1527992D01*
Y-40358D01*
X1518392D01*
G01X1525717Y156615D02*
X1526464Y155990D01*
X1527304Y155615D01*
X1528050D01*
X1528797Y155990D01*
X1529357Y156615D01*
X1529637Y157490D01*
X1529450Y158365D01*
X1528984Y159115D01*
X1528144Y159615D01*
X1527024Y159865D01*
X1526370Y160365D01*
X1526090Y161240D01*
X1526277Y162115D01*
X1526744Y162740D01*
X1527397Y163115D01*
X1528050D01*
X1528704Y162865D01*
X1529264Y162240D01*
G01X1533217Y156615D02*
X1533964Y155990D01*
X1534804Y155615D01*
X1535550D01*
X1536297Y155990D01*
X1536857Y156615D01*
X1537137Y157490D01*
X1536950Y158365D01*
X1536484Y159115D01*
X1535644Y159615D01*
X1534524Y159865D01*
X1533870Y160365D01*
X1533590Y161240D01*
X1533777Y162115D01*
X1534244Y162740D01*
X1534897Y163115D01*
X1535550D01*
X1536204Y162865D01*
X1536764Y162240D01*
G01X1540624Y155615D02*
Y163115D01*
X1542490D01*
X1543237Y162740D01*
X1543797Y162240D01*
X1544264Y161490D01*
X1544637Y160615D01*
X1544730Y159365D01*
X1544637Y158115D01*
X1544264Y157240D01*
X1543797Y156490D01*
X1543237Y155990D01*
X1542490Y155615D01*
X1540624D01*
G01X1550177D02*
Y163115D01*
X1549057Y161615D01*
G01Y155615D02*
X1551297D01*
G01X1555624Y157115D02*
X1556184Y156240D01*
X1556930Y155740D01*
X1557770Y155615D01*
X1558517Y155740D01*
X1559264Y156365D01*
X1559730Y157115D01*
X1559824Y157865D01*
X1559637Y158740D01*
X1558984Y159365D01*
X1558330Y159615D01*
X1557490D01*
G01X1558330D02*
X1558890Y159990D01*
X1559357Y160615D01*
X1559544Y161365D01*
X1559357Y162115D01*
X1558890Y162740D01*
X1558050Y163115D01*
X1557210Y162990D01*
X1556370Y162490D01*
G01X1529167Y164436D02*
X1543967D01*
G01X1529167Y195440D02*
Y164436D01*
G01X1543967Y195440D02*
X1529167D01*
G01X1526600Y204183D02*
X1523500D01*
Y205103D01*
X1523655Y205410D01*
X1524017Y205640D01*
X1524430Y205717D01*
X1524843Y205640D01*
X1525153Y205448D01*
X1525308Y205103D01*
Y204183D01*
G01X1526600Y207207D02*
X1523500D01*
Y207973D01*
X1523655Y208280D01*
X1523862Y208510D01*
X1524172Y208702D01*
X1524533Y208855D01*
X1525050Y208893D01*
X1525567Y208855D01*
X1525928Y208702D01*
X1526238Y208510D01*
X1526445Y208280D01*
X1526600Y207973D01*
Y207207D01*
G01Y211610D02*
X1523500D01*
X1525722Y210192D01*
Y212108D01*
G01X1525980Y213407D02*
X1526342Y213637D01*
X1526548Y213943D01*
X1526600Y214288D01*
X1526548Y214595D01*
X1526290Y214902D01*
X1525980Y215093D01*
X1525670Y215132D01*
X1525308Y215055D01*
X1525050Y214787D01*
X1524947Y214518D01*
Y214173D01*
G01Y214518D02*
X1524792Y214748D01*
X1524533Y214940D01*
X1524223Y215017D01*
X1523913Y214940D01*
X1523655Y214748D01*
X1523500Y214403D01*
X1523552Y214058D01*
X1523758Y213713D01*
G01X1533170Y199912D02*
Y202338D01*
G01X1539218Y203452D02*
X1527722D01*
G01D02*
Y233011D01*
G01X1533070Y236652D02*
Y234412D01*
G01X1534695Y235625D02*
X1531445D01*
G01X1527722Y233011D02*
X1539218D01*
G01X1526200Y262783D02*
X1523100D01*
Y263703D01*
X1523255Y264010D01*
X1523617Y264240D01*
X1524030Y264317D01*
X1524443Y264240D01*
X1524753Y264048D01*
X1524908Y263703D01*
Y262783D01*
G01X1526200Y265807D02*
X1523100D01*
Y266573D01*
X1523255Y266880D01*
X1523462Y267110D01*
X1523772Y267302D01*
X1524133Y267455D01*
X1524650Y267493D01*
X1525167Y267455D01*
X1525528Y267302D01*
X1525838Y267110D01*
X1526045Y266880D01*
X1526200Y266573D01*
Y265807D01*
G01Y269750D02*
X1523100D01*
X1523720Y269290D01*
G01X1526200D02*
Y270210D01*
G01Y272850D02*
X1523100D01*
X1523720Y272390D01*
G01X1526200D02*
Y273310D01*
G01X1525838Y275298D02*
X1526097Y275567D01*
X1526200Y275873D01*
X1526097Y276180D01*
X1525787Y276448D01*
X1525322Y276640D01*
X1524857Y276717D01*
X1524288D01*
X1523823Y276640D01*
X1523410Y276448D01*
X1523203Y276218D01*
X1523100Y275950D01*
X1523203Y275643D01*
X1523410Y275413D01*
X1523720Y275260D01*
X1524133Y275183D01*
X1524495Y275260D01*
X1524857Y275452D01*
X1525063Y275682D01*
X1525115Y275950D01*
X1525012Y276257D01*
X1524753Y276487D01*
X1524288Y276717D01*
G01X1532939Y259204D02*
Y261630D01*
G01X1538987Y262744D02*
X1527491D01*
G01D02*
Y292303D01*
G01X1532138Y298329D02*
Y296089D01*
G01X1533763Y297302D02*
X1530513D01*
G01X1527491Y292303D02*
X1538987D01*
G01X1524781Y322290D02*
Y353392D01*
G01X1522532D02*
X1517481Y348341D01*
G01X1524781Y353392D02*
X1522532D01*
G01X1520760Y377000D02*
Y380200D01*
G01X1526960Y377000D02*
X1520760D01*
G01X1526960Y380200D02*
Y377000D01*
G01X1520760Y380200D02*
X1526960D01*
G01Y384200D02*
Y381000D01*
G01X1520760Y384200D02*
X1526960D01*
G01X1520760Y381000D02*
Y384200D01*
G01X1526960Y381000D02*
X1520760D01*
G01X1519260Y450700D02*
X1516060D01*
G01X1519260Y456900D02*
Y450700D01*
G01X1516060Y456900D02*
X1519260D01*
G01X1516060Y450700D02*
Y456900D01*
G01X1514434Y462758D02*
Y447404D01*
G01X1520760Y458000D02*
Y461200D01*
G01X1526960Y458000D02*
X1520760D01*
G01X1526960Y461200D02*
Y458000D01*
G01X1520760Y461200D02*
X1526960D01*
G01Y465200D02*
Y462000D01*
G01X1520760Y465200D02*
X1526960D01*
G01X1520760Y462000D02*
Y465200D01*
G01X1526960Y462000D02*
X1520760D01*
G01X1515821Y543450D02*
Y537250D01*
G01X1520048Y556155D02*
Y552955D01*
G01X1513848D02*
Y556155D01*
G01X1520048Y552955D02*
X1513848D01*
G01X1520848D02*
Y556155D01*
G01X1527048Y552955D02*
X1520848D01*
G01X1527048Y556155D02*
Y552955D01*
G01X1513848Y556155D02*
X1520048D01*
G01Y560155D02*
Y556955D01*
G01X1513848Y560155D02*
X1520048D01*
G01X1513848Y556955D02*
Y560155D01*
G01X1520048Y556955D02*
X1513848D01*
G01X1520048Y564155D02*
Y560955D01*
G01X1513848Y564155D02*
X1520048D01*
G01X1513848Y560955D02*
Y564155D01*
G01X1520048Y560955D02*
X1513848D01*
G01X1520848Y556155D02*
X1527048D01*
G01X1520848Y556955D02*
Y560155D01*
G01X1527048Y556955D02*
X1520848D01*
G01X1527048Y560155D02*
Y556955D01*
G01X1520848Y560155D02*
X1527048D01*
G01X1520880Y560967D02*
Y564167D01*
G01X1527080Y560967D02*
X1520880D01*
G01X1527080Y564167D02*
Y560967D01*
G01X1520880Y564167D02*
X1527080D01*
G01X1514142Y576556D02*
Y588556D01*
G01X1520142Y576556D02*
X1514142D01*
G01X1520142Y588556D02*
Y576556D01*
G01X1521142D02*
Y588556D01*
G01X1527142Y576556D02*
X1521142D01*
G01X1527142Y588556D02*
Y576556D01*
G01X1514142Y588556D02*
X1520142D01*
G01X1521142D02*
X1527142D01*
G01X1526328Y597188D02*
Y593988D01*
G01X1520128Y597188D02*
X1526328D01*
G01X1520128Y593988D02*
Y597188D01*
G01X1526328Y593988D02*
X1520128D01*
G01X1526328Y593188D02*
Y589988D01*
G01X1520128Y593188D02*
X1526328D01*
G01X1520128Y589988D02*
Y593188D01*
G01X1526328Y589988D02*
X1520128D01*
G01X1526360Y605200D02*
Y602000D01*
G01X1520160D02*
Y605200D01*
G01X1526360Y602000D02*
X1520160D01*
G01X1526328Y601188D02*
Y597988D01*
G01X1520128Y601188D02*
X1526328D01*
G01X1520128Y597988D02*
Y601188D01*
G01X1526328Y597988D02*
X1520128D01*
G01X1520160Y605200D02*
X1526360D01*
G01Y613200D02*
Y610000D01*
G01X1520160Y613200D02*
X1526360D01*
G01X1520160Y610000D02*
Y613200D01*
G01X1526360Y610000D02*
X1520160D01*
G01X1526360Y621200D02*
Y618000D01*
G01X1520160D02*
Y621200D01*
G01X1526360Y618000D02*
X1520160D01*
G01X1526328Y609188D02*
Y605988D01*
G01X1520128Y609188D02*
X1526328D01*
G01X1520128Y605988D02*
Y609188D01*
G01X1526328Y605988D02*
X1520128D01*
G01X1526360Y617200D02*
Y614000D01*
G01X1520160Y617200D02*
X1526360D01*
G01X1520160Y614000D02*
Y617200D01*
G01X1526360Y614000D02*
X1520160D01*
G01Y621200D02*
X1526360D01*
G01Y639569D02*
Y636369D01*
G01X1520160D02*
Y639569D01*
G01X1526360Y636369D02*
X1520160D01*
G01Y629821D02*
Y633021D01*
G01X1526360Y629821D02*
X1520160D01*
G01X1526360Y633021D02*
Y629821D01*
G01X1520160Y633021D02*
X1526360D01*
G01Y625200D02*
Y622000D01*
G01X1520160Y625200D02*
X1526360D01*
G01X1520160Y622000D02*
Y625200D01*
G01X1526360Y622000D02*
X1520160D01*
G01X1526360Y629200D02*
Y626000D01*
G01X1520160Y629200D02*
X1526360D01*
G01X1520160Y626000D02*
Y629200D01*
G01X1526360Y626000D02*
X1520160D01*
G01Y639569D02*
X1526360D01*
G01Y643574D02*
Y640374D01*
G01X1520160Y643574D02*
X1526360D01*
G01X1520160Y640374D02*
Y643574D01*
G01X1526360Y640374D02*
X1520160D01*
G01X1514734Y897779D02*
Y885179D01*
G01X1523415Y908125D02*
X1526615D01*
G01X1523415Y901925D02*
Y908125D01*
G01X1526615Y901925D02*
X1523415D01*
G01X1526615Y908125D02*
Y901925D01*
G01X1522063Y976040D02*
Y971440D01*
G01X1521985Y970339D02*
Y967139D01*
G01X1515785Y970339D02*
X1521985D01*
G01X1515785Y967139D02*
Y970339D01*
G01X1521985Y967139D02*
X1515785D01*
G01X1521496Y987631D02*
X1524696D01*
G01X1521496Y981431D02*
Y987631D01*
G01X1524696Y981431D02*
X1521496D01*
G01X1524696Y987631D02*
Y981431D01*
G01X1529496Y987631D02*
X1532696D01*
G01X1529496Y981431D02*
Y987631D01*
G01X1532696Y981431D02*
X1529496D01*
G01X1517496Y987631D02*
X1520696D01*
G01X1517496Y981431D02*
Y987631D01*
G01X1520696Y981431D02*
X1517496D01*
G01X1520696Y987631D02*
Y981431D01*
G01X1521496Y990431D02*
Y996631D01*
G01X1524696Y990431D02*
X1521496D01*
G01X1524696Y996631D02*
Y990431D01*
G01X1529496D02*
Y996631D01*
G01X1532696Y990431D02*
X1529496D01*
G01X1517496D02*
Y996631D01*
G01X1520696Y990431D02*
X1517496D01*
G01X1520696Y996631D02*
Y990431D01*
G01X1525496D02*
Y996631D01*
G01X1528696Y990431D02*
X1525496D01*
G01X1528696Y996631D02*
Y990431D01*
G01X1516696Y987631D02*
Y981431D01*
G01Y996631D02*
Y990431D01*
G01X1521496Y996631D02*
X1524696D01*
G01X1529496D02*
X1532696D01*
G01X1517496D02*
X1520696D01*
G01X1525496D02*
X1528696D01*
G01X1519060Y1019871D02*
Y1015271D01*
G01Y1032471D02*
Y1027871D01*
G01X1519487Y1066535D02*
G03X1519318Y1069796I-31496J3D01*
G01X1537067Y57756D02*
Y104585D01*
G01X1536771Y58150D02*
Y104585D01*
G01X1537067Y57756D02*
X1530686D01*
G01X1536771Y58150D02*
X1531091D01*
G01X1548603Y86929D02*
X1545403D01*
G01Y93129D02*
X1548603D01*
G01X1545403Y86929D02*
Y93129D01*
G01X1542599Y97026D02*
Y103226D01*
G01X1545799Y97026D02*
X1542599D01*
G01X1545799Y103226D02*
Y97026D01*
G01X1544603Y86929D02*
X1541403D01*
G01X1544603Y93129D02*
Y86929D01*
G01X1541403Y93129D02*
X1544603D01*
G01X1541403Y86929D02*
Y93129D01*
G01X1537067Y111507D02*
Y107060D01*
G01X1536771Y111507D02*
Y107060D01*
G01Y118680D02*
Y114087D01*
G01X1537067Y118680D02*
Y114087D01*
G01X1542599Y103226D02*
X1545799D01*
G01X1536771Y132859D02*
Y128325D01*
G01X1537067Y132859D02*
Y128325D01*
G01Y125844D02*
Y121329D01*
G01X1536771Y125844D02*
Y121329D01*
G01Y152756D02*
Y135440D01*
G01X1537067Y153150D02*
Y135440D01*
G01X1543967Y164436D02*
Y195440D01*
G01X1530686Y153150D02*
X1537067D01*
G01X1531091Y152756D02*
X1536771D01*
G01X1548933Y171473D02*
X1545733D01*
G01Y177673D02*
X1548933D01*
G01X1545733Y171473D02*
Y177673D01*
G01X1541280Y213035D02*
Y225035D01*
G01X1547280Y213035D02*
X1541280D01*
G01X1539218Y233011D02*
Y203452D01*
G01X1541280Y225035D02*
X1547280D01*
G01X1540563Y250325D02*
Y234813D01*
G01D02*
X1571655D01*
G01X1538987Y292303D02*
Y262744D01*
G01X1540742Y251936D02*
Y255036D01*
X1541662D01*
X1541969Y254881D01*
X1542199Y254519D01*
X1542276Y254106D01*
X1542199Y253693D01*
X1542007Y253383D01*
X1541662Y253228D01*
X1540742D01*
G01X1543766Y251936D02*
Y255036D01*
X1544532D01*
X1544839Y254881D01*
X1545069Y254674D01*
X1545261Y254364D01*
X1545414Y254003D01*
X1545452Y253486D01*
X1545414Y252969D01*
X1545261Y252608D01*
X1545069Y252298D01*
X1544839Y252091D01*
X1544532Y251936D01*
X1543766D01*
G01X1548169D02*
Y255036D01*
X1546751Y252814D01*
X1548667D01*
G01X1549966Y252401D02*
X1550196Y252143D01*
X1550464Y251988D01*
X1550809Y251936D01*
X1551154Y252039D01*
X1551422Y252246D01*
X1551614Y252608D01*
X1551652Y253021D01*
X1551576Y253434D01*
X1551384Y253693D01*
X1551116Y253899D01*
X1550847Y253951D01*
X1550579Y253899D01*
X1550234Y253693D01*
X1550349Y255036D01*
X1551384D01*
G01X1571655Y250325D02*
X1540563D01*
G01X1540858Y271655D02*
Y283655D01*
G01X1546858Y271655D02*
X1540858D01*
G01Y283655D02*
X1546858D01*
G01X1536608Y350453D02*
Y353653D01*
G01X1542808Y350453D02*
X1536608D01*
G01X1542808Y353653D02*
Y350453D01*
G01X1536608Y353653D02*
X1542808D01*
G01X1539813Y366063D02*
Y391300D01*
G01X1537180Y366383D02*
X1537490Y366575D01*
X1537697Y366805D01*
X1537800Y367073D01*
X1537697Y367380D01*
X1537490Y367610D01*
X1537180Y367840D01*
X1536767Y367917D01*
X1534700D01*
G01X1535217Y369522D02*
X1534907Y369752D01*
X1534752Y370020D01*
X1534700Y370327D01*
X1534803Y370710D01*
X1535062Y370978D01*
X1535372Y371055D01*
X1535682Y371017D01*
X1535940Y370863D01*
X1536457Y370097D01*
X1536818Y369752D01*
X1537335Y369522D01*
X1537800Y369445D01*
Y371055D01*
G01X1536508Y372622D02*
X1536147Y372890D01*
X1535940Y373120D01*
X1535837Y373427D01*
X1535940Y373695D01*
X1536147Y373887D01*
X1536457Y374040D01*
X1536818Y374078D01*
X1537128Y374040D01*
X1537438Y373887D01*
X1537697Y373657D01*
X1537800Y373388D01*
X1537697Y373082D01*
X1537387Y372813D01*
X1536922Y372660D01*
X1536405Y372622D01*
X1535733Y372698D01*
X1535372Y372813D01*
X1535010Y373005D01*
X1534752Y373273D01*
X1534700Y373542D01*
X1534803Y373810D01*
X1535062Y374002D01*
G01X1539813Y366063D02*
X1555359D01*
G01X1539813Y398425D02*
Y393935D01*
G01Y405519D02*
Y401173D01*
G01Y412551D02*
Y408103D01*
G01Y419749D02*
Y415258D01*
G01Y426935D02*
Y422271D01*
G01Y433999D02*
Y429252D01*
G01Y441124D02*
Y436377D01*
G01Y469861D02*
Y443616D01*
G01Y477037D02*
Y472208D01*
G01Y484131D02*
Y479384D01*
G01Y491216D02*
Y486417D01*
G01Y513965D02*
Y493456D01*
G01Y521120D02*
Y516446D01*
G01Y639449D02*
Y537606D01*
G01Y528234D02*
Y523436D01*
G01Y535125D02*
Y530551D01*
G01X1533814Y653601D02*
X1533034Y652431D01*
X1532514Y651066D01*
Y649506D01*
X1533294Y647751D01*
X1534594Y646386D01*
X1536154Y645411D01*
X1538754Y644631D01*
X1541094Y644436D01*
X1543434Y644826D01*
X1544994Y645411D01*
X1546554Y646581D01*
X1547594Y647946D01*
X1548114Y649311D01*
Y650676D01*
X1547594Y652041D01*
X1546814Y653211D01*
X1545774Y654186D01*
G01X1539794Y668771D02*
X1539014Y669551D01*
X1537714Y670136D01*
X1535894Y670526D01*
X1534334Y670136D01*
X1533294Y669356D01*
X1532514Y667991D01*
Y662726D01*
X1548114D01*
Y669161D01*
X1547074Y670526D01*
X1545514Y671306D01*
X1543694Y671696D01*
X1541874Y671306D01*
X1540314Y670136D01*
X1539794Y668771D01*
Y662726D01*
G01X1532514Y681211D02*
X1548114D01*
Y689011D01*
G01X1553314Y697161D02*
Y708861D01*
G01X1532514Y720911D02*
X1548114D01*
G01X1532514Y716426D02*
Y725396D01*
G01X1548114Y738811D02*
X1547854Y737251D01*
X1546814Y735886D01*
X1545254Y734716D01*
X1543434Y733936D01*
X1541354Y733546D01*
X1539274D01*
X1537194Y733936D01*
X1535374Y734716D01*
X1533814Y735886D01*
X1532774Y737251D01*
X1532514Y738811D01*
X1532774Y740371D01*
X1533814Y741736D01*
X1535374Y742906D01*
X1537194Y743686D01*
X1539274Y744076D01*
X1541354D01*
X1543434Y743686D01*
X1545254Y742906D01*
X1546814Y741736D01*
X1547854Y740371D01*
X1548114Y738811D01*
G01Y752811D02*
X1532514D01*
Y757491D01*
X1533294Y759051D01*
X1535114Y760221D01*
X1537194Y760611D01*
X1539274Y760221D01*
X1540834Y759246D01*
X1541614Y757491D01*
Y752811D01*
G01X1555289Y639449D02*
X1539813D01*
G01X1533507Y917100D02*
Y914878D01*
X1533660Y914413D01*
X1533967Y914103D01*
X1534350Y914000D01*
X1534733Y914103D01*
X1535040Y914413D01*
X1535193Y914878D01*
Y917100D01*
G01X1537373Y914000D02*
X1537450Y914672D01*
X1537565Y915240D01*
X1537718Y915757D01*
X1537910Y916325D01*
X1538217Y917100D01*
X1536683D01*
G01X1540550D02*
X1540243Y916997D01*
X1540013Y916738D01*
X1539860Y916428D01*
X1539745Y916015D01*
X1539707Y915550D01*
X1539745Y915085D01*
X1539860Y914672D01*
X1540013Y914362D01*
X1540243Y914103D01*
X1540550Y914000D01*
X1540857Y914103D01*
X1541087Y914362D01*
X1541240Y914672D01*
X1541355Y915085D01*
X1541393Y915550D01*
X1541355Y916015D01*
X1541240Y916428D01*
X1541087Y916738D01*
X1540857Y916997D01*
X1540550Y917100D01*
G01X1530095Y919335D02*
X1534077D01*
G01D02*
Y923317D01*
G01Y959099D02*
X1530095D01*
G01X1534077Y955117D02*
Y959099D01*
G01X1548247Y968137D02*
X1542047D01*
Y971337D01*
X1548247D01*
Y968137D01*
G01X1532696Y987631D02*
Y981431D01*
G01Y996631D02*
Y990431D01*
G01X1562363Y-21819D02*
Y-18719D01*
X1563129D01*
X1563436Y-18874D01*
X1563666Y-19081D01*
X1563858Y-19391D01*
X1564011Y-19752D01*
X1564049Y-20269D01*
X1564011Y-20786D01*
X1563858Y-21147D01*
X1563666Y-21457D01*
X1563436Y-21664D01*
X1563129Y-21819D01*
X1562363D01*
G01X1567073D02*
X1565539D01*
Y-18719D01*
X1567073D01*
G01X1566459Y-20217D02*
X1565539D01*
G01X1569406Y-21819D02*
Y-18719D01*
X1568946Y-19339D01*
G01Y-21819D02*
X1569866D01*
G01X1571663Y-21354D02*
X1571893Y-21612D01*
X1572161Y-21767D01*
X1572506Y-21819D01*
X1572851Y-21716D01*
X1573119Y-21509D01*
X1573311Y-21147D01*
X1573349Y-20734D01*
X1573273Y-20321D01*
X1573081Y-20062D01*
X1572813Y-19856D01*
X1572544Y-19804D01*
X1572276Y-19856D01*
X1571931Y-20062D01*
X1572046Y-18719D01*
X1573081D01*
G01X1575606D02*
Y-21819D01*
G01X1574724Y-18719D02*
X1576488D01*
G01X1577556Y-22852D02*
X1579856D01*
G01X1581078Y-19236D02*
X1581308Y-18926D01*
X1581576Y-18771D01*
X1581883Y-18719D01*
X1582266Y-18822D01*
X1582534Y-19081D01*
X1582611Y-19391D01*
X1582573Y-19701D01*
X1582419Y-19959D01*
X1581653Y-20476D01*
X1581308Y-20837D01*
X1581078Y-21354D01*
X1581001Y-21819D01*
X1582611D01*
G01X1558469Y42578D02*
Y45678D01*
G01X1560079D02*
Y42578D01*
G01Y44128D02*
X1558469D01*
G01X1561646Y43870D02*
X1561914Y44231D01*
X1562144Y44438D01*
X1562451Y44541D01*
X1562719Y44438D01*
X1562911Y44231D01*
X1563064Y43921D01*
X1563102Y43560D01*
X1563064Y43250D01*
X1562911Y42940D01*
X1562681Y42681D01*
X1562412Y42578D01*
X1562106Y42681D01*
X1561837Y42991D01*
X1561684Y43456D01*
X1561646Y43973D01*
X1561722Y44645D01*
X1561837Y45006D01*
X1562029Y45368D01*
X1562297Y45626D01*
X1562566Y45678D01*
X1562834Y45575D01*
X1563026Y45316D01*
G01X1565934Y42578D02*
Y45678D01*
X1564516Y43456D01*
X1566432D01*
G01X1552992Y82540D02*
Y85740D01*
G01X1559192Y82540D02*
X1552992D01*
G01X1559192Y85740D02*
Y82540D01*
G01X1552992Y74540D02*
Y77740D01*
G01X1559192Y74540D02*
X1552992D01*
G01X1559192Y77740D02*
Y74540D01*
G01X1552992Y77740D02*
X1559192D01*
G01X1552992Y78540D02*
Y81740D01*
G01X1559192Y78540D02*
X1552992D01*
G01X1559192Y81740D02*
Y78540D01*
G01X1552992Y81740D02*
X1559192D01*
G01X1548603Y93129D02*
Y86929D01*
G01X1552992Y85740D02*
X1559192D01*
G01X1556612Y86929D02*
X1553412D01*
G01X1556612Y93129D02*
Y86929D01*
G01X1553412Y93129D02*
X1556612D01*
G01X1553412Y86929D02*
Y93129D01*
G01X1552603Y86929D02*
X1549403D01*
G01X1552603Y93129D02*
Y86929D01*
G01X1549403Y93129D02*
X1552603D01*
G01X1549403Y86929D02*
Y93129D01*
G01X1552682Y96673D02*
Y102873D01*
G01X1555882Y96673D02*
X1552682D01*
G01X1555882Y102873D02*
Y96673D01*
G01X1558186Y95950D02*
Y102150D01*
G01X1561386Y95950D02*
X1558186D01*
G01X1561386Y102150D02*
Y95950D01*
G01X1548682Y96673D02*
Y102873D01*
G01X1551882Y96673D02*
X1548682D01*
G01X1551882Y102873D02*
Y96673D01*
G01X1552682Y102873D02*
X1555882D01*
G01X1558186Y102150D02*
X1561386D01*
G01X1548682Y102873D02*
X1551882D01*
G01X1558186Y109762D02*
X1561386D01*
G01X1558186Y103562D02*
Y109762D01*
G01X1561386Y103562D02*
X1558186D01*
G01X1561386Y109762D02*
Y103562D01*
G01X1554665Y144690D02*
Y154138D01*
G01X1565501Y144690D02*
X1554665D01*
G01X1546297Y145940D02*
Y149140D01*
G01X1552497Y145940D02*
X1546297D01*
G01X1552497Y149140D02*
Y145940D01*
G01X1546297Y149140D02*
X1552497D01*
G01X1557246Y139647D02*
Y142847D01*
G01X1563446Y139647D02*
X1557246D01*
G01Y142847D02*
X1563446D01*
G01X1550267Y139647D02*
Y142847D01*
G01X1556467Y139647D02*
X1550267D01*
G01X1556467Y142847D02*
Y139647D01*
G01X1550267Y142847D02*
X1556467D01*
G01X1562958Y155440D02*
X1562651Y155492D01*
X1562383Y155698D01*
X1562153Y156008D01*
X1562000Y156370D01*
X1561923Y156783D01*
Y157197D01*
X1562000Y157610D01*
X1562153Y157972D01*
X1562383Y158282D01*
X1562651Y158488D01*
X1562958Y158540D01*
X1563265Y158488D01*
X1563533Y158282D01*
X1563763Y157972D01*
X1563916Y157610D01*
X1563993Y157197D01*
Y156783D01*
X1563916Y156370D01*
X1563763Y156008D01*
X1563533Y155698D01*
X1563265Y155492D01*
X1562958Y155440D01*
G01X1563265Y156267D02*
X1563725Y155440D01*
G01X1565330Y158023D02*
X1565560Y158333D01*
X1565828Y158488D01*
X1566135Y158540D01*
X1566518Y158437D01*
X1566786Y158178D01*
X1566863Y157868D01*
X1566825Y157558D01*
X1566671Y157300D01*
X1565905Y156783D01*
X1565560Y156422D01*
X1565330Y155905D01*
X1565253Y155440D01*
X1566863D01*
G01X1568315Y156060D02*
X1568545Y155698D01*
X1568851Y155492D01*
X1569196Y155440D01*
X1569503Y155492D01*
X1569810Y155750D01*
X1570001Y156060D01*
X1570040Y156370D01*
X1569963Y156732D01*
X1569695Y156990D01*
X1569426Y157093D01*
X1569081D01*
G01X1569426D02*
X1569656Y157248D01*
X1569848Y157507D01*
X1569925Y157817D01*
X1569848Y158127D01*
X1569656Y158385D01*
X1569311Y158540D01*
X1568966Y158488D01*
X1568621Y158282D01*
G01X1572258Y158540D02*
X1571951Y158437D01*
X1571721Y158178D01*
X1571568Y157868D01*
X1571453Y157455D01*
X1571415Y156990D01*
X1571453Y156525D01*
X1571568Y156112D01*
X1571721Y155802D01*
X1571951Y155543D01*
X1572258Y155440D01*
X1572565Y155543D01*
X1572795Y155802D01*
X1572948Y156112D01*
X1573063Y156525D01*
X1573101Y156990D01*
X1573063Y157455D01*
X1572948Y157868D01*
X1572795Y158178D01*
X1572565Y158437D01*
X1572258Y158540D01*
G01X1562083Y154138D02*
X1565501D01*
G01X1560083Y152414D02*
X1562083Y154138D01*
G01X1558083D02*
X1560083Y152414D01*
G01X1554665Y154138D02*
X1558083D01*
G01X1552497Y153140D02*
Y149940D01*
G01X1546297Y153140D02*
X1552497D01*
G01X1546297Y149940D02*
Y153140D01*
G01X1552497Y149940D02*
X1546297D01*
G01X1557457Y175100D02*
Y172878D01*
X1557610Y172413D01*
X1557917Y172103D01*
X1558300Y172000D01*
X1558683Y172103D01*
X1558990Y172413D01*
X1559143Y172878D01*
Y175100D01*
G01X1561323Y172000D02*
X1561400Y172672D01*
X1561515Y173240D01*
X1561668Y173757D01*
X1561860Y174325D01*
X1562167Y175100D01*
X1560633D01*
G01X1563772Y173292D02*
X1564040Y173653D01*
X1564270Y173860D01*
X1564577Y173963D01*
X1564845Y173860D01*
X1565037Y173653D01*
X1565190Y173343D01*
X1565228Y172982D01*
X1565190Y172672D01*
X1565037Y172362D01*
X1564807Y172103D01*
X1564538Y172000D01*
X1564232Y172103D01*
X1563963Y172413D01*
X1563810Y172878D01*
X1563772Y173395D01*
X1563848Y174067D01*
X1563963Y174428D01*
X1564155Y174790D01*
X1564423Y175048D01*
X1564692Y175100D01*
X1564960Y174997D01*
X1565152Y174738D01*
G01X1557661Y176944D02*
Y178897D01*
G01X1559614Y176944D02*
X1557661D01*
G01X1552933Y171473D02*
X1549733D01*
G01X1552933Y177673D02*
Y171473D01*
G01X1549733Y177673D02*
X1552933D01*
G01X1549733Y171473D02*
Y177673D01*
G01X1548933D02*
Y171473D01*
G01X1555956Y170297D02*
Y167097D01*
G01X1549756Y170297D02*
X1555956D01*
G01X1549756Y167097D02*
Y170297D01*
G01X1555956Y167097D02*
X1549756D01*
G01X1557661Y188756D02*
X1559614D01*
G01X1557661Y186803D02*
Y188756D01*
G01X1553160Y182730D02*
X1549960D01*
G01X1553160Y188930D02*
Y182730D01*
G01X1549960Y188930D02*
X1553160D01*
G01X1549960Y182730D02*
Y188930D01*
G01X1556151Y193541D02*
Y190341D01*
G01X1549951Y193541D02*
X1556151D01*
G01X1549951Y190341D02*
Y193541D01*
G01X1556151Y190341D02*
X1549951D01*
G01X1547280Y225035D02*
Y213035D01*
G01X1556589Y200607D02*
Y203707D01*
X1557509D01*
X1557816Y203552D01*
X1558046Y203190D01*
X1558123Y202777D01*
X1558046Y202364D01*
X1557854Y202054D01*
X1557509Y201899D01*
X1556589D01*
G01X1559613Y203707D02*
Y201485D01*
X1559766Y201020D01*
X1560073Y200710D01*
X1560456Y200607D01*
X1560839Y200710D01*
X1561146Y201020D01*
X1561299Y201485D01*
Y203707D01*
G01X1564016Y200607D02*
Y203707D01*
X1562598Y201485D01*
X1564514D01*
G01X1566656Y200607D02*
Y203707D01*
X1566196Y203087D01*
G01Y200607D02*
X1567116D01*
G01X1570436Y220252D02*
Y208048D01*
X1555132D01*
Y220252D01*
X1570436D01*
G01X1548120Y226621D02*
Y232621D01*
G01X1560120Y226621D02*
X1548120D01*
G01X1560120Y232621D02*
Y226621D01*
G01X1552099Y215082D02*
X1548899D01*
G01X1552099Y221282D02*
Y215082D01*
G01X1548899Y221282D02*
X1552099D01*
G01X1548899Y215082D02*
Y221282D01*
G01X1558120Y225921D02*
Y222721D01*
G01X1551920Y225921D02*
X1558120D01*
G01X1551920Y222721D02*
Y225921D01*
G01X1558120Y222721D02*
X1551920D01*
G01X1548120Y232621D02*
X1560120D01*
G01X1548788Y258010D02*
Y264210D01*
G01X1551988Y258010D02*
X1548788D01*
G01X1551988Y264210D02*
Y258010D01*
G01X1556788D02*
Y264210D01*
G01X1559988Y258010D02*
X1556788D01*
G01X1559988Y264210D02*
Y258010D01*
G01X1555988D02*
X1552788D01*
G01X1555988Y264210D02*
Y258010D01*
G01X1552788D02*
Y264210D01*
G01X1546858Y283655D02*
Y271655D01*
G01X1548788Y264210D02*
X1551988D01*
G01X1556788D02*
X1559988D01*
G01X1565067Y273701D02*
X1561867D01*
G01D02*
Y279901D01*
G01X1552788Y264210D02*
X1555988D01*
G01X1559509Y279427D02*
Y267653D01*
G01X1549747D02*
Y279427D01*
G01X1559509Y267653D02*
X1549747D01*
G01X1561867Y279901D02*
X1565067D01*
G01X1551041Y283383D02*
X1547841D01*
G01X1551041Y289583D02*
Y283383D01*
G01X1547841Y289583D02*
X1551041D01*
G01X1547841Y283383D02*
Y289583D01*
G01X1555041Y283383D02*
X1551841D01*
G01X1555041Y289583D02*
Y283383D01*
G01X1551841Y289583D02*
X1555041D01*
G01X1551841Y283383D02*
Y289583D01*
G01X1555841Y283383D02*
Y289583D01*
X1559041D01*
Y283383D01*
X1555841D01*
G01X1563800Y282633D02*
X1560700D01*
Y283553D01*
X1560855Y283860D01*
X1561217Y284090D01*
X1561630Y284167D01*
X1562043Y284090D01*
X1562353Y283898D01*
X1562508Y283553D01*
Y282633D01*
G01X1560700Y285657D02*
X1562922D01*
X1563387Y285810D01*
X1563697Y286117D01*
X1563800Y286500D01*
X1563697Y286883D01*
X1563387Y287190D01*
X1562922Y287343D01*
X1560700D01*
G01X1563800Y289600D02*
X1560700D01*
X1561320Y289140D01*
G01X1563800D02*
Y290060D01*
G01Y292700D02*
X1560700D01*
X1561320Y292240D01*
G01X1563800D02*
Y293160D01*
G01X1562508Y295072D02*
X1562147Y295340D01*
X1561940Y295570D01*
X1561837Y295877D01*
X1561940Y296145D01*
X1562147Y296337D01*
X1562457Y296490D01*
X1562818Y296528D01*
X1563128Y296490D01*
X1563438Y296337D01*
X1563697Y296107D01*
X1563800Y295838D01*
X1563697Y295532D01*
X1563387Y295263D01*
X1562922Y295110D01*
X1562405Y295072D01*
X1561733Y295148D01*
X1561372Y295263D01*
X1561010Y295455D01*
X1560752Y295723D01*
X1560700Y295992D01*
X1560803Y296260D01*
X1561062Y296452D01*
G01X1549747Y279427D02*
X1559509D01*
G01X1556779Y317963D02*
X1562979D01*
G01X1556779Y314763D02*
Y317963D01*
G01X1562979Y314763D02*
X1556779D01*
G01Y326963D02*
X1562979D01*
G01X1556779Y323763D02*
Y326963D01*
G01X1562979Y323763D02*
X1556779D01*
G01X1552979Y317963D02*
Y314763D01*
G01X1546779Y317963D02*
X1552979D01*
G01X1546779Y314763D02*
Y317963D01*
G01X1552979Y314763D02*
X1546779D01*
G01X1552979Y326963D02*
Y323763D01*
G01X1546779Y326963D02*
X1552979D01*
G01X1546779Y323763D02*
Y326963D01*
G01X1552979Y323763D02*
X1546779D01*
G01X1556779Y331463D02*
X1562979D01*
G01X1556779Y328263D02*
Y331463D01*
G01X1562979Y328263D02*
X1556779D01*
G01Y335963D02*
X1562979D01*
G01X1556779Y332763D02*
Y335963D01*
G01X1562979Y332763D02*
X1556779D01*
G01Y341763D02*
Y344963D01*
G01X1562979Y341763D02*
X1556779D01*
G01X1552979Y331463D02*
Y328263D01*
G01X1546779Y331463D02*
X1552979D01*
G01X1546779Y328263D02*
Y331463D01*
G01X1552979Y328263D02*
X1546779D01*
G01X1552979Y335963D02*
Y332763D01*
G01X1546779Y335963D02*
X1552979D01*
G01X1546779Y332763D02*
Y335963D01*
G01X1552979Y332763D02*
X1546779D01*
G01X1552979Y344963D02*
Y341763D01*
G01X1546779D02*
Y344963D01*
G01X1552979Y341763D02*
X1546779D01*
G01X1556779Y344963D02*
X1562979D01*
G01X1556779Y353963D02*
X1562979D01*
G01X1556779Y350763D02*
Y353963D01*
G01X1562979Y350763D02*
X1556779D01*
G01X1546779Y344963D02*
X1552979D01*
G01X1546779Y350763D02*
Y353963D01*
G01X1552979Y350763D02*
X1546779D01*
G01X1552979Y353963D02*
Y350763D01*
G01X1546779Y353963D02*
X1552979D01*
G01X1554707Y650100D02*
Y647878D01*
X1554860Y647413D01*
X1555167Y647103D01*
X1555550Y647000D01*
X1555933Y647103D01*
X1556240Y647413D01*
X1556393Y647878D01*
Y650100D01*
G01X1559110Y647000D02*
Y650100D01*
X1557692Y647878D01*
X1559608D01*
G01X1561750Y650100D02*
X1561443Y649997D01*
X1561213Y649738D01*
X1561060Y649428D01*
X1560945Y649015D01*
X1560907Y648550D01*
X1560945Y648085D01*
X1561060Y647672D01*
X1561213Y647362D01*
X1561443Y647103D01*
X1561750Y647000D01*
X1562057Y647103D01*
X1562287Y647362D01*
X1562440Y647672D01*
X1562555Y648085D01*
X1562593Y648550D01*
X1562555Y649015D01*
X1562440Y649428D01*
X1562287Y649738D01*
X1562057Y649997D01*
X1561750Y650100D01*
G01X1555807Y651488D02*
Y659952D01*
G01X1569069Y651488D02*
X1555807D01*
G01X1560938Y659952D02*
X1562438Y658181D01*
G01X1555807Y659952D02*
X1560938D01*
G01X1562438Y658181D02*
X1563938Y659952D01*
G01X1562372Y669083D02*
Y685283D01*
G01X1575372Y669083D02*
X1562372D01*
G01X1558100Y673307D02*
X1560322D01*
X1560787Y673460D01*
X1561097Y673767D01*
X1561200Y674150D01*
X1561097Y674533D01*
X1560787Y674840D01*
X1560322Y674993D01*
X1558100D01*
G01X1561200Y677710D02*
X1558100D01*
X1560322Y676292D01*
Y678208D01*
G01X1561200Y680350D02*
X1558100D01*
X1558720Y679890D01*
G01X1561200D02*
Y680810D01*
G01X1562372Y685283D02*
X1575372D01*
G01X1551352Y914791D02*
X1551544Y914481D01*
X1551774Y914274D01*
X1552042Y914171D01*
X1552349Y914274D01*
X1552579Y914481D01*
X1552809Y914791D01*
X1552886Y915204D01*
Y917271D01*
G01X1554491Y915463D02*
X1554759Y915824D01*
X1554989Y916031D01*
X1555296Y916134D01*
X1555564Y916031D01*
X1555756Y915824D01*
X1555909Y915514D01*
X1555947Y915153D01*
X1555909Y914843D01*
X1555756Y914533D01*
X1555526Y914274D01*
X1555257Y914171D01*
X1554951Y914274D01*
X1554682Y914584D01*
X1554529Y915049D01*
X1554491Y915566D01*
X1554567Y916238D01*
X1554682Y916599D01*
X1554874Y916961D01*
X1555142Y917219D01*
X1555411Y917271D01*
X1555679Y917168D01*
X1555871Y916909D01*
G01X1557476Y914636D02*
X1557706Y914378D01*
X1557974Y914223D01*
X1558319Y914171D01*
X1558664Y914274D01*
X1558932Y914481D01*
X1559124Y914843D01*
X1559162Y915256D01*
X1559086Y915669D01*
X1558894Y915928D01*
X1558626Y916134D01*
X1558357Y916186D01*
X1558089Y916134D01*
X1557744Y915928D01*
X1557859Y917271D01*
X1558894D01*
G01X1549614Y958200D02*
X1555814D01*
Y955000D01*
X1549614D01*
Y958200D01*
G01X1563014Y967350D02*
Y965400D01*
X1553014D01*
G01D02*
Y977350D01*
G01Y983450D02*
Y995400D01*
X1563014D01*
Y993450D01*
G01X1552797Y997587D02*
X1552989Y997277D01*
X1553219Y997070D01*
X1553487Y996967D01*
X1553794Y997070D01*
X1554024Y997277D01*
X1554254Y997587D01*
X1554331Y998000D01*
Y1000067D01*
G01X1555936Y998259D02*
X1556204Y998620D01*
X1556434Y998827D01*
X1556741Y998930D01*
X1557009Y998827D01*
X1557201Y998620D01*
X1557354Y998310D01*
X1557392Y997949D01*
X1557354Y997639D01*
X1557201Y997329D01*
X1556971Y997070D01*
X1556702Y996967D01*
X1556396Y997070D01*
X1556127Y997380D01*
X1555974Y997845D01*
X1555936Y998362D01*
X1556012Y999034D01*
X1556127Y999395D01*
X1556319Y999757D01*
X1556587Y1000015D01*
X1556856Y1000067D01*
X1557124Y999964D01*
X1557316Y999705D01*
G01X1559687Y996967D02*
X1559764Y997639D01*
X1559879Y998207D01*
X1560032Y998724D01*
X1560224Y999292D01*
X1560531Y1000067D01*
X1558997D01*
G01X1572363Y-60739D02*
Y-57639D01*
X1573129D01*
X1573436Y-57794D01*
X1573666Y-58001D01*
X1573858Y-58311D01*
X1574011Y-58672D01*
X1574049Y-59189D01*
X1574011Y-59706D01*
X1573858Y-60067D01*
X1573666Y-60377D01*
X1573436Y-60584D01*
X1573129Y-60739D01*
X1572363D01*
G01X1577073D02*
X1575539D01*
Y-57639D01*
X1577073D01*
G01X1576459Y-59137D02*
X1575539D01*
G01X1579406Y-57639D02*
X1579099Y-57742D01*
X1578869Y-58001D01*
X1578716Y-58311D01*
X1578601Y-58724D01*
X1578563Y-59189D01*
X1578601Y-59654D01*
X1578716Y-60067D01*
X1578869Y-60377D01*
X1579099Y-60636D01*
X1579406Y-60739D01*
X1579713Y-60636D01*
X1579943Y-60377D01*
X1580096Y-60067D01*
X1580211Y-59654D01*
X1580249Y-59189D01*
X1580211Y-58724D01*
X1580096Y-58311D01*
X1579943Y-58001D01*
X1579713Y-57742D01*
X1579406Y-57639D01*
G01X1581663Y-60274D02*
X1581893Y-60532D01*
X1582161Y-60687D01*
X1582506Y-60739D01*
X1582851Y-60636D01*
X1583119Y-60429D01*
X1583311Y-60067D01*
X1583349Y-59654D01*
X1583273Y-59241D01*
X1583081Y-58982D01*
X1582813Y-58776D01*
X1582544Y-58724D01*
X1582276Y-58776D01*
X1581931Y-58982D01*
X1582046Y-57639D01*
X1583081D01*
G01X1584878Y-60739D02*
Y-57639D01*
X1586334D01*
G01X1585798Y-59137D02*
X1584878D01*
G01X1587556Y-61772D02*
X1589856D01*
G01X1591078Y-58156D02*
X1591308Y-57846D01*
X1591576Y-57691D01*
X1591883Y-57639D01*
X1592266Y-57742D01*
X1592534Y-58001D01*
X1592611Y-58311D01*
X1592573Y-58621D01*
X1592419Y-58879D01*
X1591653Y-59396D01*
X1591308Y-59757D01*
X1591078Y-60274D01*
X1591001Y-60739D01*
X1592611D01*
G01X1581056Y-23786D02*
Y-40386D01*
X1571456D01*
Y-23786D01*
X1581056D01*
G01X1584490Y67523D02*
X1572286D01*
G01D02*
Y70183D01*
G01X1572983Y59613D02*
X1579183D01*
G01X1572983Y56413D02*
Y59613D01*
G01X1579183Y56413D02*
X1572983D01*
G01X1569858Y70181D02*
Y66981D01*
G01X1563658D02*
Y70181D01*
G01X1569858Y66981D02*
X1563658D01*
G01X1572286Y79047D02*
X1584490D01*
G01X1572286Y76285D02*
Y79047D01*
G01X1575388Y73285D02*
X1572286Y76285D01*
G01Y70183D02*
X1575388Y73285D01*
G01X1563658Y70181D02*
X1569858D01*
G01X1563703Y70987D02*
Y74187D01*
G01X1569903Y70987D02*
X1563703D01*
G01X1569903Y74187D02*
Y70987D01*
G01X1563703Y74187D02*
X1569903D01*
G01X1563703Y74987D02*
Y78187D01*
G01X1569903Y74987D02*
X1563703D01*
G01X1569903Y78187D02*
Y74987D01*
G01X1563703Y78187D02*
X1569903D01*
G01X1569858Y82181D02*
Y78981D01*
G01X1563658Y82181D02*
X1569858D01*
G01X1563658Y78981D02*
Y82181D01*
G01X1569858Y78981D02*
X1563658D01*
G01X1570693Y93476D02*
X1573893D01*
G01X1570693Y87276D02*
Y93476D01*
G01X1573893Y87276D02*
X1570693D01*
G01X1573893Y93476D02*
Y87276D01*
G01X1579393D02*
X1576193D01*
G01Y93476D02*
X1579393D01*
G01X1576193Y87276D02*
Y93476D01*
G01X1577100Y97507D02*
X1579322D01*
X1579787Y97660D01*
X1580097Y97967D01*
X1580200Y98350D01*
X1580097Y98733D01*
X1579787Y99040D01*
X1579322Y99193D01*
X1577100D01*
G01X1580200Y101910D02*
X1577100D01*
X1579322Y100492D01*
Y102408D01*
G01X1577100Y104550D02*
X1577203Y104243D01*
X1577462Y104013D01*
X1577772Y103860D01*
X1578185Y103745D01*
X1578650Y103707D01*
X1579115Y103745D01*
X1579528Y103860D01*
X1579838Y104013D01*
X1580097Y104243D01*
X1580200Y104550D01*
X1580097Y104857D01*
X1579838Y105087D01*
X1579528Y105240D01*
X1579115Y105355D01*
X1578650Y105393D01*
X1578185Y105355D01*
X1577772Y105240D01*
X1577462Y105087D01*
X1577203Y104857D01*
X1577100Y104550D01*
G01X1579838Y106998D02*
X1580097Y107267D01*
X1580200Y107573D01*
X1580097Y107880D01*
X1579787Y108148D01*
X1579322Y108340D01*
X1578857Y108417D01*
X1578288D01*
X1577823Y108340D01*
X1577410Y108148D01*
X1577203Y107918D01*
X1577100Y107650D01*
X1577203Y107343D01*
X1577410Y107113D01*
X1577720Y106960D01*
X1578133Y106883D01*
X1578495Y106960D01*
X1578857Y107152D01*
X1579063Y107382D01*
X1579115Y107650D01*
X1579012Y107957D01*
X1578753Y108187D01*
X1578288Y108417D01*
G01X1575528Y111267D02*
Y95913D01*
G01X1562850D02*
Y111267D01*
G01X1575331Y95913D02*
X1562850D01*
G01X1576684Y111951D02*
Y118151D01*
G01X1579884Y111951D02*
X1576684D01*
G01X1575401Y116088D02*
Y112888D01*
G01X1569201Y116088D02*
X1575401D01*
G01X1569201Y112888D02*
Y116088D01*
G01X1575401Y112888D02*
X1569201D01*
G01X1562850Y111267D02*
X1575528D01*
G01X1576684Y118151D02*
X1579884D01*
G01X1576460Y119183D02*
X1573360D01*
Y120103D01*
X1573515Y120410D01*
X1573877Y120640D01*
X1574290Y120717D01*
X1574703Y120640D01*
X1575013Y120448D01*
X1575168Y120103D01*
Y119183D01*
G01X1573360Y122207D02*
X1575582D01*
X1576047Y122360D01*
X1576357Y122667D01*
X1576460Y123050D01*
X1576357Y123433D01*
X1576047Y123740D01*
X1575582Y123893D01*
X1573360D01*
G01X1576460Y126150D02*
X1573360D01*
X1573980Y125690D01*
G01X1576460D02*
Y126610D01*
G01X1575840Y128407D02*
X1576202Y128637D01*
X1576408Y128943D01*
X1576460Y129288D01*
X1576408Y129595D01*
X1576150Y129902D01*
X1575840Y130093D01*
X1575530Y130132D01*
X1575168Y130055D01*
X1574910Y129787D01*
X1574807Y129518D01*
Y129173D01*
G01Y129518D02*
X1574652Y129748D01*
X1574393Y129940D01*
X1574083Y130017D01*
X1573773Y129940D01*
X1573515Y129748D01*
X1573360Y129403D01*
X1573412Y129058D01*
X1573618Y128713D01*
G01X1575840Y131507D02*
X1576202Y131737D01*
X1576408Y132043D01*
X1576460Y132388D01*
X1576408Y132695D01*
X1576150Y133002D01*
X1575840Y133193D01*
X1575530Y133232D01*
X1575168Y133155D01*
X1574910Y132887D01*
X1574807Y132618D01*
Y132273D01*
G01Y132618D02*
X1574652Y132848D01*
X1574393Y133040D01*
X1574083Y133117D01*
X1573773Y133040D01*
X1573515Y132848D01*
X1573360Y132503D01*
X1573412Y132158D01*
X1573618Y131813D01*
G01X1565501Y154138D02*
Y144690D01*
G01X1573108Y151368D02*
Y148168D01*
G01X1566908D02*
Y151368D01*
G01X1573108Y148168D02*
X1566908D01*
G01Y144168D02*
Y147368D01*
G01X1573108Y144168D02*
X1566908D01*
G01X1573108Y147368D02*
Y144168D01*
G01X1566908Y147368D02*
X1573108D01*
G01X1563446Y142847D02*
Y139647D01*
G01X1574100Y137507D02*
X1576322D01*
X1576787Y137660D01*
X1577097Y137967D01*
X1577200Y138350D01*
X1577097Y138733D01*
X1576787Y139040D01*
X1576322Y139193D01*
X1574100D01*
G01X1576580Y140607D02*
X1576942Y140837D01*
X1577148Y141143D01*
X1577200Y141488D01*
X1577148Y141795D01*
X1576890Y142102D01*
X1576580Y142293D01*
X1576270Y142332D01*
X1575908Y142255D01*
X1575650Y141987D01*
X1575547Y141718D01*
Y141373D01*
G01Y141718D02*
X1575392Y141948D01*
X1575133Y142140D01*
X1574823Y142217D01*
X1574513Y142140D01*
X1574255Y141948D01*
X1574100Y141603D01*
X1574152Y141258D01*
X1574358Y140913D01*
G01X1576838Y143898D02*
X1577097Y144167D01*
X1577200Y144473D01*
X1577097Y144780D01*
X1576787Y145048D01*
X1576322Y145240D01*
X1575857Y145317D01*
X1575288D01*
X1574823Y145240D01*
X1574410Y145048D01*
X1574203Y144818D01*
X1574100Y144550D01*
X1574203Y144243D01*
X1574410Y144013D01*
X1574720Y143860D01*
X1575133Y143783D01*
X1575495Y143860D01*
X1575857Y144052D01*
X1576063Y144282D01*
X1576115Y144550D01*
X1576012Y144857D01*
X1575753Y145087D01*
X1575288Y145317D01*
G01X1577200Y147573D02*
X1576528Y147650D01*
X1575960Y147765D01*
X1575443Y147918D01*
X1574875Y148110D01*
X1574100Y148417D01*
Y146883D01*
G01X1566908Y151368D02*
X1573108D01*
G01X1569473Y176944D02*
X1567520D01*
G01X1569473Y178897D02*
Y176944D01*
G01X1571665Y170313D02*
Y167113D01*
G01X1565465Y170313D02*
X1571665D01*
G01X1565465Y167113D02*
Y170313D01*
G01X1571665Y167113D02*
X1565465D01*
G01X1573844Y167065D02*
Y170265D01*
G01X1580044Y167065D02*
X1573844D01*
G01Y170265D02*
X1580044D01*
G01X1573844Y175065D02*
Y178265D01*
G01X1580044Y175065D02*
X1573844D01*
G01Y178265D02*
X1580044D01*
G01X1573844Y171065D02*
Y174265D01*
G01X1580044Y171065D02*
X1573844D01*
G01Y174265D02*
X1580044D01*
G01X1573844Y179065D02*
Y182265D01*
G01X1580044Y179065D02*
X1573844D01*
G01X1569473Y188756D02*
Y186803D01*
G01X1567520Y188756D02*
X1569473D01*
G01X1573844Y182265D02*
X1580044D01*
G01X1573844Y183065D02*
Y186265D01*
G01X1580044Y183065D02*
X1573844D01*
G01Y186265D02*
X1580044D01*
G01X1573844Y194265D02*
X1580044D01*
G01X1573844Y191065D02*
Y194265D01*
G01X1580044Y191065D02*
X1573844D01*
G01Y187065D02*
Y190265D01*
G01X1580044Y187065D02*
X1573844D01*
G01Y190265D02*
X1580044D01*
G01X1573844Y195065D02*
Y198265D01*
G01X1580044Y195065D02*
X1573844D01*
G01X1573939Y202464D02*
X1580139D01*
Y199264D01*
X1573939D01*
Y202464D01*
G01X1573844Y198265D02*
X1580044D01*
G01X1573939Y207264D02*
Y210464D01*
G01X1580139Y207264D02*
X1573939D01*
G01Y210464D02*
X1580139D01*
G01X1573939Y206464D02*
X1580139D01*
G01X1573939Y203264D02*
Y206464D01*
G01X1580139Y203264D02*
X1573939D01*
G01Y214464D02*
X1580139D01*
Y211264D01*
X1573939D01*
Y214464D01*
G01Y215264D02*
Y218464D01*
G01X1580139Y215264D02*
X1573939D01*
G01Y218464D02*
X1580139D01*
G01X1573939Y220264D02*
Y223464D01*
G01X1580139Y220264D02*
X1573939D01*
G01Y223464D02*
X1580139D01*
G01X1573936Y227319D02*
X1580136D01*
Y224119D01*
X1573936D01*
Y227319D01*
G01X1571655Y234813D02*
Y250325D01*
G01X1566699Y264635D02*
X1582211D01*
G01X1566699Y295727D02*
Y264635D01*
G01X1565067Y279901D02*
Y273701D01*
G01X1582211Y295727D02*
X1566699D01*
G01X1562979Y317963D02*
Y314763D01*
G01Y326963D02*
Y323763D01*
G01X1570100Y334600D02*
Y337800D01*
G01X1576300Y334600D02*
X1570100D01*
G01X1576300Y337800D02*
Y334600D01*
G01X1570100Y337800D02*
X1576300D01*
G01X1562979Y331463D02*
Y328263D01*
G01Y335963D02*
Y332763D01*
G01Y344963D02*
Y341763D01*
G01X1576300Y343200D02*
Y340000D01*
G01X1570100Y343200D02*
X1576300D01*
G01X1570100Y340000D02*
Y343200D01*
G01X1576300Y340000D02*
X1570100D01*
G01X1562979Y353963D02*
Y350763D01*
G01X1575305Y366063D02*
Y391537D01*
G01X1567809Y366063D02*
X1575305D01*
G01Y408102D02*
Y412746D01*
G01Y401039D02*
Y405714D01*
G01Y393802D02*
Y398671D01*
G01Y422281D02*
Y426977D01*
G01Y415104D02*
Y419739D01*
G01Y436398D02*
Y441124D01*
G01Y429376D02*
Y433999D01*
G01Y451956D02*
Y443420D01*
G01Y472291D02*
Y476944D01*
G01Y459056D02*
Y469892D01*
G01Y486417D02*
Y491184D01*
G01Y479302D02*
Y484110D01*
G01Y493480D02*
Y514036D01*
G01Y516322D02*
Y521079D01*
G01Y580396D02*
Y537748D01*
G01Y530592D02*
Y535257D01*
G01Y523437D02*
Y528152D01*
G01Y587506D02*
Y639449D01*
G01X1569069Y659952D02*
Y651488D01*
G01X1573838Y651636D02*
X1570638D01*
G01X1573838Y657836D02*
Y651636D01*
G01X1570638D02*
Y657836D01*
G01X1577838Y651636D02*
X1574638D01*
G01X1577838Y657836D02*
Y651636D01*
G01X1574638D02*
Y657836D01*
G01X1575305Y639449D02*
X1567859D01*
G01X1563938Y659952D02*
X1569069D01*
G01X1575372Y675683D02*
Y669083D01*
G01X1574601Y667875D02*
Y664675D01*
G01X1568401Y667875D02*
X1574601D01*
G01X1568401Y664675D02*
Y667875D01*
G01X1574601Y664675D02*
X1568401D01*
G01X1570616Y658802D02*
Y662002D01*
G01X1576816Y658802D02*
X1570616D01*
G01X1576816Y662002D02*
Y658802D01*
G01X1570616Y662002D02*
X1576816D01*
G01X1570638Y657836D02*
X1573838D01*
G01X1574638D02*
X1577838D01*
G01X1572872Y677183D02*
X1575372Y675683D01*
G01Y678683D02*
X1572872Y677183D01*
G01X1575372Y685283D02*
Y678683D01*
G01X1568000Y697550D02*
X1567948Y697243D01*
X1567742Y696975D01*
X1567432Y696745D01*
X1567070Y696592D01*
X1566657Y696515D01*
X1566243D01*
X1565830Y696592D01*
X1565468Y696745D01*
X1565158Y696975D01*
X1564952Y697243D01*
X1564900Y697550D01*
X1564952Y697857D01*
X1565158Y698125D01*
X1565468Y698355D01*
X1565830Y698508D01*
X1566243Y698585D01*
X1566657D01*
X1567070Y698508D01*
X1567432Y698355D01*
X1567742Y698125D01*
X1567948Y697857D01*
X1568000Y697550D01*
G01X1567173Y697857D02*
X1568000Y698317D01*
G01Y700573D02*
X1567328Y700650D01*
X1566760Y700765D01*
X1566243Y700918D01*
X1565675Y701110D01*
X1564900Y701417D01*
Y699883D01*
G01X1577714Y696206D02*
X1575383Y698537D01*
G01X1577714Y693097D02*
Y696206D01*
G01X1569052Y693097D02*
X1577714D01*
G01X1569052Y703977D02*
Y693097D01*
G01X1577714Y700868D02*
Y703977D01*
G01X1575383Y698537D02*
X1577714Y700868D01*
G01X1574637Y688094D02*
Y691294D01*
G01X1580837Y688094D02*
X1574637D01*
G01Y691294D02*
X1580837D01*
G01X1577714Y703977D02*
X1569052D01*
G01X1576717Y711729D02*
Y708529D01*
G01X1570517Y711729D02*
X1576717D01*
G01X1570517Y708529D02*
Y711729D01*
G01X1576717Y708529D02*
X1570517D01*
G01X1584028Y903558D02*
Y901608D01*
X1574028D01*
G01D02*
Y913558D01*
G01Y919658D02*
Y931608D01*
X1584028D01*
Y929658D01*
G01X1574227Y969557D02*
X1574589Y969787D01*
X1574795Y970093D01*
X1574847Y970438D01*
X1574795Y970745D01*
X1574537Y971052D01*
X1574227Y971243D01*
X1573917Y971282D01*
X1573555Y971205D01*
X1573297Y970937D01*
X1573194Y970668D01*
Y970323D01*
G01Y970668D02*
X1573039Y970898D01*
X1572780Y971090D01*
X1572470Y971167D01*
X1572160Y971090D01*
X1571902Y970898D01*
X1571747Y970553D01*
X1571799Y970208D01*
X1572005Y969863D01*
G01X1563014Y987350D02*
Y973450D01*
G01X1574567Y1689331D02*
Y1425158D01*
G01X1562756Y1436969D02*
Y1677520D01*
G01X1572894Y1462054D02*
X1565394D01*
Y1464294D01*
X1565769Y1465041D01*
X1566644Y1465601D01*
X1567644Y1465788D01*
X1568644Y1465601D01*
X1569394Y1465134D01*
X1569769Y1464294D01*
Y1462054D01*
G01X1572894Y1469554D02*
X1565394D01*
Y1471888D01*
X1565769Y1472634D01*
X1566269Y1473101D01*
X1567269Y1473288D01*
X1568269Y1473101D01*
X1568894Y1472541D01*
X1569269Y1471888D01*
Y1469554D01*
G01Y1471888D02*
X1572894Y1473288D01*
G01Y1480788D02*
Y1477054D01*
X1565394D01*
Y1480788D01*
G01X1569019Y1479294D02*
Y1477054D01*
G01X1571894Y1484461D02*
X1572519Y1485208D01*
X1572894Y1486048D01*
Y1486794D01*
X1572519Y1487541D01*
X1571894Y1488101D01*
X1571019Y1488381D01*
X1570144Y1488194D01*
X1569394Y1487728D01*
X1568894Y1486888D01*
X1568644Y1485768D01*
X1568144Y1485114D01*
X1567269Y1484834D01*
X1566394Y1485021D01*
X1565769Y1485488D01*
X1565394Y1486141D01*
Y1486794D01*
X1565644Y1487448D01*
X1566269Y1488008D01*
G01X1571894Y1491961D02*
X1572519Y1492708D01*
X1572894Y1493548D01*
Y1494294D01*
X1572519Y1495041D01*
X1571894Y1495601D01*
X1571019Y1495881D01*
X1570144Y1495694D01*
X1569394Y1495228D01*
X1568894Y1494388D01*
X1568644Y1493268D01*
X1568144Y1492614D01*
X1567269Y1492334D01*
X1566394Y1492521D01*
X1565769Y1492988D01*
X1565394Y1493641D01*
Y1494294D01*
X1565644Y1494948D01*
X1566269Y1495508D01*
G01X1570394Y1500208D02*
Y1502634D01*
G01X1572894Y1507148D02*
X1565394D01*
Y1510694D01*
G01X1569019Y1509388D02*
Y1507148D01*
G01X1565394Y1515301D02*
Y1517541D01*
G01Y1516421D02*
X1572894D01*
G01Y1515301D02*
Y1517541D01*
G01X1565394Y1523921D02*
X1572894D01*
G01X1565394Y1521774D02*
Y1526068D01*
G01X1584312Y1593817D02*
X1585112Y1594317D01*
X1585645Y1594917D01*
X1585912Y1595617D01*
X1585645Y1596417D01*
X1585112Y1597017D01*
X1584312Y1597617D01*
X1583245Y1597817D01*
X1577912D01*
G01X1585912Y1603817D02*
X1577912D01*
X1579512Y1602617D01*
G01X1585912D02*
Y1605017D01*
G01Y1613017D02*
X1577912D01*
X1583645Y1609317D01*
Y1614317D01*
G01X1591056Y-62706D02*
Y-79306D01*
X1581456D01*
Y-62706D01*
X1591056D01*
G01X1585900Y67907D02*
X1588122D01*
X1588587Y68060D01*
X1588897Y68367D01*
X1589000Y68750D01*
X1588897Y69133D01*
X1588587Y69440D01*
X1588122Y69593D01*
X1585900D01*
G01X1589000Y71850D02*
X1585900D01*
X1586520Y71390D01*
G01X1589000D02*
Y72310D01*
G01X1588380Y74107D02*
X1588742Y74337D01*
X1588948Y74643D01*
X1589000Y74988D01*
X1588948Y75295D01*
X1588690Y75602D01*
X1588380Y75793D01*
X1588070Y75832D01*
X1587708Y75755D01*
X1587450Y75487D01*
X1587347Y75218D01*
Y74873D01*
G01Y75218D02*
X1587192Y75448D01*
X1586933Y75640D01*
X1586623Y75717D01*
X1586313Y75640D01*
X1586055Y75448D01*
X1585900Y75103D01*
X1585952Y74758D01*
X1586158Y74413D01*
G01X1588638Y77398D02*
X1588897Y77667D01*
X1589000Y77973D01*
X1588897Y78280D01*
X1588587Y78548D01*
X1588122Y78740D01*
X1587657Y78817D01*
X1587088D01*
X1586623Y78740D01*
X1586210Y78548D01*
X1586003Y78318D01*
X1585900Y78050D01*
X1586003Y77743D01*
X1586210Y77513D01*
X1586520Y77360D01*
X1586933Y77283D01*
X1587295Y77360D01*
X1587657Y77552D01*
X1587863Y77782D01*
X1587915Y78050D01*
X1587812Y78357D01*
X1587553Y78587D01*
X1587088Y78817D01*
G01X1584490Y79047D02*
Y67523D01*
G01X1579183Y59613D02*
Y56413D01*
G01X1579393Y93476D02*
Y87276D01*
G01X1587249Y87299D02*
X1584049D01*
G01X1587249Y93499D02*
Y87299D01*
G01X1584049Y93499D02*
X1587249D01*
G01X1584049Y87299D02*
Y93499D01*
G01X1583342Y87204D02*
X1580142D01*
G01X1583342Y93404D02*
Y87204D01*
G01X1580142Y93404D02*
X1583342D01*
G01X1580142Y87204D02*
Y93404D01*
G01X1594221Y110172D02*
Y122172D01*
G01X1600221Y110172D02*
X1594221D01*
G01X1579884Y118151D02*
Y111951D01*
G01X1591604Y109424D02*
X1594804D01*
G01X1591604Y103224D02*
Y109424D01*
G01X1594804Y103224D02*
X1591604D01*
G01X1594804Y109424D02*
Y103224D01*
G01X1587604Y109424D02*
X1590804D01*
G01X1587604Y103224D02*
Y109424D01*
G01X1590804Y103224D02*
X1587604D01*
G01X1590804Y109424D02*
Y103224D01*
G01X1583604Y109424D02*
X1586804D01*
G01X1583604Y103224D02*
Y109424D01*
G01X1586804Y103224D02*
X1583604D01*
G01X1586804Y109424D02*
Y103224D01*
G01X1582058Y111734D02*
Y123508D01*
G01X1591820Y111734D02*
X1582058D01*
G01X1591820Y123508D02*
Y111734D01*
G01X1594221Y122172D02*
X1600221D01*
G01X1592829Y126223D02*
X1589629D01*
G01X1592829Y132423D02*
Y126223D01*
G01X1589629Y132423D02*
X1592829D01*
G01X1589629Y126223D02*
Y132423D01*
G01X1584829Y126223D02*
X1581629D01*
G01X1584829Y132423D02*
Y126223D01*
G01X1581629Y132423D02*
X1584829D01*
G01X1581629Y126223D02*
Y132423D01*
G01X1585629D02*
X1588829D01*
G01X1585629Y126223D02*
Y132423D01*
G01X1588829Y126223D02*
X1585629D01*
G01X1588829Y132423D02*
Y126223D01*
G01X1596883Y126228D02*
X1593683D01*
G01Y132428D02*
X1596883D01*
G01X1593683Y126228D02*
Y132428D01*
G01X1582058Y123508D02*
X1591820D01*
G01X1597062Y141337D02*
X1593862D01*
G01Y147537D02*
X1597062D01*
G01X1593862Y141337D02*
Y147537D01*
G01X1582018Y146229D02*
X1578818D01*
G01X1582018Y152429D02*
Y146229D01*
G01X1578818D02*
Y152429D01*
G01X1593727Y133238D02*
Y136438D01*
G01X1599927Y133238D02*
X1593727D01*
G01Y136438D02*
X1599927D01*
G01X1593727Y137238D02*
Y140438D01*
G01X1599927Y137238D02*
X1593727D01*
G01Y140438D02*
X1599927D01*
G01X1580508Y144395D02*
Y135095D01*
G01X1591108Y144395D02*
X1580508D01*
G01X1591108Y134995D02*
Y144395D01*
G01X1580508Y134995D02*
X1591108D01*
G01X1578818Y152429D02*
X1582018D01*
G01X1578818Y159540D02*
X1582018D01*
G01X1578818Y153340D02*
Y159540D01*
G01X1582018Y153340D02*
X1578818D01*
G01X1582018Y159540D02*
Y153340D01*
G01X1588731Y149950D02*
Y165304D01*
G01X1601409Y149950D02*
X1588731D01*
G01X1588928Y165304D02*
X1601409D01*
G01X1585783Y179600D02*
Y182700D01*
X1586703D01*
X1587010Y182545D01*
X1587240Y182183D01*
X1587317Y181770D01*
X1587240Y181357D01*
X1587048Y181047D01*
X1586703Y180892D01*
X1585783D01*
G01X1588807Y179600D02*
Y182700D01*
X1589573D01*
X1589880Y182545D01*
X1590110Y182338D01*
X1590302Y182028D01*
X1590455Y181667D01*
X1590493Y181150D01*
X1590455Y180633D01*
X1590302Y180272D01*
X1590110Y179962D01*
X1589880Y179755D01*
X1589573Y179600D01*
X1588807D01*
G01X1592673D02*
X1592750Y180272D01*
X1592865Y180840D01*
X1593018Y181357D01*
X1593210Y181925D01*
X1593517Y182700D01*
X1591983D01*
G01X1595007Y180220D02*
X1595237Y179858D01*
X1595543Y179652D01*
X1595888Y179600D01*
X1596195Y179652D01*
X1596502Y179910D01*
X1596693Y180220D01*
X1596732Y180530D01*
X1596655Y180892D01*
X1596387Y181150D01*
X1596118Y181253D01*
X1595773D01*
G01X1596118D02*
X1596348Y181408D01*
X1596540Y181667D01*
X1596617Y181977D01*
X1596540Y182287D01*
X1596348Y182545D01*
X1596003Y182700D01*
X1595658Y182648D01*
X1595313Y182442D01*
G01X1580044Y170265D02*
Y167065D01*
G01Y178265D02*
Y175065D01*
G01Y174265D02*
Y171065D01*
G01Y182265D02*
Y179065D01*
G01X1581612Y189435D02*
X1583852D01*
G01X1582639Y191060D02*
Y187810D01*
G01X1585253Y195583D02*
X1614812D01*
G01X1585253Y184087D02*
Y195583D01*
G01X1614812Y184087D02*
X1585253D01*
G01X1604229Y197645D02*
X1592229D01*
G01D02*
Y203645D01*
G01X1580044Y186265D02*
Y183065D01*
G01Y194265D02*
Y191065D01*
G01Y190265D02*
Y187065D01*
G01Y198265D02*
Y195065D01*
G01X1592229Y203645D02*
X1604229D01*
G01X1585406Y204506D02*
Y216506D01*
G01X1591406Y204506D02*
X1585406D01*
G01X1591406Y216506D02*
Y204506D01*
G01X1592206Y208306D02*
Y214506D01*
G01X1595406Y208306D02*
X1592206D01*
G01X1580139Y210464D02*
Y207264D01*
G01Y206464D02*
Y203264D01*
G01X1585406Y216506D02*
X1591406D01*
G01X1580139Y218464D02*
Y215264D01*
G01Y223464D02*
Y220264D01*
G01X1592206Y214506D02*
X1595406D01*
G01X1592572Y245521D02*
Y254969D01*
G01X1603408Y245521D02*
X1592572D01*
G01X1596148Y231334D02*
X1592948D01*
G01Y237534D02*
X1596148D01*
G01X1592948Y231334D02*
Y237534D01*
G01X1584204Y246771D02*
Y249971D01*
G01X1590404Y246771D02*
X1584204D01*
G01X1590404Y249971D02*
Y246771D01*
G01X1594374Y243678D02*
Y240478D01*
G01X1588174Y243678D02*
X1594374D01*
G01X1588174Y240478D02*
Y243678D01*
G01X1594374Y240478D02*
X1588174D01*
G01X1593350Y256200D02*
X1593043Y256252D01*
X1592775Y256458D01*
X1592545Y256768D01*
X1592392Y257130D01*
X1592315Y257543D01*
Y257957D01*
X1592392Y258370D01*
X1592545Y258732D01*
X1592775Y259042D01*
X1593043Y259248D01*
X1593350Y259300D01*
X1593657Y259248D01*
X1593925Y259042D01*
X1594155Y258732D01*
X1594308Y258370D01*
X1594385Y257957D01*
Y257543D01*
X1594308Y257130D01*
X1594155Y256768D01*
X1593925Y256458D01*
X1593657Y256252D01*
X1593350Y256200D01*
G01X1593657Y257027D02*
X1594117Y256200D01*
G01X1595722Y258783D02*
X1595952Y259093D01*
X1596220Y259248D01*
X1596527Y259300D01*
X1596910Y259197D01*
X1597178Y258938D01*
X1597255Y258628D01*
X1597217Y258318D01*
X1597063Y258060D01*
X1596297Y257543D01*
X1595952Y257182D01*
X1595722Y256665D01*
X1595645Y256200D01*
X1597255D01*
G01X1599550D02*
Y259300D01*
X1599090Y258680D01*
G01Y256200D02*
X1600010D01*
G01X1602650Y259300D02*
X1602343Y259197D01*
X1602113Y258938D01*
X1601960Y258628D01*
X1601845Y258215D01*
X1601807Y257750D01*
X1601845Y257285D01*
X1601960Y256872D01*
X1602113Y256562D01*
X1602343Y256303D01*
X1602650Y256200D01*
X1602957Y256303D01*
X1603187Y256562D01*
X1603340Y256872D01*
X1603455Y257285D01*
X1603493Y257750D01*
X1603455Y258215D01*
X1603340Y258628D01*
X1603187Y258938D01*
X1602957Y259197D01*
X1602650Y259300D01*
G01X1592572Y254969D02*
X1595990D01*
G01X1584204Y249971D02*
X1590404D01*
G01Y253971D02*
Y250771D01*
G01X1584204Y253971D02*
X1590404D01*
G01X1584204Y250771D02*
Y253971D01*
G01X1590404Y250771D02*
X1584204D01*
G01X1586800Y264783D02*
X1583700D01*
Y265703D01*
X1583855Y266010D01*
X1584217Y266240D01*
X1584630Y266317D01*
X1585043Y266240D01*
X1585353Y266048D01*
X1585508Y265703D01*
Y264783D01*
G01X1586800Y267807D02*
X1583700D01*
Y268573D01*
X1583855Y268880D01*
X1584062Y269110D01*
X1584372Y269302D01*
X1584733Y269455D01*
X1585250Y269493D01*
X1585767Y269455D01*
X1586128Y269302D01*
X1586438Y269110D01*
X1586645Y268880D01*
X1586800Y268573D01*
Y267807D01*
G01Y271750D02*
X1583700D01*
X1584320Y271290D01*
G01X1586800D02*
Y272210D01*
G01Y274850D02*
X1583700D01*
X1584320Y274390D01*
G01X1586800D02*
Y275310D01*
G01Y277873D02*
X1586128Y277950D01*
X1585560Y278065D01*
X1585043Y278218D01*
X1584475Y278410D01*
X1583700Y278717D01*
Y277183D01*
G01X1582211Y264635D02*
Y295727D01*
G01X1585907Y332300D02*
Y330078D01*
X1586060Y329613D01*
X1586367Y329303D01*
X1586750Y329200D01*
X1587133Y329303D01*
X1587440Y329613D01*
X1587593Y330078D01*
Y332300D01*
G01X1590310Y329200D02*
Y332300D01*
X1588892Y330078D01*
X1590808D01*
G01X1592222Y331783D02*
X1592452Y332093D01*
X1592720Y332248D01*
X1593027Y332300D01*
X1593410Y332197D01*
X1593678Y331938D01*
X1593755Y331628D01*
X1593717Y331318D01*
X1593563Y331060D01*
X1592797Y330543D01*
X1592452Y330182D01*
X1592222Y329665D01*
X1592145Y329200D01*
X1593755D01*
G01X1596050D02*
Y332300D01*
X1595590Y331680D01*
G01Y329200D02*
X1596510D01*
G01X1585238Y333487D02*
Y345691D01*
G01X1588000Y333487D02*
X1585238D01*
G01X1591000Y336589D02*
X1588000Y333487D01*
G01X1594102D02*
X1591000Y336589D01*
G01X1596762Y333487D02*
X1594102D01*
G01X1585238Y345691D02*
X1596762D01*
G01X1594160Y460400D02*
Y457200D01*
G01X1587960D02*
Y460400D01*
G01X1594160Y457200D02*
X1587960D01*
G01Y461200D02*
Y464400D01*
G01X1594160Y461200D02*
X1587960D01*
G01X1594160Y464400D02*
Y461200D01*
G01X1587960Y464400D02*
X1594160D01*
G01X1587960Y460400D02*
X1594160D01*
G01X1588160Y548200D02*
Y551400D01*
G01X1594360Y548200D02*
X1588160D01*
G01X1594360Y551400D02*
Y548200D01*
G01X1588160Y551400D02*
X1594360D01*
G01Y547400D02*
Y544200D01*
G01X1588160Y547400D02*
X1594360D01*
G01X1588160Y544200D02*
Y547400D01*
G01X1594360Y544200D02*
X1588160D01*
G01Y557200D02*
Y560400D01*
G01X1594360Y557200D02*
X1588160D01*
G01X1594360Y560400D02*
Y557200D01*
G01X1588160Y560400D02*
X1594360D01*
G01X1588160Y561200D02*
Y564400D01*
G01X1594360Y561200D02*
X1588160D01*
G01X1594360Y564400D02*
Y561200D01*
G01X1588160Y564400D02*
X1594360D01*
G01X1588560Y619800D02*
Y623000D01*
G01X1594760Y619800D02*
X1588560D01*
G01X1594760Y623000D02*
Y619800D01*
G01X1588560Y623000D02*
X1594760D01*
G01X1588560Y623800D02*
Y627000D01*
G01X1594760Y623800D02*
X1588560D01*
G01X1594760Y627000D02*
Y623800D01*
G01X1588560Y627000D02*
X1594760D01*
G01X1580837Y691294D02*
Y688094D01*
G01X1595241Y905765D02*
X1595603Y905995D01*
X1595809Y906301D01*
X1595861Y906646D01*
X1595809Y906953D01*
X1595551Y907260D01*
X1595241Y907451D01*
X1594931Y907490D01*
X1594569Y907413D01*
X1594311Y907145D01*
X1594208Y906876D01*
Y906531D01*
G01Y906876D02*
X1594053Y907106D01*
X1593794Y907298D01*
X1593484Y907375D01*
X1593174Y907298D01*
X1592916Y907106D01*
X1592761Y906761D01*
X1592813Y906416D01*
X1593019Y906071D01*
G01X1584028Y923558D02*
Y909658D01*
G01X1593879Y1021310D02*
Y1029310D01*
X1596279D01*
X1597079Y1028910D01*
X1597679Y1027977D01*
X1597879Y1026910D01*
X1597679Y1025843D01*
X1597179Y1025043D01*
X1596279Y1024643D01*
X1593879D01*
G01X1605879Y1021310D02*
X1601879D01*
Y1029310D01*
X1605879D01*
G01X1604279Y1025443D02*
X1601879D01*
G01X1609779Y1021310D02*
X1613979Y1029310D01*
G01X1609779D02*
X1613979Y1021310D01*
G01X1617679Y1022910D02*
X1618279Y1021977D01*
X1619079Y1021443D01*
X1619979Y1021310D01*
X1620779Y1021443D01*
X1621579Y1022110D01*
X1622079Y1022910D01*
X1622179Y1023710D01*
X1621979Y1024643D01*
X1621279Y1025310D01*
X1620579Y1025577D01*
X1619679D01*
G01X1620579D02*
X1621179Y1025977D01*
X1621679Y1026643D01*
X1621879Y1027443D01*
X1621679Y1028243D01*
X1621179Y1028910D01*
X1620279Y1029310D01*
X1619379Y1029177D01*
X1618479Y1028643D01*
G01X1589182Y1448088D02*
X1595382D01*
Y1444888D01*
X1589182D01*
Y1448088D01*
G01X1595408Y1440957D02*
X1589208D01*
Y1444157D01*
X1595408D01*
Y1440957D01*
G01X1586146Y1456032D02*
Y1462232D01*
X1589346D01*
Y1456032D01*
X1586146D01*
G01X1595864Y1468415D02*
X1592664D01*
G01Y1474615D02*
X1595864D01*
G01X1592664Y1468415D02*
Y1474615D01*
G01X1604548Y1481991D02*
X1592344D01*
G01Y1493515D02*
X1604548D01*
G01X1592344Y1490753D02*
Y1493515D01*
G01X1595446Y1487753D02*
X1592344Y1490753D01*
G01Y1484651D02*
X1595446Y1487753D01*
G01X1592344Y1481991D02*
Y1484651D01*
G01X1592707Y1506655D02*
X1595907D01*
G01X1592707Y1500455D02*
Y1506655D01*
G01X1595907Y1500455D02*
X1592707D01*
G01X1592900Y1513600D02*
X1596100D01*
G01X1592900Y1507400D02*
Y1513600D01*
G01X1596100Y1507400D02*
X1592900D01*
G01X1591634Y1564843D02*
X1619390D01*
G01X1591634Y1690040D02*
Y1564843D01*
G01X1619390Y1647992D02*
X1591634D01*
G01X1619390Y1690040D02*
X1591634D01*
G01X1609454Y57750D02*
X1609764Y57942D01*
X1609971Y58172D01*
X1610074Y58440D01*
X1609971Y58747D01*
X1609764Y58977D01*
X1609454Y59207D01*
X1609041Y59284D01*
X1606974D01*
G01X1610074Y62077D02*
X1606974D01*
X1609196Y60659D01*
Y62575D01*
G01X1610074Y65177D02*
X1606974D01*
X1609196Y63759D01*
Y65675D01*
G01X1603482Y96067D02*
Y99267D01*
G01X1609682Y96067D02*
X1603482D01*
G01X1609682Y99267D02*
Y96067D01*
G01X1603482Y99267D02*
X1609682D01*
G01X1600221Y122172D02*
Y110172D01*
G01X1605498Y108095D02*
Y104895D01*
G01X1599298Y108095D02*
X1605498D01*
G01X1599298Y104895D02*
Y108095D01*
G01X1605498Y104895D02*
X1599298D01*
G01X1606355Y108086D02*
X1609555D01*
G01X1606355Y101886D02*
Y108086D01*
G01X1609555Y101886D02*
X1606355D01*
G01X1609555Y108086D02*
Y101886D01*
G01X1599298Y100895D02*
Y104095D01*
G01X1605498Y100895D02*
X1599298D01*
G01X1605498Y104095D02*
Y100895D01*
G01X1599298Y104095D02*
X1605498D01*
G01X1596883Y132428D02*
Y126228D01*
G01X1597062Y147537D02*
Y141337D01*
G01X1600273Y148437D02*
X1603473D01*
G01X1600273Y142237D02*
Y148437D01*
G01X1603473Y142237D02*
X1600273D01*
G01X1603473Y148437D02*
Y142237D01*
G01X1599927Y136438D02*
Y133238D01*
G01Y140438D02*
Y137238D01*
G01X1602700Y152907D02*
X1604922D01*
X1605387Y153060D01*
X1605697Y153367D01*
X1605800Y153750D01*
X1605697Y154133D01*
X1605387Y154440D01*
X1604922Y154593D01*
X1602700D01*
G01X1605180Y156007D02*
X1605542Y156237D01*
X1605748Y156543D01*
X1605800Y156888D01*
X1605748Y157195D01*
X1605490Y157502D01*
X1605180Y157693D01*
X1604870Y157732D01*
X1604508Y157655D01*
X1604250Y157387D01*
X1604147Y157118D01*
Y156773D01*
G01Y157118D02*
X1603992Y157348D01*
X1603733Y157540D01*
X1603423Y157617D01*
X1603113Y157540D01*
X1602855Y157348D01*
X1602700Y157003D01*
X1602752Y156658D01*
X1602958Y156313D01*
G01X1605800Y159873D02*
X1605128Y159950D01*
X1604560Y160065D01*
X1604043Y160218D01*
X1603475Y160410D01*
X1602700Y160717D01*
Y159183D01*
G01X1604508Y162322D02*
X1604147Y162590D01*
X1603940Y162820D01*
X1603837Y163127D01*
X1603940Y163395D01*
X1604147Y163587D01*
X1604457Y163740D01*
X1604818Y163778D01*
X1605128Y163740D01*
X1605438Y163587D01*
X1605697Y163357D01*
X1605800Y163088D01*
X1605697Y162782D01*
X1605387Y162513D01*
X1604922Y162360D01*
X1604405Y162322D01*
X1603733Y162398D01*
X1603372Y162513D01*
X1603010Y162705D01*
X1602752Y162973D01*
X1602700Y163242D01*
X1602803Y163510D01*
X1603062Y163702D01*
G01X1601409Y165304D02*
Y149950D01*
G01X1604229Y203645D02*
Y197645D01*
G01X1595406Y214506D02*
Y208306D01*
G01X1602182Y208464D02*
Y205264D01*
G01X1595982Y208464D02*
X1602182D01*
G01X1595982Y205264D02*
Y208464D01*
G01X1602182Y205264D02*
X1595982D01*
G01X1597012Y226801D02*
X1609216D01*
Y211497D01*
X1597012D01*
Y226801D01*
G01X1603408Y254969D02*
Y245521D01*
G01X1613785Y231459D02*
X1610585D01*
G01Y237659D02*
X1613785D01*
G01X1610585Y231459D02*
Y237659D01*
G01X1601675Y231446D02*
X1598475D01*
G01X1601675Y237646D02*
Y231446D01*
G01X1598475Y237646D02*
X1601675D01*
G01X1598475Y231446D02*
Y237646D01*
G01X1596148Y237534D02*
Y231334D01*
G01X1605550Y231434D02*
X1602350D01*
G01X1605550Y237634D02*
Y231434D01*
G01X1602350Y237634D02*
X1605550D01*
G01X1602350Y231434D02*
Y237634D01*
G01X1606585Y237659D02*
X1609785D01*
G01X1606585Y231459D02*
Y237659D01*
G01X1609785Y231459D02*
X1606585D01*
G01X1609785Y237659D02*
Y231459D01*
G01X1605211Y240081D02*
Y243281D01*
G01X1611411Y240081D02*
X1605211D01*
G01Y243281D02*
X1611411D01*
G01X1601353Y243678D02*
Y240478D01*
G01X1595153Y243678D02*
X1601353D01*
G01X1595153Y240478D02*
Y243678D01*
G01X1601353Y240478D02*
X1595153D01*
G01X1599990Y254969D02*
X1603408D01*
G01X1597990Y253245D02*
X1599990Y254969D01*
G01X1595990D02*
X1597990Y253245D01*
G01X1611015Y252199D02*
Y248999D01*
G01X1604815Y252199D02*
X1611015D01*
G01X1604815Y248999D02*
Y252199D01*
G01X1611015Y248999D02*
X1604815D01*
G01X1596762Y345691D02*
Y333487D01*
G01X1607197Y337852D02*
X1613397D01*
G01X1607197Y334652D02*
Y337852D01*
G01X1613397Y334652D02*
X1607197D01*
G01Y342652D02*
Y345852D01*
G01X1613397Y342652D02*
X1607197D01*
G01Y341852D02*
X1613397D01*
G01X1607197Y338652D02*
Y341852D01*
G01X1613397Y338652D02*
X1607197D01*
G01Y345852D02*
X1613397D01*
G01X1606624Y386318D02*
Y383118D01*
G01X1600424Y386318D02*
X1606624D01*
G01X1600424Y383118D02*
Y386318D01*
G01X1606624Y383118D02*
X1600424D01*
G01X1606624Y382318D02*
Y379118D01*
G01X1600424Y382318D02*
X1606624D01*
G01X1600424Y379118D02*
Y382318D01*
G01X1606624Y379118D02*
X1600424D01*
G01X1606624Y394318D02*
Y391118D01*
G01X1600424D02*
Y394318D01*
G01X1606624Y391118D02*
X1600424D01*
G01Y387118D02*
Y390318D01*
G01X1606624Y387118D02*
X1600424D01*
G01X1606624Y390318D02*
Y387118D01*
G01X1600424Y390318D02*
X1606624D01*
G01X1600424Y394318D02*
X1606624D01*
G01Y402318D02*
Y399118D01*
G01X1600424Y402318D02*
X1606624D01*
G01X1600424Y399118D02*
Y402318D01*
G01X1606624Y399118D02*
X1600424D01*
G01X1606624Y406318D02*
Y403118D01*
G01X1600424Y406318D02*
X1606624D01*
G01X1600424Y403118D02*
Y406318D01*
G01X1606624Y403118D02*
X1600424D01*
G01X1606624Y410318D02*
Y407118D01*
G01X1600424D02*
Y410318D01*
G01X1606624Y407118D02*
X1600424D01*
G01X1606624Y398318D02*
Y395118D01*
G01X1600424Y398318D02*
X1606624D01*
G01X1600424Y395118D02*
Y398318D01*
G01X1606624Y395118D02*
X1600424D01*
G01Y410318D02*
X1606624D01*
G01Y414318D02*
Y411118D01*
G01X1600424Y414318D02*
X1606624D01*
G01X1600424Y411118D02*
Y414318D01*
G01X1606624Y411118D02*
X1600424D01*
G01X1602960Y555300D02*
Y552100D01*
G01X1596760Y555300D02*
X1602960D01*
G01X1596760Y552100D02*
Y555300D01*
G01X1602960Y552100D02*
X1596760D01*
G01Y548100D02*
Y551300D01*
G01X1602960Y548100D02*
X1596760D01*
G01X1602960Y551300D02*
Y548100D01*
G01X1596760Y551300D02*
X1602960D01*
G01Y559300D02*
Y556100D01*
G01X1596760Y559300D02*
X1602960D01*
G01X1596760Y556100D02*
Y559300D01*
G01X1602960Y556100D02*
X1596760D01*
G01X1611200Y632750D02*
X1611148Y632443D01*
X1610942Y632175D01*
X1610632Y631945D01*
X1610270Y631792D01*
X1609857Y631715D01*
X1609443D01*
X1609030Y631792D01*
X1608668Y631945D01*
X1608358Y632175D01*
X1608152Y632443D01*
X1608100Y632750D01*
X1608152Y633057D01*
X1608358Y633325D01*
X1608668Y633555D01*
X1609030Y633708D01*
X1609443Y633785D01*
X1609857D01*
X1610270Y633708D01*
X1610632Y633555D01*
X1610942Y633325D01*
X1611148Y633057D01*
X1611200Y632750D01*
G01X1610373Y633057D02*
X1611200Y633517D01*
G01Y635850D02*
X1608100D01*
X1608720Y635390D01*
G01X1611200D02*
Y636310D01*
G01X1608617Y638222D02*
X1608307Y638452D01*
X1608152Y638720D01*
X1608100Y639027D01*
X1608203Y639410D01*
X1608462Y639678D01*
X1608772Y639755D01*
X1609082Y639717D01*
X1609340Y639563D01*
X1609857Y638797D01*
X1610218Y638452D01*
X1610735Y638222D01*
X1611200Y638145D01*
Y639755D01*
G01X1608617Y641322D02*
X1608307Y641552D01*
X1608152Y641820D01*
X1608100Y642127D01*
X1608203Y642510D01*
X1608462Y642778D01*
X1608772Y642855D01*
X1609082Y642817D01*
X1609340Y642663D01*
X1609857Y641897D01*
X1610218Y641552D01*
X1610735Y641322D01*
X1611200Y641245D01*
Y642855D01*
G01X1607100Y660257D02*
X1609322D01*
X1609787Y660410D01*
X1610097Y660717D01*
X1610200Y661100D01*
X1610097Y661483D01*
X1609787Y661790D01*
X1609322Y661943D01*
X1607100D01*
G01X1610200Y664660D02*
X1607100D01*
X1609322Y663242D01*
Y665158D01*
G01X1607617Y666572D02*
X1607307Y666802D01*
X1607152Y667070D01*
X1607100Y667377D01*
X1607203Y667760D01*
X1607462Y668028D01*
X1607772Y668105D01*
X1608082Y668067D01*
X1608340Y667913D01*
X1608857Y667147D01*
X1609218Y666802D01*
X1609735Y666572D01*
X1610200Y666495D01*
Y668105D01*
G01X1615702Y698317D02*
X1609502D01*
Y701517D01*
X1615702D01*
Y698317D01*
G01X1611150Y707759D02*
X1610843Y707811D01*
X1610575Y708017D01*
X1610345Y708327D01*
X1610192Y708689D01*
X1610115Y709102D01*
Y709516D01*
X1610192Y709929D01*
X1610345Y710291D01*
X1610575Y710601D01*
X1610843Y710807D01*
X1611150Y710859D01*
X1611457Y710807D01*
X1611725Y710601D01*
X1611955Y710291D01*
X1612108Y709929D01*
X1612185Y709516D01*
Y709102D01*
X1612108Y708689D01*
X1611955Y708327D01*
X1611725Y708017D01*
X1611457Y707811D01*
X1611150Y707759D01*
G01X1611457Y708586D02*
X1611917Y707759D01*
G01X1613522Y710342D02*
X1613752Y710652D01*
X1614020Y710807D01*
X1614327Y710859D01*
X1614710Y710756D01*
X1614978Y710497D01*
X1615055Y710187D01*
X1615017Y709877D01*
X1614863Y709619D01*
X1614097Y709102D01*
X1613752Y708741D01*
X1613522Y708224D01*
X1613445Y707759D01*
X1615055D01*
G01X1616507Y708379D02*
X1616737Y708017D01*
X1617043Y707811D01*
X1617388Y707759D01*
X1617695Y707811D01*
X1618002Y708069D01*
X1618193Y708379D01*
X1618232Y708689D01*
X1618155Y709051D01*
X1617887Y709309D01*
X1617618Y709412D01*
X1617273D01*
G01X1617618D02*
X1617848Y709567D01*
X1618040Y709826D01*
X1618117Y710136D01*
X1618040Y710446D01*
X1617848Y710704D01*
X1617503Y710859D01*
X1617158Y710807D01*
X1616813Y710601D01*
G01X1620910Y707759D02*
Y710859D01*
X1619492Y708637D01*
X1621408D01*
G01X1615702Y716217D02*
X1609502D01*
Y719417D01*
X1615702D01*
Y716217D01*
G01X1610862Y725731D02*
X1610555Y725783D01*
X1610287Y725989D01*
X1610057Y726299D01*
X1609904Y726661D01*
X1609827Y727074D01*
Y727488D01*
X1609904Y727901D01*
X1610057Y728263D01*
X1610287Y728573D01*
X1610555Y728779D01*
X1610862Y728831D01*
X1611169Y728779D01*
X1611437Y728573D01*
X1611667Y728263D01*
X1611820Y727901D01*
X1611897Y727488D01*
Y727074D01*
X1611820Y726661D01*
X1611667Y726299D01*
X1611437Y725989D01*
X1611169Y725783D01*
X1610862Y725731D01*
G01X1611169Y726558D02*
X1611629Y725731D01*
G01X1613234Y728314D02*
X1613464Y728624D01*
X1613732Y728779D01*
X1614039Y728831D01*
X1614422Y728728D01*
X1614690Y728469D01*
X1614767Y728159D01*
X1614729Y727849D01*
X1614575Y727591D01*
X1613809Y727074D01*
X1613464Y726713D01*
X1613234Y726196D01*
X1613157Y725731D01*
X1614767D01*
G01X1616219Y726351D02*
X1616449Y725989D01*
X1616755Y725783D01*
X1617100Y725731D01*
X1617407Y725783D01*
X1617714Y726041D01*
X1617905Y726351D01*
X1617944Y726661D01*
X1617867Y727023D01*
X1617599Y727281D01*
X1617330Y727384D01*
X1616985D01*
G01X1617330D02*
X1617560Y727539D01*
X1617752Y727798D01*
X1617829Y728108D01*
X1617752Y728418D01*
X1617560Y728676D01*
X1617215Y728831D01*
X1616870Y728779D01*
X1616525Y728573D01*
G01X1619510Y726093D02*
X1619779Y725834D01*
X1620085Y725731D01*
X1620392Y725834D01*
X1620660Y726144D01*
X1620852Y726609D01*
X1620929Y727074D01*
Y727643D01*
X1620852Y728108D01*
X1620660Y728521D01*
X1620430Y728728D01*
X1620162Y728831D01*
X1619855Y728728D01*
X1619625Y728521D01*
X1619472Y728211D01*
X1619395Y727798D01*
X1619472Y727436D01*
X1619664Y727074D01*
X1619894Y726868D01*
X1620162Y726816D01*
X1620469Y726919D01*
X1620699Y727178D01*
X1620929Y727643D01*
G01X1616002Y730817D02*
X1609802D01*
Y734017D01*
X1616002D01*
Y730817D01*
G01X1610587Y739899D02*
X1610280Y739951D01*
X1610012Y740157D01*
X1609782Y740467D01*
X1609629Y740829D01*
X1609552Y741242D01*
Y741656D01*
X1609629Y742069D01*
X1609782Y742431D01*
X1610012Y742741D01*
X1610280Y742947D01*
X1610587Y742999D01*
X1610894Y742947D01*
X1611162Y742741D01*
X1611392Y742431D01*
X1611545Y742069D01*
X1611622Y741656D01*
Y741242D01*
X1611545Y740829D01*
X1611392Y740467D01*
X1611162Y740157D01*
X1610894Y739951D01*
X1610587Y739899D01*
G01X1610894Y740726D02*
X1611354Y739899D01*
G01X1612959Y742482D02*
X1613189Y742792D01*
X1613457Y742947D01*
X1613764Y742999D01*
X1614147Y742896D01*
X1614415Y742637D01*
X1614492Y742327D01*
X1614454Y742017D01*
X1614300Y741759D01*
X1613534Y741242D01*
X1613189Y740881D01*
X1612959Y740364D01*
X1612882Y739899D01*
X1614492D01*
G01X1615944Y740519D02*
X1616174Y740157D01*
X1616480Y739951D01*
X1616825Y739899D01*
X1617132Y739951D01*
X1617439Y740209D01*
X1617630Y740519D01*
X1617669Y740829D01*
X1617592Y741191D01*
X1617324Y741449D01*
X1617055Y741552D01*
X1616710D01*
G01X1617055D02*
X1617285Y741707D01*
X1617477Y741966D01*
X1617554Y742276D01*
X1617477Y742586D01*
X1617285Y742844D01*
X1616940Y742999D01*
X1616595Y742947D01*
X1616250Y742741D01*
G01X1619159Y742482D02*
X1619389Y742792D01*
X1619657Y742947D01*
X1619964Y742999D01*
X1620347Y742896D01*
X1620615Y742637D01*
X1620692Y742327D01*
X1620654Y742017D01*
X1620500Y741759D01*
X1619734Y741242D01*
X1619389Y740881D01*
X1619159Y740364D01*
X1619082Y739899D01*
X1620692D01*
G01X1603383Y770505D02*
X1603076Y770557D01*
X1602808Y770763D01*
X1602578Y771073D01*
X1602425Y771435D01*
X1602348Y771848D01*
Y772262D01*
X1602425Y772675D01*
X1602578Y773037D01*
X1602808Y773347D01*
X1603076Y773553D01*
X1603383Y773605D01*
X1603690Y773553D01*
X1603958Y773347D01*
X1604188Y773037D01*
X1604341Y772675D01*
X1604418Y772262D01*
Y771848D01*
X1604341Y771435D01*
X1604188Y771073D01*
X1603958Y770763D01*
X1603690Y770557D01*
X1603383Y770505D01*
G01X1603690Y771332D02*
X1604150Y770505D01*
G01X1605755Y773088D02*
X1605985Y773398D01*
X1606253Y773553D01*
X1606560Y773605D01*
X1606943Y773502D01*
X1607211Y773243D01*
X1607288Y772933D01*
X1607250Y772623D01*
X1607096Y772365D01*
X1606330Y771848D01*
X1605985Y771487D01*
X1605755Y770970D01*
X1605678Y770505D01*
X1607288D01*
G01X1608740Y771125D02*
X1608970Y770763D01*
X1609276Y770557D01*
X1609621Y770505D01*
X1609928Y770557D01*
X1610235Y770815D01*
X1610426Y771125D01*
X1610465Y771435D01*
X1610388Y771797D01*
X1610120Y772055D01*
X1609851Y772158D01*
X1609506D01*
G01X1609851D02*
X1610081Y772313D01*
X1610273Y772572D01*
X1610350Y772882D01*
X1610273Y773192D01*
X1610081Y773450D01*
X1609736Y773605D01*
X1609391Y773553D01*
X1609046Y773347D01*
G01X1611840Y771125D02*
X1612070Y770763D01*
X1612376Y770557D01*
X1612721Y770505D01*
X1613028Y770557D01*
X1613335Y770815D01*
X1613526Y771125D01*
X1613565Y771435D01*
X1613488Y771797D01*
X1613220Y772055D01*
X1612951Y772158D01*
X1612606D01*
G01X1612951D02*
X1613181Y772313D01*
X1613373Y772572D01*
X1613450Y772882D01*
X1613373Y773192D01*
X1613181Y773450D01*
X1612836Y773605D01*
X1612491Y773553D01*
X1612146Y773347D01*
G01X1610083Y785002D02*
Y778802D01*
X1606883D01*
Y785002D01*
X1610083D01*
G01X1609983Y799802D02*
Y793602D01*
X1606783D01*
Y799802D01*
X1609983D01*
G01X1609883Y813802D02*
Y807602D01*
X1606683D01*
Y813802D01*
X1609883D01*
G01X1602407Y823702D02*
X1602100Y823754D01*
X1601832Y823960D01*
X1601602Y824270D01*
X1601449Y824632D01*
X1601372Y825045D01*
Y825459D01*
X1601449Y825872D01*
X1601602Y826234D01*
X1601832Y826544D01*
X1602100Y826750D01*
X1602407Y826802D01*
X1602714Y826750D01*
X1602982Y826544D01*
X1603212Y826234D01*
X1603365Y825872D01*
X1603442Y825459D01*
Y825045D01*
X1603365Y824632D01*
X1603212Y824270D01*
X1602982Y823960D01*
X1602714Y823754D01*
X1602407Y823702D01*
G01X1602714Y824529D02*
X1603174Y823702D01*
G01X1604779Y826285D02*
X1605009Y826595D01*
X1605277Y826750D01*
X1605584Y826802D01*
X1605967Y826699D01*
X1606235Y826440D01*
X1606312Y826130D01*
X1606274Y825820D01*
X1606120Y825562D01*
X1605354Y825045D01*
X1605009Y824684D01*
X1604779Y824167D01*
X1604702Y823702D01*
X1606312D01*
G01X1607764Y824322D02*
X1607994Y823960D01*
X1608300Y823754D01*
X1608645Y823702D01*
X1608952Y823754D01*
X1609259Y824012D01*
X1609450Y824322D01*
X1609489Y824632D01*
X1609412Y824994D01*
X1609144Y825252D01*
X1608875Y825355D01*
X1608530D01*
G01X1608875D02*
X1609105Y825510D01*
X1609297Y825769D01*
X1609374Y826079D01*
X1609297Y826389D01*
X1609105Y826647D01*
X1608760Y826802D01*
X1608415Y826750D01*
X1608070Y826544D01*
G01X1611707Y823702D02*
X1611975Y823754D01*
X1612282Y823909D01*
X1612474Y824167D01*
X1612550Y824529D01*
X1612474Y824890D01*
X1612244Y825200D01*
X1611899Y825355D01*
X1611515D01*
X1611285Y825459D01*
X1611094Y825717D01*
X1611017Y826079D01*
X1611132Y826440D01*
X1611400Y826699D01*
X1611707Y826802D01*
X1612014Y826699D01*
X1612282Y826440D01*
X1612397Y826079D01*
X1612320Y825717D01*
X1612129Y825459D01*
X1611899Y825355D01*
X1611515D01*
X1611170Y825200D01*
X1610940Y824890D01*
X1610864Y824529D01*
X1610940Y824167D01*
X1611132Y823909D01*
X1611439Y823754D01*
X1611707Y823702D01*
G01X1601725Y879536D02*
X1601917Y879226D01*
X1602147Y879019D01*
X1602415Y878916D01*
X1602722Y879019D01*
X1602952Y879226D01*
X1603182Y879536D01*
X1603259Y879949D01*
Y882016D01*
G01X1604864Y880208D02*
X1605132Y880569D01*
X1605362Y880776D01*
X1605669Y880879D01*
X1605937Y880776D01*
X1606129Y880569D01*
X1606282Y880259D01*
X1606320Y879898D01*
X1606282Y879588D01*
X1606129Y879278D01*
X1605899Y879019D01*
X1605630Y878916D01*
X1605324Y879019D01*
X1605055Y879329D01*
X1604902Y879794D01*
X1604864Y880311D01*
X1604940Y880983D01*
X1605055Y881344D01*
X1605247Y881706D01*
X1605515Y881964D01*
X1605784Y882016D01*
X1606052Y881913D01*
X1606244Y881654D01*
G01X1608692Y878916D02*
X1608960Y878968D01*
X1609267Y879123D01*
X1609459Y879381D01*
X1609535Y879743D01*
X1609459Y880104D01*
X1609229Y880414D01*
X1608884Y880569D01*
X1608500D01*
X1608270Y880673D01*
X1608079Y880931D01*
X1608002Y881293D01*
X1608117Y881654D01*
X1608385Y881913D01*
X1608692Y882016D01*
X1608999Y881913D01*
X1609267Y881654D01*
X1609382Y881293D01*
X1609305Y880931D01*
X1609114Y880673D01*
X1608884Y880569D01*
X1608500D01*
X1608155Y880414D01*
X1607925Y880104D01*
X1607849Y879743D01*
X1607925Y879381D01*
X1608117Y879123D01*
X1608424Y878968D01*
X1608692Y878916D01*
G01X1601156Y950303D02*
X1601348Y949993D01*
X1601578Y949786D01*
X1601846Y949683D01*
X1602153Y949786D01*
X1602383Y949993D01*
X1602613Y950303D01*
X1602690Y950716D01*
Y952783D01*
G01X1604295Y950975D02*
X1604563Y951336D01*
X1604793Y951543D01*
X1605100Y951646D01*
X1605368Y951543D01*
X1605560Y951336D01*
X1605713Y951026D01*
X1605751Y950665D01*
X1605713Y950355D01*
X1605560Y950045D01*
X1605330Y949786D01*
X1605061Y949683D01*
X1604755Y949786D01*
X1604486Y950096D01*
X1604333Y950561D01*
X1604295Y951078D01*
X1604371Y951750D01*
X1604486Y952111D01*
X1604678Y952473D01*
X1604946Y952731D01*
X1605215Y952783D01*
X1605483Y952680D01*
X1605675Y952421D01*
G01X1607395Y950975D02*
X1607663Y951336D01*
X1607893Y951543D01*
X1608200Y951646D01*
X1608468Y951543D01*
X1608660Y951336D01*
X1608813Y951026D01*
X1608851Y950665D01*
X1608813Y950355D01*
X1608660Y950045D01*
X1608430Y949786D01*
X1608161Y949683D01*
X1607855Y949786D01*
X1607586Y950096D01*
X1607433Y950561D01*
X1607395Y951078D01*
X1607471Y951750D01*
X1607586Y952111D01*
X1607778Y952473D01*
X1608046Y952731D01*
X1608315Y952783D01*
X1608583Y952680D01*
X1608775Y952421D01*
G01X1601933Y1448085D02*
Y1441885D01*
X1598733D01*
Y1448085D01*
X1601933D01*
G01X1607840Y1455722D02*
X1607533Y1455774D01*
X1607265Y1455980D01*
X1607035Y1456290D01*
X1606882Y1456652D01*
X1606805Y1457065D01*
Y1457479D01*
X1606882Y1457892D01*
X1607035Y1458254D01*
X1607265Y1458564D01*
X1607533Y1458770D01*
X1607840Y1458822D01*
X1608147Y1458770D01*
X1608415Y1458564D01*
X1608645Y1458254D01*
X1608798Y1457892D01*
X1608875Y1457479D01*
Y1457065D01*
X1608798Y1456652D01*
X1608645Y1456290D01*
X1608415Y1455980D01*
X1608147Y1455774D01*
X1607840Y1455722D01*
G01X1608147Y1456549D02*
X1608607Y1455722D01*
G01X1610212Y1458305D02*
X1610442Y1458615D01*
X1610710Y1458770D01*
X1611017Y1458822D01*
X1611400Y1458719D01*
X1611668Y1458460D01*
X1611745Y1458150D01*
X1611707Y1457840D01*
X1611553Y1457582D01*
X1610787Y1457065D01*
X1610442Y1456704D01*
X1610212Y1456187D01*
X1610135Y1455722D01*
X1611745D01*
G01X1614500D02*
Y1458822D01*
X1613082Y1456600D01*
X1614998D01*
G01X1616412Y1458305D02*
X1616642Y1458615D01*
X1616910Y1458770D01*
X1617217Y1458822D01*
X1617600Y1458719D01*
X1617868Y1458460D01*
X1617945Y1458150D01*
X1617907Y1457840D01*
X1617753Y1457582D01*
X1616987Y1457065D01*
X1616642Y1456704D01*
X1616412Y1456187D01*
X1616335Y1455722D01*
X1617945D01*
G01X1605134Y1454401D02*
X1595686D01*
Y1465237D01*
X1605134D01*
Y1461819D01*
X1603410Y1459819D01*
X1605134Y1457819D01*
Y1454401D01*
G01X1595864Y1474615D02*
Y1468415D01*
G01X1600012Y1473573D02*
X1606212D01*
Y1470373D01*
X1600012D01*
Y1473573D01*
G01X1603966Y1466423D02*
X1597766D01*
Y1469623D01*
X1603966D01*
Y1466423D01*
G01X1607136Y1489575D02*
Y1487353D01*
X1607289Y1486888D01*
X1607596Y1486578D01*
X1607979Y1486475D01*
X1608362Y1486578D01*
X1608669Y1486888D01*
X1608822Y1487353D01*
Y1489575D01*
G01X1611539Y1486475D02*
Y1489575D01*
X1610121Y1487353D01*
X1612037D01*
G01X1613451Y1489058D02*
X1613681Y1489368D01*
X1613949Y1489523D01*
X1614256Y1489575D01*
X1614639Y1489472D01*
X1614907Y1489213D01*
X1614984Y1488903D01*
X1614946Y1488593D01*
X1614792Y1488335D01*
X1614026Y1487818D01*
X1613681Y1487457D01*
X1613451Y1486940D01*
X1613374Y1486475D01*
X1614984D01*
G01X1616551Y1489058D02*
X1616781Y1489368D01*
X1617049Y1489523D01*
X1617356Y1489575D01*
X1617739Y1489472D01*
X1618007Y1489213D01*
X1618084Y1488903D01*
X1618046Y1488593D01*
X1617892Y1488335D01*
X1617126Y1487818D01*
X1616781Y1487457D01*
X1616551Y1486940D01*
X1616474Y1486475D01*
X1618084D01*
G01X1604548Y1493515D02*
Y1481991D01*
G01X1595907Y1506655D02*
Y1500455D01*
G01X1603100Y1507400D02*
X1599900D01*
G01X1603100Y1513600D02*
Y1507400D01*
G01X1599900Y1513600D02*
X1603100D01*
G01X1599900Y1507400D02*
Y1513600D01*
G01X1599600Y1507400D02*
X1596400D01*
G01X1599600Y1513600D02*
Y1507400D01*
G01X1596400Y1513600D02*
X1599600D01*
G01X1596400Y1507400D02*
Y1513600D01*
G01X1610100Y1507400D02*
X1606900D01*
G01X1610100Y1513600D02*
Y1507400D01*
G01X1606900Y1513600D02*
X1610100D01*
G01X1606900Y1507400D02*
Y1513600D01*
G01X1603400D02*
X1606600D01*
G01X1603400Y1507400D02*
Y1513600D01*
G01X1606600Y1507400D02*
X1603400D01*
G01X1606600Y1513600D02*
Y1507400D01*
G01X1596100Y1513600D02*
Y1507400D01*
G01X1617285Y1526958D02*
X1611085D01*
Y1530158D01*
X1617285D01*
Y1526958D01*
G01X1609258Y1518715D02*
Y1524915D01*
X1612458D01*
Y1518715D01*
X1609258D01*
G01X1599742Y1531985D02*
Y1525785D01*
X1596542D01*
Y1531985D01*
X1599742D01*
G01X1608203Y1528934D02*
Y1525734D01*
G01X1602003Y1528934D02*
X1608203D01*
G01X1602003Y1525734D02*
Y1528934D01*
G01X1608203Y1525734D02*
X1602003D01*
G01X1616985Y1533658D02*
X1610785D01*
Y1536858D01*
X1616985D01*
Y1533658D01*
G01X1602003Y1537734D02*
Y1540934D01*
G01X1608203Y1537734D02*
X1602003D01*
G01X1608203Y1540934D02*
Y1537734D01*
G01X1602003Y1540934D02*
X1608203D01*
G01X1601991Y1544973D02*
X1608191D01*
Y1541773D01*
X1601991D01*
Y1544973D01*
G01X1614921Y58150D02*
Y111478D01*
G01X1614625Y57756D02*
Y111478D01*
G01X1621006Y57756D02*
X1614625D01*
G01X1620601Y58150D02*
X1614921D01*
G01Y118848D02*
Y114048D01*
G01X1614625Y118848D02*
Y114048D01*
G01X1614921Y132607D02*
Y128340D01*
G01X1614625Y132607D02*
Y128340D01*
G01Y125781D02*
Y121219D01*
G01X1614921Y125781D02*
Y121219D01*
G01X1614625Y153150D02*
Y135509D01*
G01X1614921Y152756D02*
Y135509D01*
G01X1626579Y156615D02*
X1627326Y155990D01*
X1628166Y155615D01*
X1628912D01*
X1629659Y155990D01*
X1630219Y156615D01*
X1630499Y157490D01*
X1630312Y158365D01*
X1629846Y159115D01*
X1629006Y159615D01*
X1627886Y159865D01*
X1627232Y160365D01*
X1626952Y161240D01*
X1627139Y162115D01*
X1627606Y162740D01*
X1628259Y163115D01*
X1628912D01*
X1629566Y162865D01*
X1630126Y162240D01*
G01X1634079Y156615D02*
X1634826Y155990D01*
X1635666Y155615D01*
X1636412D01*
X1637159Y155990D01*
X1637719Y156615D01*
X1637999Y157490D01*
X1637812Y158365D01*
X1637346Y159115D01*
X1636506Y159615D01*
X1635386Y159865D01*
X1634732Y160365D01*
X1634452Y161240D01*
X1634639Y162115D01*
X1635106Y162740D01*
X1635759Y163115D01*
X1636412D01*
X1637066Y162865D01*
X1637626Y162240D01*
G01X1641486Y155615D02*
Y163115D01*
X1643352D01*
X1644099Y162740D01*
X1644659Y162240D01*
X1645126Y161490D01*
X1645499Y160615D01*
X1645592Y159365D01*
X1645499Y158115D01*
X1645126Y157240D01*
X1644659Y156490D01*
X1644099Y155990D01*
X1643352Y155615D01*
X1641486D01*
G01X1651039D02*
Y163115D01*
X1649919Y161615D01*
G01Y155615D02*
X1652159D01*
G01X1659659D02*
Y163115D01*
X1656206Y157740D01*
X1660872D01*
G01X1614625Y153150D02*
X1621006D01*
G01X1614921Y152756D02*
X1620601D01*
G01X1618352Y189535D02*
X1615926D01*
G01X1614812Y195583D02*
Y184087D01*
G01X1628800Y203983D02*
X1625700D01*
Y204903D01*
X1625855Y205210D01*
X1626217Y205440D01*
X1626630Y205517D01*
X1627043Y205440D01*
X1627353Y205248D01*
X1627508Y204903D01*
Y203983D01*
G01X1628800Y207007D02*
X1625700D01*
Y207773D01*
X1625855Y208080D01*
X1626062Y208310D01*
X1626372Y208502D01*
X1626733Y208655D01*
X1627250Y208693D01*
X1627767Y208655D01*
X1628128Y208502D01*
X1628438Y208310D01*
X1628645Y208080D01*
X1628800Y207773D01*
Y207007D01*
G01Y210950D02*
X1625700D01*
X1626320Y210490D01*
G01X1628800D02*
Y211410D01*
G01X1626217Y213322D02*
X1625907Y213552D01*
X1625752Y213820D01*
X1625700Y214127D01*
X1625803Y214510D01*
X1626062Y214778D01*
X1626372Y214855D01*
X1626682Y214817D01*
X1626940Y214663D01*
X1627457Y213897D01*
X1627818Y213552D01*
X1628335Y213322D01*
X1628800Y213245D01*
Y214855D01*
G01X1626217Y216422D02*
X1625907Y216652D01*
X1625752Y216920D01*
X1625700Y217227D01*
X1625803Y217610D01*
X1626062Y217878D01*
X1626372Y217955D01*
X1626682Y217917D01*
X1626940Y217763D01*
X1627457Y216997D01*
X1627818Y216652D01*
X1628335Y216422D01*
X1628800Y216345D01*
Y217955D01*
G01X1615501Y215842D02*
X1612401D01*
Y216762D01*
X1612556Y217069D01*
X1612918Y217299D01*
X1613331Y217376D01*
X1613744Y217299D01*
X1614054Y217107D01*
X1614209Y216762D01*
Y215842D01*
G01X1612401Y218866D02*
X1614623D01*
X1615088Y219019D01*
X1615398Y219326D01*
X1615501Y219709D01*
X1615398Y220092D01*
X1615088Y220399D01*
X1614623Y220552D01*
X1612401D01*
G01X1614209Y222081D02*
X1613848Y222349D01*
X1613641Y222579D01*
X1613538Y222886D01*
X1613641Y223154D01*
X1613848Y223346D01*
X1614158Y223499D01*
X1614519Y223537D01*
X1614829Y223499D01*
X1615139Y223346D01*
X1615398Y223116D01*
X1615501Y222847D01*
X1615398Y222541D01*
X1615088Y222272D01*
X1614623Y222119D01*
X1614106Y222081D01*
X1613434Y222157D01*
X1613073Y222272D01*
X1612711Y222464D01*
X1612453Y222732D01*
X1612401Y223001D01*
X1612504Y223269D01*
X1612763Y223461D01*
G01X1615501Y225832D02*
X1614829Y225909D01*
X1614261Y226024D01*
X1613744Y226177D01*
X1613176Y226369D01*
X1612401Y226676D01*
Y225142D01*
G01X1613785Y237659D02*
Y231459D01*
G01X1611411Y243281D02*
Y240081D01*
G01X1628400Y263183D02*
X1625300D01*
Y264103D01*
X1625455Y264410D01*
X1625817Y264640D01*
X1626230Y264717D01*
X1626643Y264640D01*
X1626953Y264448D01*
X1627108Y264103D01*
Y263183D01*
G01X1628400Y266207D02*
X1625300D01*
Y266973D01*
X1625455Y267280D01*
X1625662Y267510D01*
X1625972Y267702D01*
X1626333Y267855D01*
X1626850Y267893D01*
X1627367Y267855D01*
X1627728Y267702D01*
X1628038Y267510D01*
X1628245Y267280D01*
X1628400Y266973D01*
Y266207D01*
G01Y270610D02*
X1625300D01*
X1627522Y269192D01*
Y271108D01*
G01X1628400Y273173D02*
X1627728Y273250D01*
X1627160Y273365D01*
X1626643Y273518D01*
X1626075Y273710D01*
X1625300Y274017D01*
Y272483D01*
G01X1613397Y337852D02*
Y334652D01*
G01Y345852D02*
Y342652D01*
G01X1615197D02*
Y345852D01*
G01X1621397D02*
Y342652D01*
G01D02*
X1615197D01*
G01Y338652D02*
Y341852D01*
G01X1621397Y338652D02*
X1615197D01*
G01X1621397Y341852D02*
Y338652D01*
G01X1615197Y341852D02*
X1621397D01*
G01X1613397D02*
Y338652D01*
G01X1615197Y345852D02*
X1621397D01*
G01X1618860Y444273D02*
Y447473D01*
G01X1625060Y444273D02*
X1618860D01*
G01X1625060Y447473D02*
Y444273D01*
G01X1618860Y447473D02*
X1625060D01*
G01X1618860Y448273D02*
Y451473D01*
G01X1625060Y448273D02*
X1618860D01*
G01X1625060Y451473D02*
Y448273D01*
G01X1618860Y451473D02*
X1625060D01*
G01Y460459D02*
Y457259D01*
G01X1618860D02*
Y460459D01*
G01X1625060Y457259D02*
X1618860D01*
G01X1625060Y455473D02*
Y452273D01*
G01X1618860Y455473D02*
X1625060D01*
G01X1618860Y452273D02*
Y455473D01*
G01X1625060Y452273D02*
X1618860D01*
G01Y460459D02*
X1625060D01*
G01X1618860Y461259D02*
Y464459D01*
G01X1625060Y461259D02*
X1618860D01*
G01X1625060Y464459D02*
Y461259D01*
G01X1618860Y464459D02*
X1625060D01*
G01X1624245Y544312D02*
Y541112D01*
G01X1618045Y544312D02*
X1624245D01*
G01X1618045Y541112D02*
Y544312D01*
G01X1624245Y541112D02*
X1618045D01*
G01Y545112D02*
Y548312D01*
G01X1624245Y545112D02*
X1618045D01*
G01X1624245Y548312D02*
Y545112D01*
G01X1618045Y548312D02*
X1624245D01*
G01X1616138Y619263D02*
X1612938D01*
G01X1616138Y625463D02*
Y619263D01*
G01X1612938D02*
Y625463D01*
G01X1620138Y619263D02*
X1616938D01*
G01X1620138Y625463D02*
Y619263D01*
G01X1616938D02*
Y625463D01*
G01X1624138Y619263D02*
X1620938D01*
G01X1624138Y625463D02*
Y619263D01*
G01X1620938D02*
Y625463D01*
G01X1612567Y635329D02*
X1614291Y637329D01*
G01X1612567Y631911D02*
Y635329D01*
G01X1622015Y631911D02*
X1612567D01*
G01X1622015Y642747D02*
Y631911D01*
G01X1612938Y625463D02*
X1616138D01*
G01X1616938D02*
X1620138D01*
G01X1620938D02*
X1624138D01*
G01X1612567Y639329D02*
Y642747D01*
G01X1614291Y637329D02*
X1612567Y639329D01*
G01Y642747D02*
X1622015D01*
G01X1611762Y649146D02*
Y655346D01*
G01X1614962Y649146D02*
X1611762D01*
G01X1614962Y655346D02*
Y649146D01*
G01X1615762D02*
Y655346D01*
G01X1618962Y649146D02*
X1615762D01*
G01X1618962Y655346D02*
Y649146D01*
G01X1619762D02*
Y655346D01*
G01X1622962Y649146D02*
X1619762D01*
G01X1622962Y655346D02*
Y649146D01*
G01X1611762Y655346D02*
X1614962D01*
G01X1615762D02*
X1618962D01*
G01X1619762D02*
X1622962D01*
G01X1624343Y673013D02*
Y658013D01*
G01X1611343D02*
Y673013D01*
G01X1624343Y658013D02*
X1611343D01*
G01X1617785Y677432D02*
Y674232D01*
G01X1611585Y677432D02*
X1617785D01*
G01X1611585Y674232D02*
Y677432D01*
G01X1617785Y674232D02*
X1611585D01*
G01X1618425Y674289D02*
Y677489D01*
G01X1624625Y674289D02*
X1618425D01*
G01X1624625Y677489D02*
Y674289D01*
G01X1618425Y677489D02*
X1624625D01*
G01X1611343Y673013D02*
X1624343D01*
G01X1636116Y707607D02*
Y698159D01*
X1625280D01*
Y707607D01*
X1628698D01*
X1630698Y705883D01*
X1632698Y707607D01*
X1636116D01*
G01Y725507D02*
Y716059D01*
X1625280D01*
Y725507D01*
X1628698D01*
X1630698Y723783D01*
X1632698Y725507D01*
X1636116D01*
G01X1636416Y740107D02*
Y730659D01*
X1625580D01*
Y740107D01*
X1628998D01*
X1630998Y738383D01*
X1632998Y740107D01*
X1636416D01*
G01Y758307D02*
Y748859D01*
X1625580D01*
Y758307D01*
X1628998D01*
X1630998Y756583D01*
X1632998Y758307D01*
X1636416D01*
G01X1618283Y752102D02*
Y745902D01*
X1615083D01*
Y752102D01*
X1618283D01*
G01X1632102Y742717D02*
X1625902D01*
Y745917D01*
X1632102D01*
Y742717D01*
G01X1624898Y765867D02*
X1624591Y765919D01*
X1624323Y766125D01*
X1624093Y766435D01*
X1623940Y766797D01*
X1623863Y767210D01*
Y767624D01*
X1623940Y768037D01*
X1624093Y768399D01*
X1624323Y768709D01*
X1624591Y768915D01*
X1624898Y768967D01*
X1625205Y768915D01*
X1625473Y768709D01*
X1625703Y768399D01*
X1625856Y768037D01*
X1625933Y767624D01*
Y767210D01*
X1625856Y766797D01*
X1625703Y766435D01*
X1625473Y766125D01*
X1625205Y765919D01*
X1624898Y765867D01*
G01X1625205Y766694D02*
X1625665Y765867D01*
G01X1627270Y768450D02*
X1627500Y768760D01*
X1627768Y768915D01*
X1628075Y768967D01*
X1628458Y768864D01*
X1628726Y768605D01*
X1628803Y768295D01*
X1628765Y767985D01*
X1628611Y767727D01*
X1627845Y767210D01*
X1627500Y766849D01*
X1627270Y766332D01*
X1627193Y765867D01*
X1628803D01*
G01X1630255Y766487D02*
X1630485Y766125D01*
X1630791Y765919D01*
X1631136Y765867D01*
X1631443Y765919D01*
X1631750Y766177D01*
X1631941Y766487D01*
X1631980Y766797D01*
X1631903Y767159D01*
X1631635Y767417D01*
X1631366Y767520D01*
X1631021D01*
G01X1631366D02*
X1631596Y767675D01*
X1631788Y767934D01*
X1631865Y768244D01*
X1631788Y768554D01*
X1631596Y768812D01*
X1631251Y768967D01*
X1630906Y768915D01*
X1630561Y768709D01*
G01X1633470Y767159D02*
X1633738Y767520D01*
X1633968Y767727D01*
X1634275Y767830D01*
X1634543Y767727D01*
X1634735Y767520D01*
X1634888Y767210D01*
X1634926Y766849D01*
X1634888Y766539D01*
X1634735Y766229D01*
X1634505Y765970D01*
X1634236Y765867D01*
X1633930Y765970D01*
X1633661Y766280D01*
X1633508Y766745D01*
X1633470Y767262D01*
X1633546Y767934D01*
X1633661Y768295D01*
X1633853Y768657D01*
X1634121Y768915D01*
X1634390Y768967D01*
X1634658Y768864D01*
X1634850Y768605D01*
G01X1618183Y766102D02*
Y759902D01*
X1614983D01*
Y766102D01*
X1618183D01*
G01X1631402Y761117D02*
X1625202D01*
Y764317D01*
X1631402D01*
Y761117D01*
G01X1625616Y782507D02*
Y773059D01*
X1614780D01*
Y782507D01*
X1618198D01*
X1620198Y780783D01*
X1622198Y782507D01*
X1625616D01*
G01X1613107Y795934D02*
X1612800Y795986D01*
X1612532Y796192D01*
X1612302Y796502D01*
X1612149Y796864D01*
X1612072Y797277D01*
Y797691D01*
X1612149Y798104D01*
X1612302Y798466D01*
X1612532Y798776D01*
X1612800Y798982D01*
X1613107Y799034D01*
X1613414Y798982D01*
X1613682Y798776D01*
X1613912Y798466D01*
X1614065Y798104D01*
X1614142Y797691D01*
Y797277D01*
X1614065Y796864D01*
X1613912Y796502D01*
X1613682Y796192D01*
X1613414Y795986D01*
X1613107Y795934D01*
G01X1613414Y796761D02*
X1613874Y795934D01*
G01X1615479Y798517D02*
X1615709Y798827D01*
X1615977Y798982D01*
X1616284Y799034D01*
X1616667Y798931D01*
X1616935Y798672D01*
X1617012Y798362D01*
X1616974Y798052D01*
X1616820Y797794D01*
X1616054Y797277D01*
X1615709Y796916D01*
X1615479Y796399D01*
X1615402Y795934D01*
X1617012D01*
G01X1618464Y796554D02*
X1618694Y796192D01*
X1619000Y795986D01*
X1619345Y795934D01*
X1619652Y795986D01*
X1619959Y796244D01*
X1620150Y796554D01*
X1620189Y796864D01*
X1620112Y797226D01*
X1619844Y797484D01*
X1619575Y797587D01*
X1619230D01*
G01X1619575D02*
X1619805Y797742D01*
X1619997Y798001D01*
X1620074Y798311D01*
X1619997Y798621D01*
X1619805Y798879D01*
X1619460Y799034D01*
X1619115Y798982D01*
X1618770Y798776D01*
G01X1621564Y796399D02*
X1621794Y796141D01*
X1622062Y795986D01*
X1622407Y795934D01*
X1622752Y796037D01*
X1623020Y796244D01*
X1623212Y796606D01*
X1623250Y797019D01*
X1623174Y797432D01*
X1622982Y797691D01*
X1622714Y797897D01*
X1622445Y797949D01*
X1622177Y797897D01*
X1621832Y797691D01*
X1621947Y799034D01*
X1622982D01*
G01X1625416Y795207D02*
Y785759D01*
X1614580D01*
Y795207D01*
X1617998D01*
X1619998Y793483D01*
X1621998Y795207D01*
X1625416D01*
G01X1628557Y812192D02*
X1628250Y812244D01*
X1627982Y812450D01*
X1627752Y812760D01*
X1627599Y813122D01*
X1627522Y813535D01*
Y813949D01*
X1627599Y814362D01*
X1627752Y814724D01*
X1627982Y815034D01*
X1628250Y815240D01*
X1628557Y815292D01*
X1628864Y815240D01*
X1629132Y815034D01*
X1629362Y814724D01*
X1629515Y814362D01*
X1629592Y813949D01*
Y813535D01*
X1629515Y813122D01*
X1629362Y812760D01*
X1629132Y812450D01*
X1628864Y812244D01*
X1628557Y812192D01*
G01X1628864Y813019D02*
X1629324Y812192D01*
G01X1630929Y814775D02*
X1631159Y815085D01*
X1631427Y815240D01*
X1631734Y815292D01*
X1632117Y815189D01*
X1632385Y814930D01*
X1632462Y814620D01*
X1632424Y814310D01*
X1632270Y814052D01*
X1631504Y813535D01*
X1631159Y813174D01*
X1630929Y812657D01*
X1630852Y812192D01*
X1632462D01*
G01X1633914Y812812D02*
X1634144Y812450D01*
X1634450Y812244D01*
X1634795Y812192D01*
X1635102Y812244D01*
X1635409Y812502D01*
X1635600Y812812D01*
X1635639Y813122D01*
X1635562Y813484D01*
X1635294Y813742D01*
X1635025Y813845D01*
X1634680D01*
G01X1635025D02*
X1635255Y814000D01*
X1635447Y814259D01*
X1635524Y814569D01*
X1635447Y814879D01*
X1635255Y815137D01*
X1634910Y815292D01*
X1634565Y815240D01*
X1634220Y815034D01*
G01X1637780Y812192D02*
X1637857Y812864D01*
X1637972Y813432D01*
X1638125Y813949D01*
X1638317Y814517D01*
X1638624Y815292D01*
X1637090D01*
G01X1625116Y809307D02*
Y799859D01*
X1614280D01*
Y809307D01*
X1617698D01*
X1619698Y807583D01*
X1621698Y809307D01*
X1625116D01*
G01X1625216Y823407D02*
Y813959D01*
X1614380D01*
Y823407D01*
X1617798D01*
X1619798Y821683D01*
X1621798Y823407D01*
X1625216D01*
G01X1621102Y826517D02*
X1614902D01*
Y829717D01*
X1621102D01*
Y826517D01*
G01X1634401Y868303D02*
Y866353D01*
X1624401D01*
G01D02*
Y878303D01*
G01Y884403D02*
Y896353D01*
X1634401D01*
Y894403D01*
G01X1633832Y939070D02*
Y937120D01*
X1623832D01*
G01D02*
Y949070D01*
G01Y955170D02*
Y967120D01*
X1633832D01*
Y965170D01*
G01X1620885Y1537758D02*
X1614685D01*
Y1540958D01*
X1620885D01*
Y1537758D01*
G01X1611995Y1560779D02*
X1612187Y1560469D01*
X1612417Y1560262D01*
X1612685Y1560159D01*
X1612992Y1560262D01*
X1613222Y1560469D01*
X1613452Y1560779D01*
X1613529Y1561192D01*
Y1563259D01*
G01X1615134Y1561451D02*
X1615402Y1561812D01*
X1615632Y1562019D01*
X1615939Y1562122D01*
X1616207Y1562019D01*
X1616399Y1561812D01*
X1616552Y1561502D01*
X1616590Y1561141D01*
X1616552Y1560831D01*
X1616399Y1560521D01*
X1616169Y1560262D01*
X1615900Y1560159D01*
X1615594Y1560262D01*
X1615325Y1560572D01*
X1615172Y1561037D01*
X1615134Y1561554D01*
X1615210Y1562226D01*
X1615325Y1562587D01*
X1615517Y1562949D01*
X1615785Y1563207D01*
X1616054Y1563259D01*
X1616322Y1563156D01*
X1616514Y1562897D01*
G01X1618234Y1562742D02*
X1618464Y1563052D01*
X1618732Y1563207D01*
X1619039Y1563259D01*
X1619422Y1563156D01*
X1619690Y1562897D01*
X1619767Y1562587D01*
X1619729Y1562277D01*
X1619575Y1562019D01*
X1618809Y1561502D01*
X1618464Y1561141D01*
X1618234Y1560624D01*
X1618157Y1560159D01*
X1619767D01*
G01X1619390Y1564843D02*
Y1690040D01*
G01X1630764Y1599500D02*
X1631564Y1600000D01*
X1632097Y1600600D01*
X1632364Y1601300D01*
X1632097Y1602100D01*
X1631564Y1602700D01*
X1630764Y1603300D01*
X1629697Y1603500D01*
X1624364D01*
G01X1631431Y1607800D02*
X1632097Y1608500D01*
X1632364Y1609300D01*
X1632097Y1610100D01*
X1631298Y1610800D01*
X1630097Y1611300D01*
X1628897Y1611500D01*
X1627431D01*
X1626231Y1611300D01*
X1625164Y1610800D01*
X1624631Y1610200D01*
X1624364Y1609500D01*
X1624631Y1608700D01*
X1625164Y1608100D01*
X1625964Y1607700D01*
X1627031Y1607500D01*
X1627964Y1607700D01*
X1628897Y1608200D01*
X1629431Y1608800D01*
X1629564Y1609500D01*
X1629298Y1610300D01*
X1628631Y1610900D01*
X1627431Y1611500D01*
G01X1639133Y58150D02*
Y104461D01*
G01X1639429Y57756D02*
Y104461D01*
G01Y57756D02*
X1633048D01*
G01X1639133Y58150D02*
X1633453D01*
G01X1639429Y111507D02*
Y107060D01*
G01X1639133Y111507D02*
Y107060D01*
G01Y118680D02*
Y114087D01*
G01X1639429Y118680D02*
Y114087D01*
G01X1639133Y132859D02*
Y128325D01*
G01X1639429Y132859D02*
Y128325D01*
G01Y125844D02*
Y121329D01*
G01X1639133Y125844D02*
Y121329D01*
G01X1639429Y153150D02*
Y135518D01*
G01X1639133Y152756D02*
Y135518D01*
G01X1631529Y164436D02*
X1646329D01*
G01X1631529Y195440D02*
Y164436D01*
G01X1633048Y153150D02*
X1639429D01*
G01X1633453Y152756D02*
X1639133D01*
G01X1646329Y195440D02*
X1631529D01*
G01X1643642Y213035D02*
Y225035D01*
G01X1649642Y213035D02*
X1643642D01*
G01X1635532Y199912D02*
Y202338D01*
G01X1641580Y203452D02*
X1630084D01*
G01X1641580Y233011D02*
Y203452D01*
G01X1630084D02*
Y233011D01*
G01X1643642Y225035D02*
X1649642D01*
G01X1635432Y236652D02*
Y234412D01*
G01X1637057Y235625D02*
X1633807D01*
G01X1630084Y233011D02*
X1641580D01*
G01X1642925Y250325D02*
Y234813D01*
G01D02*
X1674017D01*
G01X1635301Y259204D02*
Y261630D01*
G01X1641349Y262744D02*
X1629853D01*
G01X1641349Y292303D02*
Y262744D01*
G01X1629853D02*
Y292303D01*
G01X1643104Y251936D02*
Y255036D01*
X1644024D01*
X1644331Y254881D01*
X1644561Y254519D01*
X1644638Y254106D01*
X1644561Y253693D01*
X1644369Y253383D01*
X1644024Y253228D01*
X1643104D01*
G01X1646128Y251936D02*
Y255036D01*
X1646894D01*
X1647201Y254881D01*
X1647431Y254674D01*
X1647623Y254364D01*
X1647776Y254003D01*
X1647814Y253486D01*
X1647776Y252969D01*
X1647623Y252608D01*
X1647431Y252298D01*
X1647201Y252091D01*
X1646894Y251936D01*
X1646128D01*
G01X1650071D02*
Y255036D01*
X1649611Y254416D01*
G01Y251936D02*
X1650531D01*
G01X1652443Y254519D02*
X1652673Y254829D01*
X1652941Y254984D01*
X1653248Y255036D01*
X1653631Y254933D01*
X1653899Y254674D01*
X1653976Y254364D01*
X1653938Y254054D01*
X1653784Y253796D01*
X1653018Y253279D01*
X1652673Y252918D01*
X1652443Y252401D01*
X1652366Y251936D01*
X1653976D01*
G01X1656271D02*
Y255036D01*
X1655811Y254416D01*
G01Y251936D02*
X1656731D01*
G01X1674017Y250325D02*
X1642925D01*
G01X1643220Y271655D02*
Y283655D01*
G01X1649220Y271655D02*
X1643220D01*
G01Y283655D02*
X1649220D01*
G01X1635743Y297556D02*
Y295316D01*
G01X1637368Y296529D02*
X1634118D01*
G01X1629853Y292303D02*
X1641349D01*
G01X1633980Y367183D02*
X1634290Y367375D01*
X1634497Y367605D01*
X1634600Y367873D01*
X1634497Y368180D01*
X1634290Y368410D01*
X1633980Y368640D01*
X1633567Y368717D01*
X1631500D01*
G01X1632017Y370322D02*
X1631707Y370552D01*
X1631552Y370820D01*
X1631500Y371127D01*
X1631603Y371510D01*
X1631862Y371778D01*
X1632172Y371855D01*
X1632482Y371817D01*
X1632740Y371663D01*
X1633257Y370897D01*
X1633618Y370552D01*
X1634135Y370322D01*
X1634600Y370245D01*
Y371855D01*
G01Y374073D02*
X1633928Y374150D01*
X1633360Y374265D01*
X1632843Y374418D01*
X1632275Y374610D01*
X1631500Y374917D01*
Y373383D01*
G01X1636900Y366063D02*
X1644346D01*
G01X1636900Y418006D02*
Y366063D01*
G01Y425116D02*
Y467535D01*
G01Y474925D02*
Y470260D01*
G01Y481999D02*
Y477273D01*
G01Y489023D02*
Y484398D01*
G01Y511780D02*
Y491483D01*
G01Y519090D02*
Y514395D01*
G01Y526062D02*
Y521356D01*
G01Y533279D02*
Y528543D01*
G01Y546456D02*
Y535678D01*
G01Y553556D02*
Y562026D01*
G01Y569098D02*
Y564383D01*
G01Y576183D02*
Y571518D01*
G01Y583287D02*
Y578613D01*
G01Y590310D02*
Y585655D01*
G01Y597384D02*
Y592730D01*
G01Y604489D02*
Y599824D01*
G01Y639449D02*
Y614055D01*
G01Y611543D02*
Y606908D01*
G01X1657577Y645269D02*
X1641977D01*
X1657577Y654239D01*
X1641977D01*
G01Y665314D02*
Y669994D01*
G01Y667654D02*
X1657577D01*
G01Y665314D02*
Y669994D01*
G01X1643277Y689844D02*
X1642497Y688674D01*
X1641977Y687309D01*
Y685749D01*
X1642757Y683994D01*
X1644057Y682629D01*
X1645617Y681654D01*
X1648217Y680874D01*
X1650557Y680679D01*
X1652897Y681069D01*
X1654457Y681654D01*
X1656017Y682824D01*
X1657057Y684189D01*
X1657577Y685554D01*
Y686919D01*
X1657057Y688284D01*
X1656277Y689454D01*
X1655237Y690429D01*
G01X1657577Y703064D02*
X1654197Y703454D01*
X1651337Y704039D01*
X1648737Y704819D01*
X1645877Y705794D01*
X1641977Y707354D01*
Y699554D01*
G01X1644396Y639449D02*
X1636900D01*
G01X1635702Y709817D02*
X1629502D01*
Y713017D01*
X1635702D01*
Y709817D01*
G01X1643102Y726517D02*
X1636902D01*
Y729717D01*
X1643102D01*
Y726517D01*
G01X1635683Y779302D02*
Y773102D01*
X1632483D01*
Y779302D01*
X1635683D01*
G01X1634183Y792002D02*
Y785802D01*
X1630983D01*
Y792002D01*
X1634183D01*
G01X1632983Y806102D02*
Y799902D01*
X1629783D01*
Y806102D01*
X1632983D01*
G01X1645614Y870510D02*
X1645976Y870740D01*
X1646182Y871046D01*
X1646234Y871391D01*
X1646182Y871698D01*
X1645924Y872005D01*
X1645614Y872196D01*
X1645304Y872235D01*
X1644942Y872158D01*
X1644684Y871890D01*
X1644581Y871621D01*
Y871276D01*
G01Y871621D02*
X1644426Y871851D01*
X1644167Y872043D01*
X1643857Y872120D01*
X1643547Y872043D01*
X1643289Y871851D01*
X1643134Y871506D01*
X1643186Y871161D01*
X1643392Y870816D01*
G01X1634401Y888303D02*
Y874403D01*
G01X1645350Y880399D02*
X1639150D01*
Y883599D01*
X1645350D01*
Y880399D01*
G01X1645698Y915641D02*
X1639498D01*
Y918841D01*
X1645698D01*
Y915641D01*
G01X1645045Y941277D02*
X1645407Y941507D01*
X1645613Y941813D01*
X1645665Y942158D01*
X1645613Y942465D01*
X1645355Y942772D01*
X1645045Y942963D01*
X1644735Y943002D01*
X1644373Y942925D01*
X1644115Y942657D01*
X1644012Y942388D01*
Y942043D01*
G01Y942388D02*
X1643857Y942618D01*
X1643598Y942810D01*
X1643288Y942887D01*
X1642978Y942810D01*
X1642720Y942618D01*
X1642565Y942273D01*
X1642617Y941928D01*
X1642823Y941583D01*
G01X1633832Y959070D02*
Y945170D01*
G01X1645456Y950525D02*
X1639256D01*
Y953725D01*
X1645456D01*
Y950525D01*
G01X1634803Y1425158D02*
Y1689331D01*
G01X1747795Y1425158D02*
X1634803D01*
G01Y1689331D02*
X1747795D01*
G01X1655354Y82540D02*
Y85740D01*
G01X1661554Y82540D02*
X1655354D01*
G01Y78540D02*
Y81740D01*
G01X1661554Y78540D02*
X1655354D01*
G01Y81740D02*
X1661554D01*
G01X1655354Y74540D02*
Y77740D01*
G01X1661554Y74540D02*
X1655354D01*
G01Y77740D02*
X1661554D01*
G01X1654965Y86929D02*
X1651765D01*
G01X1654965Y93129D02*
Y86929D01*
G01X1651765Y93129D02*
X1654965D01*
G01X1651765Y86929D02*
Y93129D01*
G01X1658974Y86929D02*
X1655774D01*
G01X1658974Y93129D02*
Y86929D01*
G01X1655774Y93129D02*
X1658974D01*
G01X1655774Y86929D02*
Y93129D01*
G01X1644961Y97026D02*
Y103226D01*
G01X1648161Y97026D02*
X1644961D01*
G01X1648161Y103226D02*
Y97026D01*
G01X1646965Y86929D02*
X1643765D01*
G01X1646965Y93129D02*
Y86929D01*
G01X1643765Y93129D02*
X1646965D01*
G01X1643765Y86929D02*
Y93129D01*
G01X1655354Y85740D02*
X1661554D01*
G01X1650965Y86929D02*
X1647765D01*
G01X1650965Y93129D02*
Y86929D01*
G01X1647765Y93129D02*
X1650965D01*
G01X1647765Y86929D02*
Y93129D01*
G01X1651044Y96673D02*
Y102873D01*
G01X1654244Y96673D02*
X1651044D01*
G01X1654244Y102873D02*
Y96673D01*
G01X1655044D02*
Y102873D01*
G01X1658244Y96673D02*
X1655044D01*
G01X1658244Y102873D02*
Y96673D01*
G01X1644961Y103226D02*
X1648161D01*
G01X1651044Y102873D02*
X1654244D01*
G01X1655044D02*
X1658244D01*
G01X1657027Y144690D02*
Y154138D01*
G01X1667863Y144690D02*
X1657027D01*
G01X1652629Y139647D02*
Y142847D01*
G01X1658829Y139647D02*
X1652629D01*
G01X1658829Y142847D02*
Y139647D01*
G01X1652629Y142847D02*
X1658829D01*
G01X1648659Y145940D02*
Y149140D01*
G01X1654859Y145940D02*
X1648659D01*
G01X1654859Y149140D02*
Y145940D01*
G01X1648659Y149140D02*
X1654859D01*
G01X1659608Y139647D02*
Y142847D01*
G01X1665808Y139647D02*
X1659608D01*
G01Y142847D02*
X1665808D01*
G01X1646329Y164436D02*
Y195440D01*
G01X1657027Y154138D02*
X1660445D01*
G01X1654859Y153140D02*
Y149940D01*
G01X1648659Y153140D02*
X1654859D01*
G01X1648659Y149940D02*
Y153140D01*
G01X1654859Y149940D02*
X1648659D01*
G01X1659857Y174900D02*
Y172678D01*
X1660010Y172213D01*
X1660317Y171903D01*
X1660700Y171800D01*
X1661083Y171903D01*
X1661390Y172213D01*
X1661543Y172678D01*
Y174900D01*
G01X1663723Y171800D02*
X1663800Y172472D01*
X1663915Y173040D01*
X1664068Y173557D01*
X1664260Y174125D01*
X1664567Y174900D01*
X1663033D01*
G01X1666823Y171800D02*
X1666900Y172472D01*
X1667015Y173040D01*
X1667168Y173557D01*
X1667360Y174125D01*
X1667667Y174900D01*
X1666133D01*
G01X1655295Y171473D02*
X1652095D01*
G01X1655295Y177673D02*
Y171473D01*
G01X1652095Y177673D02*
X1655295D01*
G01X1652095Y171473D02*
Y177673D01*
G01X1658318Y170297D02*
Y167097D01*
G01X1652118Y170297D02*
X1658318D01*
G01X1652118Y167097D02*
Y170297D01*
G01X1658318Y167097D02*
X1652118D01*
G01X1651295Y171473D02*
X1648095D01*
G01X1651295Y177673D02*
Y171473D01*
G01X1648095Y177673D02*
X1651295D01*
G01X1648095Y171473D02*
Y177673D01*
G01X1655522Y182730D02*
X1652322D01*
G01X1655522Y188930D02*
Y182730D01*
G01X1652322Y188930D02*
X1655522D01*
G01X1652322Y182730D02*
Y188930D01*
G01X1658513Y193541D02*
Y190341D01*
G01X1652313Y193541D02*
X1658513D01*
G01X1652313Y190341D02*
Y193541D01*
G01X1658513Y190341D02*
X1652313D01*
G01X1649642Y225035D02*
Y213035D01*
G01X1658951Y201618D02*
Y204718D01*
X1659871D01*
X1660178Y204563D01*
X1660408Y204201D01*
X1660485Y203788D01*
X1660408Y203375D01*
X1660216Y203065D01*
X1659871Y202910D01*
X1658951D01*
G01X1661975Y204718D02*
Y202496D01*
X1662128Y202031D01*
X1662435Y201721D01*
X1662818Y201618D01*
X1663201Y201721D01*
X1663508Y202031D01*
X1663661Y202496D01*
Y204718D01*
G01X1666378Y201618D02*
Y204718D01*
X1664960Y202496D01*
X1666876D01*
G01X1668175Y202238D02*
X1668405Y201876D01*
X1668711Y201670D01*
X1669056Y201618D01*
X1669363Y201670D01*
X1669670Y201928D01*
X1669861Y202238D01*
X1669900Y202548D01*
X1669823Y202910D01*
X1669555Y203168D01*
X1669286Y203271D01*
X1668941D01*
G01X1669286D02*
X1669516Y203426D01*
X1669708Y203685D01*
X1669785Y203995D01*
X1669708Y204305D01*
X1669516Y204563D01*
X1669171Y204718D01*
X1668826Y204666D01*
X1668481Y204460D01*
G01X1672798Y220252D02*
Y208048D01*
X1657494D01*
Y220252D01*
X1672798D01*
G01X1650482Y226621D02*
Y232621D01*
G01X1662482Y226621D02*
X1650482D01*
G01X1654461Y215082D02*
X1651261D01*
G01X1654461Y221282D02*
Y215082D01*
G01X1651261Y221282D02*
X1654461D01*
G01X1651261Y215082D02*
Y221282D01*
G01X1654282Y225921D02*
X1660482D01*
G01X1654282Y222721D02*
Y225921D01*
G01X1660482Y222721D02*
X1654282D01*
G01X1650482Y232621D02*
X1662482D01*
G01X1651150Y258010D02*
Y264210D01*
G01X1654350Y258010D02*
X1651150D01*
G01X1654350Y264210D02*
Y258010D01*
G01X1659150D02*
Y264210D01*
G01X1662350Y258010D02*
X1659150D01*
G01X1658350D02*
X1655150D01*
G01X1658350Y264210D02*
Y258010D01*
G01X1655150D02*
Y264210D01*
G01X1649220Y283655D02*
Y271655D01*
G01X1651150Y264210D02*
X1654350D01*
G01X1659150D02*
X1662350D01*
G01X1655150D02*
X1658350D01*
G01X1652109Y267653D02*
Y279427D01*
G01X1661871Y267653D02*
X1652109D01*
G01X1653403Y283383D02*
X1650203D01*
G01X1653403Y289583D02*
Y283383D01*
G01X1650203Y289583D02*
X1653403D01*
G01X1650203Y283383D02*
Y289583D01*
G01X1657403Y283383D02*
X1654203D01*
G01X1657403Y289583D02*
Y283383D01*
G01X1654203Y289583D02*
X1657403D01*
G01X1654203Y283383D02*
Y289583D01*
G01X1658203Y283383D02*
Y289583D01*
X1661403D01*
Y283383D01*
X1658203D01*
G01X1652109Y279427D02*
X1661871D01*
G01X1656675Y316273D02*
Y319473D01*
G01X1662875Y316273D02*
X1656675D01*
G01Y319473D02*
X1662875D01*
G01X1656916Y366063D02*
X1672392D01*
G01Y639449D02*
X1656846D01*
G01X1652915Y869745D02*
X1646715D01*
Y872945D01*
X1652915D01*
Y869745D01*
G01X1653452Y907679D02*
X1647252D01*
Y910879D01*
X1653452D01*
Y907679D01*
G01X1653059Y940536D02*
X1646859D01*
Y943736D01*
X1653059D01*
Y940536D01*
G01X1650656Y1419282D02*
X1652523D01*
Y1417032D01*
X1651963Y1416282D01*
X1651309Y1415782D01*
X1650376Y1415532D01*
X1649443Y1415782D01*
X1648789Y1416282D01*
X1648229Y1417032D01*
X1647856Y1417907D01*
X1647669Y1418907D01*
Y1419782D01*
X1647856Y1420532D01*
X1648229Y1421407D01*
X1648789Y1422157D01*
X1649349Y1422657D01*
X1650096Y1423032D01*
X1650749D01*
X1651496Y1422782D01*
X1652056Y1422282D01*
G01X1655729Y1415532D02*
Y1423032D01*
X1657969D01*
X1658716Y1422657D01*
X1659276Y1421782D01*
X1659463Y1420782D01*
X1659276Y1419782D01*
X1658809Y1419032D01*
X1657969Y1418657D01*
X1655729D01*
G01X1663043Y1423032D02*
Y1417657D01*
X1663416Y1416532D01*
X1664163Y1415782D01*
X1665096Y1415532D01*
X1666029Y1415782D01*
X1666776Y1416532D01*
X1667149Y1417657D01*
Y1423032D01*
G01X1669796Y1413032D02*
X1675396D01*
G01X1677763Y1415532D02*
X1680096Y1423032D01*
X1682429Y1415532D01*
G01X1681589Y1418157D02*
X1678603D01*
G01X1646614Y1677520D02*
Y1436969D01*
G01D02*
X1735984D01*
G01X1646614Y1647993D02*
X1735984D01*
G01Y1677520D02*
X1646614D01*
G01X1686852Y67523D02*
X1674648D01*
G01D02*
Y70183D01*
G01X1675345Y59613D02*
X1681545D01*
G01X1675345Y56413D02*
Y59613D01*
G01X1681545Y56413D02*
X1675345D01*
G01X1672220Y70181D02*
Y66981D01*
G01X1666020D02*
Y70181D01*
G01X1672220Y66981D02*
X1666020D01*
G01X1674648Y79047D02*
X1686852D01*
G01X1674648Y76285D02*
Y79047D01*
G01X1677750Y73285D02*
X1674648Y76285D01*
G01Y70183D02*
X1677750Y73285D01*
G01X1661554Y85740D02*
Y82540D01*
G01Y81740D02*
Y78540D01*
G01Y77740D02*
Y74540D01*
G01X1666020Y70181D02*
X1672220D01*
G01X1666065Y70987D02*
Y74187D01*
G01X1672265Y70987D02*
X1666065D01*
G01X1672265Y74187D02*
Y70987D01*
G01X1666065Y74187D02*
X1672265D01*
G01X1666065Y74987D02*
Y78187D01*
G01X1672265Y74987D02*
X1666065D01*
G01X1672265Y78187D02*
Y74987D01*
G01X1666065Y78187D02*
X1672265D01*
G01X1672220Y82181D02*
Y78981D01*
G01X1666020Y82181D02*
X1672220D01*
G01X1666020Y78981D02*
Y82181D01*
G01X1672220Y78981D02*
X1666020D01*
G01X1673055Y93476D02*
X1676255D01*
G01X1673055Y87276D02*
Y93476D01*
G01X1676255Y87276D02*
X1673055D01*
G01X1660548Y95950D02*
Y102150D01*
G01X1663748Y95950D02*
X1660548D01*
G01X1663748Y102150D02*
Y95950D01*
G01X1665212Y95913D02*
Y111267D01*
G01X1677693Y95913D02*
X1665212D01*
G01X1660548Y102150D02*
X1663748D01*
G01X1660548Y109762D02*
X1663748D01*
G01X1660548Y103562D02*
Y109762D01*
G01X1663748Y103562D02*
X1660548D01*
G01X1663748Y109762D02*
Y103562D01*
G01X1671563Y116088D02*
X1677763D01*
G01X1671563Y112888D02*
Y116088D01*
G01X1677763Y112888D02*
X1671563D01*
G01X1665212Y111267D02*
X1677890D01*
G01X1679064Y121261D02*
X1675964D01*
Y122181D01*
X1676119Y122488D01*
X1676481Y122718D01*
X1676894Y122795D01*
X1677307Y122718D01*
X1677617Y122526D01*
X1677772Y122181D01*
Y121261D01*
G01X1675964Y124285D02*
X1678186D01*
X1678651Y124438D01*
X1678961Y124745D01*
X1679064Y125128D01*
X1678961Y125511D01*
X1678651Y125818D01*
X1678186Y125971D01*
X1675964D01*
G01X1679064Y128228D02*
X1675964D01*
X1676584Y127768D01*
G01X1679064D02*
Y128688D01*
G01X1678444Y130485D02*
X1678806Y130715D01*
X1679012Y131021D01*
X1679064Y131366D01*
X1679012Y131673D01*
X1678754Y131980D01*
X1678444Y132171D01*
X1678134Y132210D01*
X1677772Y132133D01*
X1677514Y131865D01*
X1677411Y131596D01*
Y131251D01*
G01Y131596D02*
X1677256Y131826D01*
X1676997Y132018D01*
X1676687Y132095D01*
X1676377Y132018D01*
X1676119Y131826D01*
X1675964Y131481D01*
X1676016Y131136D01*
X1676222Y130791D01*
G01X1679064Y134888D02*
X1675964D01*
X1678186Y133470D01*
Y135386D01*
G01X1667863Y154138D02*
Y144690D01*
G01X1665808Y142847D02*
Y139647D01*
G01X1675470Y151368D02*
Y148168D01*
G01X1669270D02*
Y151368D01*
G01X1675470Y148168D02*
X1669270D01*
G01Y144168D02*
Y147368D01*
G01X1675470Y144168D02*
X1669270D01*
G01X1675470Y147368D02*
Y144168D01*
G01X1669270Y147368D02*
X1675470D01*
G01X1665748Y155056D02*
X1665441Y155108D01*
X1665173Y155314D01*
X1664943Y155624D01*
X1664790Y155986D01*
X1664713Y156399D01*
Y156813D01*
X1664790Y157226D01*
X1664943Y157588D01*
X1665173Y157898D01*
X1665441Y158104D01*
X1665748Y158156D01*
X1666055Y158104D01*
X1666323Y157898D01*
X1666553Y157588D01*
X1666706Y157226D01*
X1666783Y156813D01*
Y156399D01*
X1666706Y155986D01*
X1666553Y155624D01*
X1666323Y155314D01*
X1666055Y155108D01*
X1665748Y155056D01*
G01X1666055Y155883D02*
X1666515Y155056D01*
G01X1668120Y157639D02*
X1668350Y157949D01*
X1668618Y158104D01*
X1668925Y158156D01*
X1669308Y158053D01*
X1669576Y157794D01*
X1669653Y157484D01*
X1669615Y157174D01*
X1669461Y156916D01*
X1668695Y156399D01*
X1668350Y156038D01*
X1668120Y155521D01*
X1668043Y155056D01*
X1669653D01*
G01X1671105Y155676D02*
X1671335Y155314D01*
X1671641Y155108D01*
X1671986Y155056D01*
X1672293Y155108D01*
X1672600Y155366D01*
X1672791Y155676D01*
X1672830Y155986D01*
X1672753Y156348D01*
X1672485Y156606D01*
X1672216Y156709D01*
X1671871D01*
G01X1672216D02*
X1672446Y156864D01*
X1672638Y157123D01*
X1672715Y157433D01*
X1672638Y157743D01*
X1672446Y158001D01*
X1672101Y158156D01*
X1671756Y158104D01*
X1671411Y157898D01*
G01X1675048Y155056D02*
Y158156D01*
X1674588Y157536D01*
G01Y155056D02*
X1675508D01*
G01X1664445Y154138D02*
X1667863D01*
G01X1662445Y152414D02*
X1664445Y154138D01*
G01X1660445D02*
X1662445Y152414D01*
G01X1669270Y151368D02*
X1675470D01*
G01X1671835Y176944D02*
X1669882D01*
G01X1660023D02*
Y178897D01*
G01X1661976Y176944D02*
X1660023D01*
G01X1671835Y178897D02*
Y176944D01*
G01X1674027Y170313D02*
Y167113D01*
G01X1667827Y170313D02*
X1674027D01*
G01X1667827Y167113D02*
Y170313D01*
G01X1674027Y167113D02*
X1667827D01*
G01X1671835Y188756D02*
Y186803D01*
G01X1669882Y188756D02*
X1671835D01*
G01X1660023D02*
X1661976D01*
G01X1660023Y186803D02*
Y188756D01*
G01X1668882Y195020D02*
Y198220D01*
G01X1675082Y195020D02*
X1668882D01*
G01X1675082Y198220D02*
Y195020D01*
G01X1668882Y198220D02*
X1675082D01*
G01X1662482Y232621D02*
Y226621D01*
G01X1660482Y225921D02*
Y222721D01*
G01X1674017Y234813D02*
Y250325D01*
G01X1662350Y264210D02*
Y258010D01*
G01X1669061Y264635D02*
X1684573D01*
G01X1669061Y295727D02*
Y264635D01*
G01X1667429Y273701D02*
X1664229D01*
G01X1667429Y279901D02*
Y273701D01*
G01X1664229D02*
Y279901D01*
G01X1661871Y279427D02*
Y267653D01*
G01X1664229Y279901D02*
X1667429D01*
G01X1666400Y282833D02*
X1663300D01*
Y283753D01*
X1663455Y284060D01*
X1663817Y284290D01*
X1664230Y284367D01*
X1664643Y284290D01*
X1664953Y284098D01*
X1665108Y283753D01*
Y282833D01*
G01X1663300Y285857D02*
X1665522D01*
X1665987Y286010D01*
X1666297Y286317D01*
X1666400Y286700D01*
X1666297Y287083D01*
X1665987Y287390D01*
X1665522Y287543D01*
X1663300D01*
G01X1666400Y289800D02*
X1663300D01*
X1663920Y289340D01*
G01X1666400D02*
Y290260D01*
G01Y292900D02*
X1663300D01*
X1663920Y292440D01*
G01X1666400D02*
Y293360D01*
G01Y295923D02*
X1665728Y296000D01*
X1665160Y296115D01*
X1664643Y296268D01*
X1664075Y296460D01*
X1663300Y296767D01*
Y295233D01*
G01X1684573Y295727D02*
X1669061D01*
G01X1668150Y324800D02*
X1667843Y324852D01*
X1667575Y325058D01*
X1667345Y325368D01*
X1667192Y325730D01*
X1667115Y326143D01*
Y326557D01*
X1667192Y326970D01*
X1667345Y327332D01*
X1667575Y327642D01*
X1667843Y327848D01*
X1668150Y327900D01*
X1668457Y327848D01*
X1668725Y327642D01*
X1668955Y327332D01*
X1669108Y326970D01*
X1669185Y326557D01*
Y326143D01*
X1669108Y325730D01*
X1668955Y325368D01*
X1668725Y325058D01*
X1668457Y324852D01*
X1668150Y324800D01*
G01X1668457Y325627D02*
X1668917Y324800D01*
G01X1671250D02*
X1671518Y324852D01*
X1671825Y325007D01*
X1672017Y325265D01*
X1672093Y325627D01*
X1672017Y325988D01*
X1671787Y326298D01*
X1671442Y326453D01*
X1671058D01*
X1670828Y326557D01*
X1670637Y326815D01*
X1670560Y327177D01*
X1670675Y327538D01*
X1670943Y327797D01*
X1671250Y327900D01*
X1671557Y327797D01*
X1671825Y327538D01*
X1671940Y327177D01*
X1671863Y326815D01*
X1671672Y326557D01*
X1671442Y326453D01*
X1671058D01*
X1670713Y326298D01*
X1670483Y325988D01*
X1670407Y325627D01*
X1670483Y325265D01*
X1670675Y325007D01*
X1670982Y324852D01*
X1671250Y324800D01*
G01X1677164Y323621D02*
X1674833Y321290D01*
G01X1669393Y314959D02*
X1680273D01*
G01X1669393Y323621D02*
Y314959D01*
G01X1672502Y323621D02*
X1669393D01*
G01X1674833Y321290D02*
X1672502Y323621D01*
G01X1677403Y327342D02*
X1674203D01*
G01D02*
Y333542D01*
G01X1662875Y319473D02*
Y316273D01*
G01X1672245Y340646D02*
Y349110D01*
G01X1685507Y340646D02*
X1672245D01*
G01X1674203Y333542D02*
X1677403D01*
G01X1675507Y353300D02*
Y351078D01*
X1675660Y350613D01*
X1675967Y350303D01*
X1676350Y350200D01*
X1676733Y350303D01*
X1677040Y350613D01*
X1677193Y351078D01*
Y353300D01*
G01X1679910Y350200D02*
Y353300D01*
X1678492Y351078D01*
X1680408D01*
G01X1681707Y350665D02*
X1681937Y350407D01*
X1682205Y350252D01*
X1682550Y350200D01*
X1682895Y350303D01*
X1683163Y350510D01*
X1683355Y350872D01*
X1683393Y351285D01*
X1683317Y351698D01*
X1683125Y351957D01*
X1682857Y352163D01*
X1682588Y352215D01*
X1682320Y352163D01*
X1681975Y351957D01*
X1682090Y353300D01*
X1683125D01*
G01X1672245Y349110D02*
X1677376D01*
G01X1672392Y366063D02*
Y467728D01*
G01Y470189D02*
Y474925D01*
G01Y484428D02*
Y488909D01*
G01Y477324D02*
Y481824D01*
G01Y491595D02*
Y511832D01*
G01Y521427D02*
Y526164D01*
G01Y514354D02*
Y519080D01*
G01Y535565D02*
Y561873D01*
G01Y528512D02*
Y533125D01*
G01Y564498D02*
Y568894D01*
G01Y585748D02*
Y589992D01*
G01Y578695D02*
Y583103D01*
G01Y571662D02*
Y575968D01*
G01Y599937D02*
Y604181D01*
G01Y592945D02*
Y597230D01*
G01Y639449D02*
Y614065D01*
G01Y607072D02*
Y611439D01*
G01X1667079Y653823D02*
X1666299Y652653D01*
X1665779Y651288D01*
Y649728D01*
X1666559Y647973D01*
X1667859Y646608D01*
X1669419Y645633D01*
X1672019Y644853D01*
X1674359Y644658D01*
X1676699Y645048D01*
X1678259Y645633D01*
X1679819Y646803D01*
X1680859Y648168D01*
X1681379Y649533D01*
Y650898D01*
X1680859Y652263D01*
X1680079Y653433D01*
X1679039Y654408D01*
G01X1673059Y668993D02*
X1672279Y669773D01*
X1670979Y670358D01*
X1669159Y670748D01*
X1667599Y670358D01*
X1666559Y669578D01*
X1665779Y668213D01*
Y662948D01*
X1681379D01*
Y669383D01*
X1680339Y670748D01*
X1678779Y671528D01*
X1676959Y671918D01*
X1675139Y671528D01*
X1673579Y670358D01*
X1673059Y668993D01*
Y662948D01*
G01X1665779Y681433D02*
X1681379D01*
Y689233D01*
G01X1686579Y697383D02*
Y709083D01*
G01X1673059Y722693D02*
X1672279Y723473D01*
X1670979Y724058D01*
X1669159Y724448D01*
X1667599Y724058D01*
X1666559Y723278D01*
X1665779Y721913D01*
Y716648D01*
X1681379D01*
Y723083D01*
X1680339Y724448D01*
X1678779Y725228D01*
X1676959Y725618D01*
X1675139Y725228D01*
X1673579Y724058D01*
X1673059Y722693D01*
Y716648D01*
G01X1681379Y739033D02*
X1681119Y737473D01*
X1680079Y736108D01*
X1678519Y734938D01*
X1676699Y734158D01*
X1674619Y733768D01*
X1672539D01*
X1670459Y734158D01*
X1668639Y734938D01*
X1667079Y736108D01*
X1666039Y737473D01*
X1665779Y739033D01*
X1666039Y740593D01*
X1667079Y741958D01*
X1668639Y743128D01*
X1670459Y743908D01*
X1672539Y744298D01*
X1674619D01*
X1676699Y743908D01*
X1678519Y743128D01*
X1680079Y741958D01*
X1681119Y740593D01*
X1681379Y739033D01*
G01X1665779Y756933D02*
X1681379D01*
G01X1665779Y752448D02*
Y761418D01*
G01X1688300Y67907D02*
X1690522D01*
X1690987Y68060D01*
X1691297Y68367D01*
X1691400Y68750D01*
X1691297Y69133D01*
X1690987Y69440D01*
X1690522Y69593D01*
X1688300D01*
G01X1691400Y71850D02*
X1688300D01*
X1688920Y71390D01*
G01X1691400D02*
Y72310D01*
G01Y75410D02*
X1688300D01*
X1690522Y73992D01*
Y75908D01*
G01X1688300Y78050D02*
X1688403Y77743D01*
X1688662Y77513D01*
X1688972Y77360D01*
X1689385Y77245D01*
X1689850Y77207D01*
X1690315Y77245D01*
X1690728Y77360D01*
X1691038Y77513D01*
X1691297Y77743D01*
X1691400Y78050D01*
X1691297Y78357D01*
X1691038Y78587D01*
X1690728Y78740D01*
X1690315Y78855D01*
X1689850Y78893D01*
X1689385Y78855D01*
X1688972Y78740D01*
X1688662Y78587D01*
X1688403Y78357D01*
X1688300Y78050D01*
G01X1686852Y79047D02*
Y67523D01*
G01X1681545Y59613D02*
Y56413D01*
G01X1676255Y93476D02*
Y87276D01*
G01X1681755D02*
X1678555D01*
G01X1681755Y93476D02*
Y87276D01*
G01X1678555Y93476D02*
X1681755D01*
G01X1678555Y87276D02*
Y93476D01*
G01X1685704Y87204D02*
X1682504D01*
G01X1685704Y93404D02*
Y87204D01*
G01X1682504Y93404D02*
X1685704D01*
G01X1682504Y87204D02*
Y93404D01*
G01X1689611Y87299D02*
X1686411D01*
G01X1689611Y93499D02*
Y87299D01*
G01X1686411Y93499D02*
X1689611D01*
G01X1686411Y87299D02*
Y93499D01*
G01X1679300Y97307D02*
X1681522D01*
X1681987Y97460D01*
X1682297Y97767D01*
X1682400Y98150D01*
X1682297Y98533D01*
X1681987Y98840D01*
X1681522Y98993D01*
X1679300D01*
G01X1682400Y101710D02*
X1679300D01*
X1681522Y100292D01*
Y102208D01*
G01X1679300Y104350D02*
X1679403Y104043D01*
X1679662Y103813D01*
X1679972Y103660D01*
X1680385Y103545D01*
X1680850Y103507D01*
X1681315Y103545D01*
X1681728Y103660D01*
X1682038Y103813D01*
X1682297Y104043D01*
X1682400Y104350D01*
X1682297Y104657D01*
X1682038Y104887D01*
X1681728Y105040D01*
X1681315Y105155D01*
X1680850Y105193D01*
X1680385Y105155D01*
X1679972Y105040D01*
X1679662Y104887D01*
X1679403Y104657D01*
X1679300Y104350D01*
G01X1681108Y106722D02*
X1680747Y106990D01*
X1680540Y107220D01*
X1680437Y107527D01*
X1680540Y107795D01*
X1680747Y107987D01*
X1681057Y108140D01*
X1681418Y108178D01*
X1681728Y108140D01*
X1682038Y107987D01*
X1682297Y107757D01*
X1682400Y107488D01*
X1682297Y107182D01*
X1681987Y106913D01*
X1681522Y106760D01*
X1681005Y106722D01*
X1680333Y106798D01*
X1679972Y106913D01*
X1679610Y107105D01*
X1679352Y107373D01*
X1679300Y107642D01*
X1679403Y107910D01*
X1679662Y108102D01*
G01X1677890Y111267D02*
Y95913D01*
G01X1679046Y111951D02*
Y118151D01*
G01X1682246Y111951D02*
X1679046D01*
G01X1682246Y118151D02*
Y111951D01*
G01X1689966Y109424D02*
X1693166D01*
G01X1689966Y103224D02*
Y109424D01*
G01X1693166Y103224D02*
X1689966D01*
G01X1685966Y109424D02*
X1689166D01*
G01X1685966Y103224D02*
Y109424D01*
G01X1689166Y103224D02*
X1685966D01*
G01X1689166Y109424D02*
Y103224D01*
G01X1677763Y116088D02*
Y112888D01*
G01X1684420Y111734D02*
Y123508D01*
G01X1694182Y111734D02*
X1684420D01*
G01X1679046Y118151D02*
X1682246D01*
G01X1695191Y126223D02*
X1691991D01*
G01Y132423D02*
X1695191D01*
G01X1691991Y126223D02*
Y132423D01*
G01X1685191Y126223D02*
X1681991D01*
G01X1685191Y132423D02*
Y126223D01*
G01X1681991Y132423D02*
X1685191D01*
G01X1681991Y126223D02*
Y132423D01*
G01X1687991D02*
X1691191D01*
G01X1687991Y126223D02*
Y132423D01*
G01X1691191Y126223D02*
X1687991D01*
G01X1691191Y132423D02*
Y126223D01*
G01X1684420Y123508D02*
X1694182D01*
G01X1684380Y146229D02*
X1681180D01*
G01X1684380Y152429D02*
Y146229D01*
G01X1681180D02*
Y152429D01*
G01X1676500Y137107D02*
X1678722D01*
X1679187Y137260D01*
X1679497Y137567D01*
X1679600Y137950D01*
X1679497Y138333D01*
X1679187Y138640D01*
X1678722Y138793D01*
X1676500D01*
G01X1678980Y140207D02*
X1679342Y140437D01*
X1679548Y140743D01*
X1679600Y141088D01*
X1679548Y141395D01*
X1679290Y141702D01*
X1678980Y141893D01*
X1678670Y141932D01*
X1678308Y141855D01*
X1678050Y141587D01*
X1677947Y141318D01*
Y140973D01*
G01Y141318D02*
X1677792Y141548D01*
X1677533Y141740D01*
X1677223Y141817D01*
X1676913Y141740D01*
X1676655Y141548D01*
X1676500Y141203D01*
X1676552Y140858D01*
X1676758Y140513D01*
G01X1679238Y143498D02*
X1679497Y143767D01*
X1679600Y144073D01*
X1679497Y144380D01*
X1679187Y144648D01*
X1678722Y144840D01*
X1678257Y144917D01*
X1677688D01*
X1677223Y144840D01*
X1676810Y144648D01*
X1676603Y144418D01*
X1676500Y144150D01*
X1676603Y143843D01*
X1676810Y143613D01*
X1677120Y143460D01*
X1677533Y143383D01*
X1677895Y143460D01*
X1678257Y143652D01*
X1678463Y143882D01*
X1678515Y144150D01*
X1678412Y144457D01*
X1678153Y144687D01*
X1677688Y144917D01*
G01X1678308Y146522D02*
X1677947Y146790D01*
X1677740Y147020D01*
X1677637Y147327D01*
X1677740Y147595D01*
X1677947Y147787D01*
X1678257Y147940D01*
X1678618Y147978D01*
X1678928Y147940D01*
X1679238Y147787D01*
X1679497Y147557D01*
X1679600Y147288D01*
X1679497Y146982D01*
X1679187Y146713D01*
X1678722Y146560D01*
X1678205Y146522D01*
X1677533Y146598D01*
X1677172Y146713D01*
X1676810Y146905D01*
X1676552Y147173D01*
X1676500Y147442D01*
X1676603Y147710D01*
X1676862Y147902D01*
G01X1682870Y144395D02*
Y135095D01*
G01X1693470Y144395D02*
X1682870D01*
G01Y134995D02*
X1693470D01*
G01X1681180Y152429D02*
X1684380D01*
G01X1681180Y159540D02*
X1684380D01*
G01X1681180Y153340D02*
Y159540D01*
G01X1684380Y153340D02*
X1681180D01*
G01X1684380Y159540D02*
Y153340D01*
G01X1691093Y149950D02*
Y165304D01*
G01X1703771Y149950D02*
X1691093D01*
G01X1691290Y165304D02*
X1703771D01*
G01X1688183Y179600D02*
Y182700D01*
X1689103D01*
X1689410Y182545D01*
X1689640Y182183D01*
X1689717Y181770D01*
X1689640Y181357D01*
X1689448Y181047D01*
X1689103Y180892D01*
X1688183D01*
G01X1691207Y179600D02*
Y182700D01*
X1691973D01*
X1692280Y182545D01*
X1692510Y182338D01*
X1692702Y182028D01*
X1692855Y181667D01*
X1692893Y181150D01*
X1692855Y180633D01*
X1692702Y180272D01*
X1692510Y179962D01*
X1692280Y179755D01*
X1691973Y179600D01*
X1691207D01*
G01X1695073D02*
X1695150Y180272D01*
X1695265Y180840D01*
X1695418Y181357D01*
X1695610Y181925D01*
X1695917Y182700D01*
X1694383D01*
G01X1698710Y179600D02*
Y182700D01*
X1697292Y180478D01*
X1699208D01*
G01X1676206Y167065D02*
Y170265D01*
G01X1682406Y167065D02*
X1676206D01*
G01X1682406Y170265D02*
Y167065D01*
G01X1676206Y170265D02*
X1682406D01*
G01X1676206Y175065D02*
Y178265D01*
G01X1682406Y175065D02*
X1676206D01*
G01X1682406Y178265D02*
Y175065D01*
G01X1676206Y178265D02*
X1682406D01*
G01X1676206Y171065D02*
Y174265D01*
G01X1682406Y171065D02*
X1676206D01*
G01X1682406Y174265D02*
Y171065D01*
G01X1676206Y174265D02*
X1682406D01*
G01X1676206Y179065D02*
Y182265D01*
G01X1682406Y179065D02*
X1676206D01*
G01X1682406Y182265D02*
Y179065D01*
G01X1683974Y189435D02*
X1686214D01*
G01X1685001Y191060D02*
Y187810D01*
G01X1687615Y195583D02*
X1717174D01*
G01X1687615Y184087D02*
Y195583D01*
G01X1717174Y184087D02*
X1687615D01*
G01X1682406Y194265D02*
Y191065D01*
G01X1676206Y194265D02*
X1682406D01*
G01X1676206Y191065D02*
Y194265D01*
G01X1682406Y191065D02*
X1676206D01*
G01Y187065D02*
Y190265D01*
G01X1682406Y187065D02*
X1676206D01*
G01X1682406Y190265D02*
Y187065D01*
G01X1676206Y190265D02*
X1682406D01*
G01X1676206Y183065D02*
Y186265D01*
G01X1682406Y183065D02*
X1676206D01*
G01X1682406Y186265D02*
Y183065D01*
G01X1676206Y186265D02*
X1682406D01*
G01X1676206Y182265D02*
X1682406D01*
G01Y198265D02*
Y195065D01*
G01X1676206D02*
Y198265D01*
G01X1682406Y195065D02*
X1676206D01*
G01X1687768Y204506D02*
Y216506D01*
G01X1693768Y204506D02*
X1687768D01*
G01X1676301Y202464D02*
X1682501D01*
Y199264D01*
X1676301D01*
Y202464D01*
G01Y207264D02*
Y210464D01*
G01X1682501Y207264D02*
X1676301D01*
G01X1682501Y210464D02*
Y207264D01*
G01X1676301Y210464D02*
X1682501D01*
G01Y206464D02*
Y203264D01*
G01X1676301Y206464D02*
X1682501D01*
G01X1676301Y203264D02*
Y206464D01*
G01X1682501Y203264D02*
X1676301D01*
G01X1676206Y198265D02*
X1682406D01*
G01X1676301Y214464D02*
X1682501D01*
Y211264D01*
X1676301D01*
Y214464D01*
G01X1687768Y216506D02*
X1693768D01*
G01X1676301Y215264D02*
Y218464D01*
G01X1682501Y215264D02*
X1676301D01*
G01X1682501Y218464D02*
Y215264D01*
G01X1676301Y218464D02*
X1682501D01*
G01X1676301Y220264D02*
Y223464D01*
G01X1682501Y220264D02*
X1676301D01*
G01X1682501Y223464D02*
Y220264D01*
G01X1676301Y223464D02*
X1682501D01*
G01X1676298Y227319D02*
X1682498D01*
Y224119D01*
X1676298D01*
Y227319D01*
G01X1690536Y243678D02*
X1696736D01*
G01X1690536Y240478D02*
Y243678D01*
G01X1696736Y240478D02*
X1690536D01*
G01X1686566Y246771D02*
Y249971D01*
G01X1692766Y246771D02*
X1686566D01*
G01Y249971D02*
X1692766D01*
G01X1686566Y253971D02*
X1692766D01*
G01X1686566Y250771D02*
Y253971D01*
G01X1692766Y250771D02*
X1686566D01*
G01X1689200Y264583D02*
X1686100D01*
Y265503D01*
X1686255Y265810D01*
X1686617Y266040D01*
X1687030Y266117D01*
X1687443Y266040D01*
X1687753Y265848D01*
X1687908Y265503D01*
Y264583D01*
G01X1689200Y267607D02*
X1686100D01*
Y268373D01*
X1686255Y268680D01*
X1686462Y268910D01*
X1686772Y269102D01*
X1687133Y269255D01*
X1687650Y269293D01*
X1688167Y269255D01*
X1688528Y269102D01*
X1688838Y268910D01*
X1689045Y268680D01*
X1689200Y268373D01*
Y267607D01*
G01X1688580Y270707D02*
X1688942Y270937D01*
X1689148Y271243D01*
X1689200Y271588D01*
X1689148Y271895D01*
X1688890Y272202D01*
X1688580Y272393D01*
X1688270Y272432D01*
X1687908Y272355D01*
X1687650Y272087D01*
X1687547Y271818D01*
Y271473D01*
G01Y271818D02*
X1687392Y272048D01*
X1687133Y272240D01*
X1686823Y272317D01*
X1686513Y272240D01*
X1686255Y272048D01*
X1686100Y271703D01*
X1686152Y271358D01*
X1686358Y271013D01*
G01X1689200Y274573D02*
X1688528Y274650D01*
X1687960Y274765D01*
X1687443Y274918D01*
X1686875Y275110D01*
X1686100Y275417D01*
Y273883D01*
G01X1684573Y264635D02*
Y295727D01*
G01X1685123Y310215D02*
X1681923D01*
G01X1685123Y316415D02*
Y310215D01*
G01X1681923D02*
Y316415D01*
G01X1688187Y309749D02*
Y324749D01*
G01X1701187Y309749D02*
X1688187D01*
G01X1680273Y323621D02*
X1677164D01*
G01X1680273Y314959D02*
Y323621D01*
G01X1685211Y326084D02*
X1678611D01*
G01X1686711Y328584D02*
X1685211Y326084D01*
G01X1688211D02*
X1686711Y328584D01*
G01X1694811Y326084D02*
X1688211D01*
G01X1678611D02*
Y339084D01*
G01X1677403Y333542D02*
Y327342D01*
G01X1681923Y316415D02*
X1685123D01*
G01X1681923Y323415D02*
X1685123D01*
G01X1681923Y317215D02*
Y323415D01*
G01X1685123Y317215D02*
X1681923D01*
G01X1685123Y323415D02*
Y317215D01*
G01X1688187Y324749D02*
X1701187D01*
G01X1685507Y349110D02*
Y340646D01*
G01X1678611Y339084D02*
X1694811D01*
G01X1687076Y340794D02*
Y346994D01*
G01X1690276Y340794D02*
X1687076D01*
G01X1690276Y346994D02*
Y340794D01*
G01X1691076D02*
Y346994D01*
G01X1694276Y340794D02*
X1691076D01*
G01X1677376Y349110D02*
X1678876Y347339D01*
G01X1680376Y349110D02*
X1685507D01*
G01X1678876Y347339D02*
X1680376Y349110D01*
G01X1687068Y349250D02*
Y352450D01*
G01X1693268Y349250D02*
X1687068D01*
G01Y352450D02*
X1693268D01*
G01X1687076Y346994D02*
X1690276D01*
G01X1691076D02*
X1694276D01*
G01X1691809Y429437D02*
Y417437D01*
G01X1685809D02*
Y429437D01*
G01X1691809Y417437D02*
X1685809D01*
G01Y429437D02*
X1691809D01*
G01X1685809Y436931D02*
Y448931D01*
G01X1691809Y436931D02*
X1685809D01*
G01X1691809Y448931D02*
Y436931D01*
G01X1685809Y448931D02*
X1691809D01*
G01X1691445Y547512D02*
Y544312D01*
G01X1685245Y547512D02*
X1691445D01*
G01X1685245Y544312D02*
Y547512D01*
G01X1691445Y544312D02*
X1685245D01*
G01Y540312D02*
Y543512D01*
G01X1691445Y540312D02*
X1685245D01*
G01X1691445Y543512D02*
Y540312D01*
G01X1685245Y543512D02*
X1691445D01*
G01X1685245Y621312D02*
Y624512D01*
G01X1691445Y621312D02*
X1685245D01*
G01X1691445Y624512D02*
Y621312D01*
G01X1685245Y624512D02*
X1691445D01*
G01Y628512D02*
Y625312D01*
G01X1685245Y628512D02*
X1691445D01*
G01X1685245Y625312D02*
Y628512D01*
G01X1691445Y625312D02*
X1685245D01*
G01X1705844Y96067D02*
Y99267D01*
G01X1712044Y96067D02*
X1705844D01*
G01Y99267D02*
X1712044D01*
G01X1702583Y122172D02*
Y110172D01*
G01X1696583D02*
Y122172D01*
G01X1702583Y110172D02*
X1696583D01*
G01X1693966Y109424D02*
X1697166D01*
G01X1693966Y103224D02*
Y109424D01*
G01X1697166Y103224D02*
X1693966D01*
G01X1697166Y109424D02*
Y103224D01*
G01X1707860Y108095D02*
Y104895D01*
G01X1701660Y108095D02*
X1707860D01*
G01X1701660Y104895D02*
Y108095D01*
G01X1707860Y104895D02*
X1701660D01*
G01X1693166Y109424D02*
Y103224D01*
G01X1701660Y100895D02*
Y104095D01*
G01X1707860Y100895D02*
X1701660D01*
G01X1707860Y104095D02*
Y100895D01*
G01X1701660Y104095D02*
X1707860D01*
G01X1694182Y123508D02*
Y111734D01*
G01X1696583Y122172D02*
X1702583D01*
G01X1695191Y132423D02*
Y126223D01*
G01X1699245Y126228D02*
X1696045D01*
G01X1699245Y132428D02*
Y126228D01*
G01X1696045Y132428D02*
X1699245D01*
G01X1696045Y126228D02*
Y132428D01*
G01X1699424Y141337D02*
X1696224D01*
G01X1699424Y147537D02*
Y141337D01*
G01X1696224Y147537D02*
X1699424D01*
G01X1696224Y141337D02*
Y147537D01*
G01X1696089Y133238D02*
Y136438D01*
G01X1702289Y133238D02*
X1696089D01*
G01X1702289Y136438D02*
Y133238D01*
G01X1696089Y136438D02*
X1702289D01*
G01X1702635Y148437D02*
X1705835D01*
G01X1702635Y142237D02*
Y148437D01*
G01X1705835Y142237D02*
X1702635D01*
G01X1705835Y148437D02*
Y142237D01*
G01X1696089Y137238D02*
Y140438D01*
G01X1702289Y137238D02*
X1696089D01*
G01X1702289Y140438D02*
Y137238D01*
G01X1696089Y140438D02*
X1702289D01*
G01X1693470Y134995D02*
Y144395D01*
G01X1705300Y153107D02*
X1707522D01*
X1707987Y153260D01*
X1708297Y153567D01*
X1708400Y153950D01*
X1708297Y154333D01*
X1707987Y154640D01*
X1707522Y154793D01*
X1705300D01*
G01X1707780Y156207D02*
X1708142Y156437D01*
X1708348Y156743D01*
X1708400Y157088D01*
X1708348Y157395D01*
X1708090Y157702D01*
X1707780Y157893D01*
X1707470Y157932D01*
X1707108Y157855D01*
X1706850Y157587D01*
X1706747Y157318D01*
Y156973D01*
G01Y157318D02*
X1706592Y157548D01*
X1706333Y157740D01*
X1706023Y157817D01*
X1705713Y157740D01*
X1705455Y157548D01*
X1705300Y157203D01*
X1705352Y156858D01*
X1705558Y156513D01*
G01X1708400Y160073D02*
X1707728Y160150D01*
X1707160Y160265D01*
X1706643Y160418D01*
X1706075Y160610D01*
X1705300Y160917D01*
Y159383D01*
G01X1708400Y163250D02*
X1708348Y163518D01*
X1708193Y163825D01*
X1707935Y164017D01*
X1707573Y164093D01*
X1707212Y164017D01*
X1706902Y163787D01*
X1706747Y163442D01*
Y163058D01*
X1706643Y162828D01*
X1706385Y162637D01*
X1706023Y162560D01*
X1705662Y162675D01*
X1705403Y162943D01*
X1705300Y163250D01*
X1705403Y163557D01*
X1705662Y163825D01*
X1706023Y163940D01*
X1706385Y163863D01*
X1706643Y163672D01*
X1706747Y163442D01*
Y163058D01*
X1706902Y162713D01*
X1707212Y162483D01*
X1707573Y162407D01*
X1707935Y162483D01*
X1708193Y162675D01*
X1708348Y162982D01*
X1708400Y163250D01*
G01X1703771Y165304D02*
Y149950D01*
G01X1706591Y197645D02*
X1694591D01*
G01X1706591Y203645D02*
Y197645D01*
G01X1694591D02*
Y203645D01*
G01X1693768Y216506D02*
Y204506D01*
G01X1694591Y203645D02*
X1706591D01*
G01X1694568Y208306D02*
Y214506D01*
G01X1697768Y208306D02*
X1694568D01*
G01X1697768Y214506D02*
Y208306D01*
G01X1704544Y208464D02*
Y205264D01*
G01X1698344Y208464D02*
X1704544D01*
G01X1698344Y205264D02*
Y208464D01*
G01X1704544Y205264D02*
X1698344D01*
G01X1699374Y226801D02*
X1711578D01*
Y211497D01*
X1699374D01*
Y226801D01*
G01X1694568Y214506D02*
X1697768D01*
G01X1694934Y245521D02*
Y254969D01*
G01X1705770Y245521D02*
X1694934D01*
G01X1705770Y254969D02*
Y245521D01*
G01X1704037Y231446D02*
X1700837D01*
G01X1704037Y237646D02*
Y231446D01*
G01X1700837Y237646D02*
X1704037D01*
G01X1700837Y231446D02*
Y237646D01*
G01X1698510Y231334D02*
X1695310D01*
G01X1698510Y237534D02*
Y231334D01*
G01X1695310Y237534D02*
X1698510D01*
G01X1695310Y231334D02*
Y237534D01*
G01X1696736Y243678D02*
Y240478D01*
G01X1692766Y249971D02*
Y246771D01*
G01X1707912Y231434D02*
X1704712D01*
G01X1707912Y237634D02*
Y231434D01*
G01X1704712Y237634D02*
X1707912D01*
G01X1704712Y231434D02*
Y237634D01*
G01X1707573Y240081D02*
Y243281D01*
G01X1713773Y240081D02*
X1707573D01*
G01Y243281D02*
X1713773D01*
G01X1703715Y243678D02*
Y240478D01*
G01X1697515Y243678D02*
X1703715D01*
G01X1697515Y240478D02*
Y243678D01*
G01X1703715Y240478D02*
X1697515D01*
G01X1697215Y258664D02*
X1696908Y258716D01*
X1696640Y258922D01*
X1696410Y259232D01*
X1696257Y259594D01*
X1696180Y260007D01*
Y260421D01*
X1696257Y260834D01*
X1696410Y261196D01*
X1696640Y261506D01*
X1696908Y261712D01*
X1697215Y261764D01*
X1697522Y261712D01*
X1697790Y261506D01*
X1698020Y261196D01*
X1698173Y260834D01*
X1698250Y260421D01*
Y260007D01*
X1698173Y259594D01*
X1698020Y259232D01*
X1697790Y258922D01*
X1697522Y258716D01*
X1697215Y258664D01*
G01X1697522Y259491D02*
X1697982Y258664D01*
G01X1699587Y261247D02*
X1699817Y261557D01*
X1700085Y261712D01*
X1700392Y261764D01*
X1700775Y261661D01*
X1701043Y261402D01*
X1701120Y261092D01*
X1701082Y260782D01*
X1700928Y260524D01*
X1700162Y260007D01*
X1699817Y259646D01*
X1699587Y259129D01*
X1699510Y258664D01*
X1701120D01*
G01X1703415D02*
Y261764D01*
X1702955Y261144D01*
G01Y258664D02*
X1703875D01*
G01X1706515D02*
Y261764D01*
X1706055Y261144D01*
G01Y258664D02*
X1706975D01*
G01X1702352Y254969D02*
X1705770D01*
G01X1700352Y253245D02*
X1702352Y254969D01*
G01X1698352D02*
X1700352Y253245D01*
G01X1694934Y254969D02*
X1698352D01*
G01X1707177Y252199D02*
X1713377D01*
G01X1707177Y248999D02*
Y252199D01*
G01X1713377Y248999D02*
X1707177D01*
G01X1692766Y253971D02*
Y250771D01*
G01X1699817Y308252D02*
Y305052D01*
G01X1693617Y308252D02*
X1699817D01*
G01X1693617Y305052D02*
Y308252D01*
G01X1699817Y305052D02*
X1693617D01*
G01X1702300Y310657D02*
X1704522D01*
X1704987Y310810D01*
X1705297Y311117D01*
X1705400Y311500D01*
X1705297Y311883D01*
X1704987Y312190D01*
X1704522Y312343D01*
X1702300D01*
G01X1705400Y315060D02*
X1702300D01*
X1704522Y313642D01*
Y315558D01*
G01X1705400Y317623D02*
X1704728Y317700D01*
X1704160Y317815D01*
X1703643Y317968D01*
X1703075Y318160D01*
X1702300Y318467D01*
Y316933D01*
G01X1701187Y324749D02*
Y309749D01*
G01X1694811Y339084D02*
Y326084D01*
G01X1695900Y330907D02*
X1698122D01*
X1698587Y331060D01*
X1698897Y331367D01*
X1699000Y331750D01*
X1698897Y332133D01*
X1698587Y332440D01*
X1698122Y332593D01*
X1695900D01*
G01X1699000Y335310D02*
X1695900D01*
X1698122Y333892D01*
Y335808D01*
G01X1697708Y337222D02*
X1697347Y337490D01*
X1697140Y337720D01*
X1697037Y338027D01*
X1697140Y338295D01*
X1697347Y338487D01*
X1697657Y338640D01*
X1698018Y338678D01*
X1698328Y338640D01*
X1698638Y338487D01*
X1698897Y338257D01*
X1699000Y337988D01*
X1698897Y337682D01*
X1698587Y337413D01*
X1698122Y337260D01*
X1697605Y337222D01*
X1696933Y337298D01*
X1696572Y337413D01*
X1696210Y337605D01*
X1695952Y337873D01*
X1695900Y338142D01*
X1696003Y338410D01*
X1696262Y338602D01*
G01X1694276Y346994D02*
Y340794D01*
G01X1693268Y352450D02*
Y349250D01*
G01X1692945Y554812D02*
X1696145D01*
G01X1692945Y548612D02*
Y554812D01*
G01X1696145Y548612D02*
X1692945D01*
G01X1696145Y554812D02*
Y548612D01*
G01X1699457Y546700D02*
Y544478D01*
X1699610Y544013D01*
X1699917Y543703D01*
X1700300Y543600D01*
X1700683Y543703D01*
X1700990Y544013D01*
X1701143Y544478D01*
Y546700D01*
G01X1703860Y543600D02*
Y546700D01*
X1702442Y544478D01*
X1704358D01*
G01X1706960Y543600D02*
Y546700D01*
X1705542Y544478D01*
X1707458D01*
G01X1697606Y548035D02*
Y563389D01*
G01X1710087Y548035D02*
X1697606D01*
G01Y563389D02*
X1710284D01*
G01X1692741Y1067784D02*
G03X1755708Y1066535I31471J-1249D01*
G01X1699606Y1071456D02*
Y1258464D01*
G01X1755708Y1066535D02*
G03X1703945Y1090644I-31496J0D01*
G01X1708426Y1101367D02*
Y1104467D01*
G01X1710036D02*
Y1101367D01*
G01Y1102917D02*
X1708426D01*
G01X1711679Y1101729D02*
X1711948Y1101470D01*
X1712254Y1101367D01*
X1712561Y1101470D01*
X1712829Y1101780D01*
X1713021Y1102245D01*
X1713098Y1102710D01*
Y1103279D01*
X1713021Y1103744D01*
X1712829Y1104157D01*
X1712599Y1104364D01*
X1712331Y1104467D01*
X1712024Y1104364D01*
X1711794Y1104157D01*
X1711641Y1103847D01*
X1711564Y1103434D01*
X1711641Y1103072D01*
X1711833Y1102710D01*
X1712063Y1102504D01*
X1712331Y1102452D01*
X1712638Y1102555D01*
X1712868Y1102814D01*
X1713098Y1103279D01*
G01X1714779Y1101729D02*
X1715048Y1101470D01*
X1715354Y1101367D01*
X1715661Y1101470D01*
X1715929Y1101780D01*
X1716121Y1102245D01*
X1716198Y1102710D01*
Y1103279D01*
X1716121Y1103744D01*
X1715929Y1104157D01*
X1715699Y1104364D01*
X1715431Y1104467D01*
X1715124Y1104364D01*
X1714894Y1104157D01*
X1714741Y1103847D01*
X1714664Y1103434D01*
X1714741Y1103072D01*
X1714933Y1102710D01*
X1715163Y1102504D01*
X1715431Y1102452D01*
X1715738Y1102555D01*
X1715968Y1102814D01*
X1716198Y1103279D01*
G01X1709615Y1141804D02*
Y1135604D01*
X1706415D01*
Y1141804D01*
X1709615D01*
G01X1703539Y1156532D02*
X1705761D01*
X1706226Y1156685D01*
X1706536Y1156992D01*
X1706639Y1157375D01*
X1706536Y1157758D01*
X1706226Y1158065D01*
X1705761Y1158218D01*
X1703539D01*
G01X1706639Y1160935D02*
X1703539D01*
X1705761Y1159517D01*
Y1161433D01*
G01X1704056Y1162847D02*
X1703746Y1163077D01*
X1703591Y1163345D01*
X1703539Y1163652D01*
X1703642Y1164035D01*
X1703901Y1164303D01*
X1704211Y1164380D01*
X1704521Y1164342D01*
X1704779Y1164188D01*
X1705296Y1163422D01*
X1705657Y1163077D01*
X1706174Y1162847D01*
X1706639Y1162770D01*
Y1164380D01*
G01Y1166675D02*
X1706587Y1166943D01*
X1706432Y1167250D01*
X1706174Y1167442D01*
X1705812Y1167518D01*
X1705451Y1167442D01*
X1705141Y1167212D01*
X1704986Y1166867D01*
Y1166483D01*
X1704882Y1166253D01*
X1704624Y1166062D01*
X1704262Y1165985D01*
X1703901Y1166100D01*
X1703642Y1166368D01*
X1703539Y1166675D01*
X1703642Y1166982D01*
X1703901Y1167250D01*
X1704262Y1167365D01*
X1704624Y1167288D01*
X1704882Y1167097D01*
X1704986Y1166867D01*
Y1166483D01*
X1705141Y1166138D01*
X1705451Y1165908D01*
X1705812Y1165832D01*
X1706174Y1165908D01*
X1706432Y1166100D01*
X1706587Y1166407D01*
X1706639Y1166675D01*
G01X1707605Y1161425D02*
X1708798Y1160525D01*
X1707605Y1159525D01*
G01Y1161525D02*
Y1164625D01*
X1720007D01*
Y1156425D01*
X1707605D01*
Y1159525D01*
G01X1710489Y1180425D02*
Y1174225D01*
X1707289D01*
Y1180425D01*
X1710489D01*
G01X1711420Y1194990D02*
X1708220D01*
G01Y1201190D02*
X1711420D01*
G01X1708220Y1194990D02*
Y1201190D01*
G01X1711427Y1207940D02*
Y1201740D01*
X1708227D01*
Y1207940D01*
X1711427D01*
G01X1710345Y1228800D02*
Y1222600D01*
X1707145D01*
Y1228800D01*
X1710345D01*
G01X1703158Y1239961D02*
G03X1727193Y1232033I21053J23428D01*
G01X1755708Y1263386D02*
G03X1692719Y1262968I-31496J0D01*
G01X1696553Y1290353D02*
Y1293453D01*
G01X1698163D02*
Y1290353D01*
G01Y1291903D02*
X1696553D01*
G01X1699806Y1290715D02*
X1700075Y1290456D01*
X1700381Y1290353D01*
X1700688Y1290456D01*
X1700956Y1290766D01*
X1701148Y1291231D01*
X1701225Y1291696D01*
Y1292265D01*
X1701148Y1292730D01*
X1700956Y1293143D01*
X1700726Y1293350D01*
X1700458Y1293453D01*
X1700151Y1293350D01*
X1699921Y1293143D01*
X1699768Y1292833D01*
X1699691Y1292420D01*
X1699768Y1292058D01*
X1699960Y1291696D01*
X1700190Y1291490D01*
X1700458Y1291438D01*
X1700765Y1291541D01*
X1700995Y1291800D01*
X1701225Y1292265D01*
G01X1702715Y1290973D02*
X1702945Y1290611D01*
X1703251Y1290405D01*
X1703596Y1290353D01*
X1703903Y1290405D01*
X1704210Y1290663D01*
X1704401Y1290973D01*
X1704440Y1291283D01*
X1704363Y1291645D01*
X1704095Y1291903D01*
X1703826Y1292006D01*
X1703481D01*
G01X1703826D02*
X1704056Y1292161D01*
X1704248Y1292420D01*
X1704325Y1292730D01*
X1704248Y1293040D01*
X1704056Y1293298D01*
X1703711Y1293453D01*
X1703366Y1293401D01*
X1703021Y1293195D01*
G01X1716987Y57756D02*
Y111477D01*
G01X1717283Y58150D02*
Y111477D01*
G01X1714305Y57726D02*
X1714615Y57918D01*
X1714822Y58148D01*
X1714925Y58416D01*
X1714822Y58723D01*
X1714615Y58953D01*
X1714305Y59183D01*
X1713892Y59260D01*
X1711825D01*
G01X1714925Y62053D02*
X1711825D01*
X1714047Y60635D01*
Y62551D01*
G01X1714460Y63850D02*
X1714718Y64080D01*
X1714873Y64348D01*
X1714925Y64693D01*
X1714822Y65038D01*
X1714615Y65306D01*
X1714253Y65498D01*
X1713840Y65536D01*
X1713427Y65460D01*
X1713168Y65268D01*
X1712962Y65000D01*
X1712910Y64731D01*
X1712962Y64463D01*
X1713168Y64118D01*
X1711825Y64233D01*
Y65268D01*
G01X1723368Y57756D02*
X1716987D01*
G01X1722963Y58150D02*
X1717283D01*
G01X1712044Y99267D02*
Y96067D01*
G01X1717283Y118848D02*
Y114048D01*
G01X1716987Y118848D02*
Y114048D01*
G01X1708717Y108086D02*
X1711917D01*
G01X1708717Y101886D02*
Y108086D01*
G01X1711917Y101886D02*
X1708717D01*
G01X1711917Y108086D02*
Y101886D01*
G01X1717283Y132607D02*
Y128340D01*
G01X1716987Y132607D02*
Y128340D01*
G01Y125781D02*
Y121219D01*
G01X1717283Y125781D02*
Y121219D01*
G01Y152756D02*
Y135450D01*
G01X1716987Y153150D02*
Y135450D01*
G01Y153150D02*
X1723368D01*
G01X1717283Y152756D02*
X1722963D01*
G01X1720714Y189535D02*
X1718288D01*
G01X1717174Y195583D02*
Y184087D01*
G01X1718586Y214398D02*
X1715486D01*
Y215318D01*
X1715641Y215625D01*
X1716003Y215855D01*
X1716416Y215932D01*
X1716829Y215855D01*
X1717139Y215663D01*
X1717294Y215318D01*
Y214398D01*
G01X1715486Y217422D02*
X1717708D01*
X1718173Y217575D01*
X1718483Y217882D01*
X1718586Y218265D01*
X1718483Y218648D01*
X1718173Y218955D01*
X1717708Y219108D01*
X1715486D01*
G01X1717294Y220637D02*
X1716933Y220905D01*
X1716726Y221135D01*
X1716623Y221442D01*
X1716726Y221710D01*
X1716933Y221902D01*
X1717243Y222055D01*
X1717604Y222093D01*
X1717914Y222055D01*
X1718224Y221902D01*
X1718483Y221672D01*
X1718586Y221403D01*
X1718483Y221097D01*
X1718173Y220828D01*
X1717708Y220675D01*
X1717191Y220637D01*
X1716519Y220713D01*
X1716158Y220828D01*
X1715796Y221020D01*
X1715538Y221288D01*
X1715486Y221557D01*
X1715589Y221825D01*
X1715848Y222017D01*
G01X1718586Y224465D02*
X1718534Y224733D01*
X1718379Y225040D01*
X1718121Y225232D01*
X1717759Y225308D01*
X1717398Y225232D01*
X1717088Y225002D01*
X1716933Y224657D01*
Y224273D01*
X1716829Y224043D01*
X1716571Y223852D01*
X1716209Y223775D01*
X1715848Y223890D01*
X1715589Y224158D01*
X1715486Y224465D01*
X1715589Y224772D01*
X1715848Y225040D01*
X1716209Y225155D01*
X1716571Y225078D01*
X1716829Y224887D01*
X1716933Y224657D01*
Y224273D01*
X1717088Y223928D01*
X1717398Y223698D01*
X1717759Y223622D01*
X1718121Y223698D01*
X1718379Y223890D01*
X1718534Y224197D01*
X1718586Y224465D01*
G01X1716147Y231459D02*
X1712947D01*
G01X1716147Y237659D02*
Y231459D01*
G01X1712947Y237659D02*
X1716147D01*
G01X1712947Y231459D02*
Y237659D01*
G01X1708947D02*
X1712147D01*
G01X1708947Y231459D02*
Y237659D01*
G01X1712147Y231459D02*
X1708947D01*
G01X1712147Y237659D02*
Y231459D01*
G01X1713773Y243281D02*
Y240081D01*
G01X1713377Y252199D02*
Y248999D01*
G01X1726803Y388619D02*
X1724850D01*
G01D02*
Y390572D01*
G01X1720451Y392408D02*
X1717251D01*
G01X1720451Y398608D02*
Y392408D01*
G01X1717251D02*
Y398608D01*
G01X1712146Y384248D02*
X1715346D01*
G01X1712146Y378048D02*
Y384248D01*
G01X1715346Y378048D02*
X1712146D01*
G01X1715346Y384248D02*
Y378048D01*
G01X1716146Y384248D02*
X1719346D01*
G01X1716146Y378048D02*
Y384248D01*
G01X1719346Y378048D02*
X1716146D01*
G01X1719346Y384248D02*
Y378048D01*
G01X1724146Y384248D02*
X1727346D01*
G01X1724146Y378048D02*
Y384248D01*
G01X1727346Y378048D02*
X1724146D01*
G01X1720146Y384248D02*
X1723346D01*
G01X1720146Y378048D02*
Y384248D01*
G01X1723346Y378048D02*
X1720146D01*
G01X1723346Y384248D02*
Y378048D01*
G01X1724850Y400431D02*
X1726803D01*
G01X1724850Y398478D02*
Y400431D01*
G01X1721074Y399509D02*
X1718812Y401771D01*
G01X1725458Y403893D02*
X1721074Y399509D01*
G01X1723196Y406155D02*
X1725458Y403893D01*
G01X1718812Y401771D02*
X1723196Y406155D01*
G01X1717251Y398608D02*
X1720451D01*
G01X1722862Y407402D02*
Y413602D01*
G01X1726062Y407402D02*
X1722862D01*
G01X1711708Y415040D02*
X1742712D01*
G01X1711708Y429840D02*
Y415040D01*
G01X1722862Y413602D02*
X1726062D01*
G01X1742712Y429840D02*
X1711708D01*
G01X1723385Y459934D02*
Y456734D01*
G01X1717185D02*
Y459934D01*
G01X1723385Y456734D02*
X1717185D01*
G01X1723385Y451934D02*
Y448734D01*
G01X1717185Y451934D02*
X1723385D01*
G01X1717185Y448734D02*
Y451934D01*
G01X1723385Y448734D02*
X1717185D01*
G01Y452734D02*
Y455934D01*
G01X1723385Y452734D02*
X1717185D01*
G01X1723385Y455934D02*
Y452734D01*
G01X1717185Y455934D02*
X1723385D01*
G01X1714031Y449114D02*
X1710931D01*
Y450034D01*
X1711086Y450341D01*
X1711448Y450571D01*
X1711861Y450648D01*
X1712274Y450571D01*
X1712584Y450379D01*
X1712739Y450034D01*
Y449114D01*
G01X1710931Y452138D02*
X1713153D01*
X1713618Y452291D01*
X1713928Y452598D01*
X1714031Y452981D01*
X1713928Y453364D01*
X1713618Y453671D01*
X1713153Y453824D01*
X1710931D01*
G01X1714031Y456081D02*
X1710931D01*
X1711551Y455621D01*
G01X1714031D02*
Y456541D01*
G01X1711448Y458453D02*
X1711138Y458683D01*
X1710983Y458951D01*
X1710931Y459258D01*
X1711034Y459641D01*
X1711293Y459909D01*
X1711603Y459986D01*
X1711913Y459948D01*
X1712171Y459794D01*
X1712688Y459028D01*
X1713049Y458683D01*
X1713566Y458453D01*
X1714031Y458376D01*
Y459986D01*
G01X1711448Y461553D02*
X1711138Y461783D01*
X1710983Y462051D01*
X1710931Y462358D01*
X1711034Y462741D01*
X1711293Y463009D01*
X1711603Y463086D01*
X1711913Y463048D01*
X1712171Y462894D01*
X1712688Y462128D01*
X1713049Y461783D01*
X1713566Y461553D01*
X1714031Y461476D01*
Y463086D01*
G01X1719289Y464270D02*
Y466696D01*
G01X1712600Y468383D02*
X1709500D01*
Y469303D01*
X1709655Y469610D01*
X1710017Y469840D01*
X1710430Y469917D01*
X1710843Y469840D01*
X1711153Y469648D01*
X1711308Y469303D01*
Y468383D01*
G01X1712600Y471407D02*
X1709500D01*
Y472173D01*
X1709655Y472480D01*
X1709862Y472710D01*
X1710172Y472902D01*
X1710533Y473055D01*
X1711050Y473093D01*
X1711567Y473055D01*
X1711928Y472902D01*
X1712238Y472710D01*
X1712445Y472480D01*
X1712600Y472173D01*
Y471407D01*
G01X1712135Y474507D02*
X1712393Y474737D01*
X1712548Y475005D01*
X1712600Y475350D01*
X1712497Y475695D01*
X1712290Y475963D01*
X1711928Y476155D01*
X1711515Y476193D01*
X1711102Y476117D01*
X1710843Y475925D01*
X1710637Y475657D01*
X1710585Y475388D01*
X1710637Y475120D01*
X1710843Y474775D01*
X1709500Y474890D01*
Y475925D01*
G01X1712238Y477798D02*
X1712497Y478067D01*
X1712600Y478373D01*
X1712497Y478680D01*
X1712187Y478948D01*
X1711722Y479140D01*
X1711257Y479217D01*
X1710688D01*
X1710223Y479140D01*
X1709810Y478948D01*
X1709603Y478718D01*
X1709500Y478450D01*
X1709603Y478143D01*
X1709810Y477913D01*
X1710120Y477760D01*
X1710533Y477683D01*
X1710895Y477760D01*
X1711257Y477952D01*
X1711463Y478182D01*
X1711515Y478450D01*
X1711412Y478757D01*
X1711153Y478987D01*
X1710688Y479217D01*
G01X1725337Y467810D02*
X1713841D01*
G01D02*
Y497369D01*
G01X1717185Y459934D02*
X1723385D01*
G01X1719189Y501010D02*
Y498770D01*
G01X1720814Y499983D02*
X1717564D01*
G01X1713841Y497369D02*
X1725337D01*
G01X1711945Y553612D02*
Y559812D01*
G01X1715145Y553612D02*
X1711945D01*
G01X1715145Y559812D02*
Y553612D01*
G01X1710284Y563389D02*
Y548035D01*
G01X1715145Y560612D02*
X1711945D01*
G01X1715145Y566812D02*
Y560612D01*
G01X1711945Y566812D02*
X1715145D01*
G01X1711945Y560612D02*
Y566812D01*
G01Y559812D02*
X1715145D01*
G01X1722608Y1135604D02*
X1719408D01*
G01X1722608Y1141804D02*
Y1135604D01*
G01X1719408D02*
Y1141804D01*
G01X1715408Y1135604D02*
Y1141804D01*
G01X1718608Y1135604D02*
X1715408D01*
G01X1718608Y1141804D02*
Y1135604D01*
G01X1726608D02*
X1723408D01*
G01D02*
Y1141804D01*
G01X1714608Y1135604D02*
X1711408D01*
G01X1714608Y1141804D02*
Y1135604D01*
G01X1711408D02*
Y1141804D01*
G01X1722006Y1149643D02*
Y1161167D01*
G01X1734210Y1149643D02*
X1722006D01*
G01X1719408Y1141804D02*
X1722608D01*
G01X1715408D02*
X1718608D01*
G01X1723408D02*
X1726608D01*
G01X1711408D02*
X1714608D01*
G01X1719785Y1144471D02*
X1713585D01*
Y1147671D01*
X1719785D01*
Y1144471D01*
G01X1722006Y1161167D02*
X1734210D01*
G01X1720516Y1169520D02*
Y1172720D01*
G01X1726716Y1169520D02*
X1720516D01*
G01X1724074Y1179765D02*
X1727274D01*
G01X1724074Y1173565D02*
Y1179765D01*
G01X1727274Y1173565D02*
X1724074D01*
G01X1720074Y1179765D02*
X1723274D01*
G01X1720074Y1173565D02*
Y1179765D01*
G01X1723274Y1173565D02*
X1720074D01*
G01X1723274Y1179765D02*
Y1173565D01*
G01X1720516Y1172720D02*
X1726716D01*
G01X1724102Y1186730D02*
X1727302D01*
G01X1724102Y1180530D02*
Y1186730D01*
G01X1727302Y1180530D02*
X1724102D01*
G01X1720102Y1186730D02*
X1723302D01*
G01X1720102Y1180530D02*
Y1186730D01*
G01X1723302Y1180530D02*
X1720102D01*
G01X1723302Y1186730D02*
Y1180530D01*
G01X1711115Y1180445D02*
Y1186645D01*
X1714315D01*
Y1180445D01*
X1711115D01*
G01X1715131Y1180375D02*
Y1186575D01*
X1718331D01*
Y1180375D01*
X1715131D01*
G01X1723262Y1201918D02*
X1720062D01*
G01X1723262Y1208118D02*
Y1201918D01*
G01X1720062D02*
Y1208118D01*
G01X1727262Y1201918D02*
X1724062D01*
G01D02*
Y1208118D01*
G01X1723260Y1193894D02*
X1720060D01*
G01X1723260Y1200094D02*
Y1193894D01*
G01X1720060Y1200094D02*
X1723260D01*
G01X1720060Y1193894D02*
Y1200094D01*
G01X1727260Y1193894D02*
X1724060D01*
G01Y1200094D02*
X1727260D01*
G01X1724060Y1193894D02*
Y1200094D01*
G01X1711420Y1201190D02*
Y1194990D01*
G01X1719168Y1201718D02*
X1715968D01*
G01X1719168Y1207918D02*
Y1201718D01*
G01X1715968D02*
Y1207918D01*
G01X1715321Y1207986D02*
Y1201786D01*
X1712121D01*
Y1207986D01*
X1715321D01*
G01X1720062Y1208118D02*
X1723262D01*
G01X1724062D02*
X1727262D01*
G01X1722992Y1221417D02*
X1720730Y1219155D01*
G01X1718608Y1225801D02*
X1722992Y1221417D01*
G01X1720730Y1219155D02*
X1716346Y1223539D01*
G01X1720163Y1218590D02*
X1717901Y1216328D01*
G01X1715779Y1222974D02*
X1720163Y1218590D01*
G01X1713517Y1220712D02*
X1715779Y1222974D01*
G01X1717901Y1216328D02*
X1713517Y1220712D01*
G01X1723044Y1217761D02*
X1725306Y1220023D01*
G01X1727428Y1213377D02*
X1723044Y1217761D01*
G01X1726862Y1212811D02*
X1724600Y1210549D01*
G01X1722478Y1217195D02*
X1726862Y1212811D01*
G01X1720216Y1214933D02*
X1722478Y1217195D01*
G01X1724600Y1210549D02*
X1720216Y1214933D01*
G01X1715968Y1207918D02*
X1719168D01*
G01X1716346Y1223539D02*
X1718608Y1225801D01*
G01X1725821Y1224246D02*
X1723559Y1221984D01*
G01X1721437Y1228630D02*
X1725821Y1224246D01*
G01X1719175Y1226368D02*
X1721437Y1228630D01*
G01X1723559Y1221984D02*
X1719175Y1226368D01*
G01X1724266Y1231459D02*
X1728650Y1227075D01*
G01X1722004Y1229197D02*
X1724266Y1231459D01*
G01X1726388Y1224813D02*
X1722004Y1229197D01*
G01X1714566Y1228791D02*
Y1222591D01*
X1711366D01*
Y1228791D01*
X1714566D01*
G01X1726166Y1701772D02*
X1726476Y1701964D01*
X1726683Y1702194D01*
X1726786Y1702462D01*
X1726683Y1702769D01*
X1726476Y1702999D01*
X1726166Y1703229D01*
X1725753Y1703306D01*
X1723686D01*
G01X1726786Y1706099D02*
X1723686D01*
X1725908Y1704681D01*
Y1706597D01*
G01X1725494Y1708011D02*
X1725133Y1708279D01*
X1724926Y1708509D01*
X1724823Y1708816D01*
X1724926Y1709084D01*
X1725133Y1709276D01*
X1725443Y1709429D01*
X1725804Y1709467D01*
X1726114Y1709429D01*
X1726424Y1709276D01*
X1726683Y1709046D01*
X1726786Y1708777D01*
X1726683Y1708471D01*
X1726373Y1708202D01*
X1725908Y1708049D01*
X1725391Y1708011D01*
X1724719Y1708087D01*
X1724358Y1708202D01*
X1723996Y1708394D01*
X1723738Y1708662D01*
X1723686Y1708931D01*
X1723789Y1709199D01*
X1724048Y1709391D01*
G01X1726166Y1730791D02*
X1726476Y1730983D01*
X1726683Y1731213D01*
X1726786Y1731481D01*
X1726683Y1731788D01*
X1726476Y1732018D01*
X1726166Y1732248D01*
X1725753Y1732325D01*
X1723686D01*
G01X1726786Y1735118D02*
X1723686D01*
X1725908Y1733700D01*
Y1735616D01*
G01X1726786Y1737758D02*
X1726734Y1738026D01*
X1726579Y1738333D01*
X1726321Y1738525D01*
X1725959Y1738601D01*
X1725598Y1738525D01*
X1725288Y1738295D01*
X1725133Y1737950D01*
Y1737566D01*
X1725029Y1737336D01*
X1724771Y1737145D01*
X1724409Y1737068D01*
X1724048Y1737183D01*
X1723789Y1737451D01*
X1723686Y1737758D01*
X1723789Y1738065D01*
X1724048Y1738333D01*
X1724409Y1738448D01*
X1724771Y1738371D01*
X1725029Y1738180D01*
X1725133Y1737950D01*
Y1737566D01*
X1725288Y1737221D01*
X1725598Y1736991D01*
X1725959Y1736915D01*
X1726321Y1736991D01*
X1726579Y1737183D01*
X1726734Y1737490D01*
X1726786Y1737758D01*
G01X1726159Y1759960D02*
X1726469Y1760152D01*
X1726676Y1760382D01*
X1726779Y1760650D01*
X1726676Y1760957D01*
X1726469Y1761187D01*
X1726159Y1761417D01*
X1725746Y1761494D01*
X1723679D01*
G01X1726314Y1762984D02*
X1726572Y1763214D01*
X1726727Y1763482D01*
X1726779Y1763827D01*
X1726676Y1764172D01*
X1726469Y1764440D01*
X1726107Y1764632D01*
X1725694Y1764670D01*
X1725281Y1764594D01*
X1725022Y1764402D01*
X1724816Y1764134D01*
X1724764Y1763865D01*
X1724816Y1763597D01*
X1725022Y1763252D01*
X1723679Y1763367D01*
Y1764402D01*
G01X1724196Y1766199D02*
X1723886Y1766429D01*
X1723731Y1766697D01*
X1723679Y1767004D01*
X1723782Y1767387D01*
X1724041Y1767655D01*
X1724351Y1767732D01*
X1724661Y1767694D01*
X1724919Y1767540D01*
X1725436Y1766774D01*
X1725797Y1766429D01*
X1726314Y1766199D01*
X1726779Y1766122D01*
Y1767732D01*
G01X1737536Y-79278D02*
Y-62678D01*
X1747136D01*
Y-79278D01*
X1737536D01*
G01X1731507Y-59700D02*
Y-56600D01*
X1732273D01*
X1732580Y-56755D01*
X1732810Y-56962D01*
X1733002Y-57272D01*
X1733155Y-57633D01*
X1733193Y-58150D01*
X1733155Y-58667D01*
X1733002Y-59028D01*
X1732810Y-59338D01*
X1732580Y-59545D01*
X1732273Y-59700D01*
X1731507D01*
G01X1736217D02*
X1734683D01*
Y-56600D01*
X1736217D01*
G01X1735603Y-58098D02*
X1734683D01*
G01X1738550Y-56600D02*
X1738243Y-56703D01*
X1738013Y-56962D01*
X1737860Y-57272D01*
X1737745Y-57685D01*
X1737707Y-58150D01*
X1737745Y-58615D01*
X1737860Y-59028D01*
X1738013Y-59338D01*
X1738243Y-59597D01*
X1738550Y-59700D01*
X1738857Y-59597D01*
X1739087Y-59338D01*
X1739240Y-59028D01*
X1739355Y-58615D01*
X1739393Y-58150D01*
X1739355Y-57685D01*
X1739240Y-57272D01*
X1739087Y-56962D01*
X1738857Y-56703D01*
X1738550Y-56600D01*
G01X1740807Y-59235D02*
X1741037Y-59493D01*
X1741305Y-59648D01*
X1741650Y-59700D01*
X1741995Y-59597D01*
X1742263Y-59390D01*
X1742455Y-59028D01*
X1742493Y-58615D01*
X1742417Y-58202D01*
X1742225Y-57943D01*
X1741957Y-57737D01*
X1741688Y-57685D01*
X1741420Y-57737D01*
X1741075Y-57943D01*
X1741190Y-56600D01*
X1742225D01*
G01X1744022Y-59700D02*
Y-56600D01*
X1745478D01*
G01X1744942Y-58098D02*
X1744022D01*
G01X1746700Y-60733D02*
X1749000D01*
G01X1750950Y-59700D02*
Y-56600D01*
X1750490Y-57220D01*
G01Y-59700D02*
X1751410D01*
G01X1741791Y57756D02*
X1735410D01*
G01X1741495Y58150D02*
X1735815D01*
G01X1730441Y156615D02*
X1731188Y155990D01*
X1732028Y155615D01*
X1732774D01*
X1733521Y155990D01*
X1734081Y156615D01*
X1734361Y157490D01*
X1734174Y158365D01*
X1733708Y159115D01*
X1732868Y159615D01*
X1731748Y159865D01*
X1731094Y160365D01*
X1730814Y161240D01*
X1731001Y162115D01*
X1731468Y162740D01*
X1732121Y163115D01*
X1732774D01*
X1733428Y162865D01*
X1733988Y162240D01*
G01X1737941Y156615D02*
X1738688Y155990D01*
X1739528Y155615D01*
X1740274D01*
X1741021Y155990D01*
X1741581Y156615D01*
X1741861Y157490D01*
X1741674Y158365D01*
X1741208Y159115D01*
X1740368Y159615D01*
X1739248Y159865D01*
X1738594Y160365D01*
X1738314Y161240D01*
X1738501Y162115D01*
X1738968Y162740D01*
X1739621Y163115D01*
X1740274D01*
X1740928Y162865D01*
X1741488Y162240D01*
G01X1745348Y155615D02*
Y163115D01*
X1747214D01*
X1747961Y162740D01*
X1748521Y162240D01*
X1748988Y161490D01*
X1749361Y160615D01*
X1749454Y159365D01*
X1749361Y158115D01*
X1748988Y157240D01*
X1748521Y156490D01*
X1747961Y155990D01*
X1747214Y155615D01*
X1745348D01*
G01X1754901D02*
Y163115D01*
X1753781Y161615D01*
G01Y155615D02*
X1756021D01*
G01X1760348Y156740D02*
X1760908Y156115D01*
X1761561Y155740D01*
X1762401Y155615D01*
X1763241Y155865D01*
X1763894Y156365D01*
X1764361Y157240D01*
X1764454Y158240D01*
X1764268Y159240D01*
X1763801Y159865D01*
X1763148Y160365D01*
X1762494Y160490D01*
X1761841Y160365D01*
X1761001Y159865D01*
X1761281Y163115D01*
X1763801D01*
G01X1733891Y164436D02*
X1748691D01*
G01X1733891Y195440D02*
Y164436D01*
G01X1735410Y153150D02*
X1741791D01*
G01X1735815Y152756D02*
X1741495D01*
G01X1748691Y195440D02*
X1733891D01*
G01X1731200Y204183D02*
X1728100D01*
Y205103D01*
X1728255Y205410D01*
X1728617Y205640D01*
X1729030Y205717D01*
X1729443Y205640D01*
X1729753Y205448D01*
X1729908Y205103D01*
Y204183D01*
G01X1731200Y207207D02*
X1728100D01*
Y207973D01*
X1728255Y208280D01*
X1728462Y208510D01*
X1728772Y208702D01*
X1729133Y208855D01*
X1729650Y208893D01*
X1730167Y208855D01*
X1730528Y208702D01*
X1730838Y208510D01*
X1731045Y208280D01*
X1731200Y207973D01*
Y207207D01*
G01Y211150D02*
X1728100D01*
X1728720Y210690D01*
G01X1731200D02*
Y211610D01*
G01X1728617Y213522D02*
X1728307Y213752D01*
X1728152Y214020D01*
X1728100Y214327D01*
X1728203Y214710D01*
X1728462Y214978D01*
X1728772Y215055D01*
X1729082Y215017D01*
X1729340Y214863D01*
X1729857Y214097D01*
X1730218Y213752D01*
X1730735Y213522D01*
X1731200Y213445D01*
Y215055D01*
G01X1730580Y216507D02*
X1730942Y216737D01*
X1731148Y217043D01*
X1731200Y217388D01*
X1731148Y217695D01*
X1730890Y218002D01*
X1730580Y218193D01*
X1730270Y218232D01*
X1729908Y218155D01*
X1729650Y217887D01*
X1729547Y217618D01*
Y217273D01*
G01Y217618D02*
X1729392Y217848D01*
X1729133Y218040D01*
X1728823Y218117D01*
X1728513Y218040D01*
X1728255Y217848D01*
X1728100Y217503D01*
X1728152Y217158D01*
X1728358Y216813D01*
G01X1737894Y199912D02*
Y202338D01*
G01X1743942Y203452D02*
X1732446D01*
G01D02*
Y233011D01*
G01X1737794Y236652D02*
Y234412D01*
G01X1739419Y235625D02*
X1736169D01*
G01X1732446Y233011D02*
X1743942D01*
G01X1737663Y259204D02*
Y261630D01*
G01X1730800Y263183D02*
X1727700D01*
Y264103D01*
X1727855Y264410D01*
X1728217Y264640D01*
X1728630Y264717D01*
X1729043Y264640D01*
X1729353Y264448D01*
X1729508Y264103D01*
Y263183D01*
G01X1730800Y266207D02*
X1727700D01*
Y266973D01*
X1727855Y267280D01*
X1728062Y267510D01*
X1728372Y267702D01*
X1728733Y267855D01*
X1729250Y267893D01*
X1729767Y267855D01*
X1730128Y267702D01*
X1730438Y267510D01*
X1730645Y267280D01*
X1730800Y266973D01*
Y266207D01*
G01X1730335Y269307D02*
X1730593Y269537D01*
X1730748Y269805D01*
X1730800Y270150D01*
X1730697Y270495D01*
X1730490Y270763D01*
X1730128Y270955D01*
X1729715Y270993D01*
X1729302Y270917D01*
X1729043Y270725D01*
X1728837Y270457D01*
X1728785Y270188D01*
X1728837Y269920D01*
X1729043Y269575D01*
X1727700Y269690D01*
Y270725D01*
G01X1730800Y273250D02*
X1727700D01*
X1728320Y272790D01*
G01X1730800D02*
Y273710D01*
G01X1743711Y262744D02*
X1732215D01*
G01D02*
Y292303D01*
G01X1737809Y297413D02*
Y295173D01*
G01X1739434Y296386D02*
X1736184D01*
G01X1732215Y292303D02*
X1743711D01*
G01X1738700Y392257D02*
X1740922D01*
X1741387Y392410D01*
X1741697Y392717D01*
X1741800Y393100D01*
X1741697Y393483D01*
X1741387Y393790D01*
X1740922Y393943D01*
X1738700D01*
G01X1741800Y396200D02*
X1741748Y396468D01*
X1741593Y396775D01*
X1741335Y396967D01*
X1740973Y397043D01*
X1740612Y396967D01*
X1740302Y396737D01*
X1740147Y396392D01*
Y396008D01*
X1740043Y395778D01*
X1739785Y395587D01*
X1739423Y395510D01*
X1739062Y395625D01*
X1738803Y395893D01*
X1738700Y396200D01*
X1738803Y396507D01*
X1739062Y396775D01*
X1739423Y396890D01*
X1739785Y396813D01*
X1740043Y396622D01*
X1740147Y396392D01*
Y396008D01*
X1740302Y395663D01*
X1740612Y395433D01*
X1740973Y395357D01*
X1741335Y395433D01*
X1741593Y395625D01*
X1741748Y395932D01*
X1741800Y396200D01*
G01X1740508Y398572D02*
X1740147Y398840D01*
X1739940Y399070D01*
X1739837Y399377D01*
X1739940Y399645D01*
X1740147Y399837D01*
X1740457Y399990D01*
X1740818Y400028D01*
X1741128Y399990D01*
X1741438Y399837D01*
X1741697Y399607D01*
X1741800Y399338D01*
X1741697Y399032D01*
X1741387Y398763D01*
X1740922Y398610D01*
X1740405Y398572D01*
X1739733Y398648D01*
X1739372Y398763D01*
X1739010Y398955D01*
X1738752Y399223D01*
X1738700Y399492D01*
X1738803Y399760D01*
X1739062Y399952D01*
G01X1736662Y388619D02*
X1734709D01*
G01X1736662Y390572D02*
Y388619D01*
G01X1727346Y384248D02*
Y378048D01*
G01X1732146Y384248D02*
X1735346D01*
G01X1732146Y378048D02*
Y384248D01*
G01X1735346Y378048D02*
X1732146D01*
G01X1735346Y384248D02*
Y378048D01*
G01X1743346D02*
X1740146D01*
G01Y384248D02*
X1743346D01*
G01X1740146Y378048D02*
Y384248D01*
G01X1739346Y378048D02*
X1736146D01*
G01X1739346Y384248D02*
Y378048D01*
G01X1736146Y384248D02*
X1739346D01*
G01X1736146Y378048D02*
Y384248D01*
G01X1728146D02*
X1731346D01*
G01X1728146Y378048D02*
Y384248D01*
G01X1731346Y378048D02*
X1728146D01*
G01X1731346Y384248D02*
Y378048D01*
G01X1736662Y400431D02*
Y398478D01*
G01X1734709Y400431D02*
X1736662D01*
G01X1731136Y404932D02*
Y408132D01*
G01X1737336Y404932D02*
X1731136D01*
G01X1737336Y408132D02*
Y404932D01*
G01X1731136Y408132D02*
X1737336D01*
G01X1741447Y401941D02*
X1738247D01*
G01Y408141D02*
X1741447D01*
G01X1738247Y401941D02*
Y408141D01*
G01X1726062Y413602D02*
Y407402D01*
G01X1740179Y438502D02*
Y450502D01*
G01X1746179Y438502D02*
X1740179D01*
G01X1730302Y431902D02*
Y443902D01*
G01X1736302Y431902D02*
X1730302D01*
G01X1736302Y443902D02*
Y431902D01*
G01X1740179Y450502D02*
X1746179D01*
G01X1730302Y443902D02*
X1736302D01*
G01X1731480Y445757D02*
Y448957D01*
G01X1737680Y445757D02*
X1731480D01*
G01X1737680Y448957D02*
Y445757D01*
G01X1731480Y448957D02*
X1737680D01*
G01X1740184Y456709D02*
Y459909D01*
G01X1746384Y456709D02*
X1740184D01*
G01Y452709D02*
Y455909D01*
G01X1746384Y452709D02*
X1740184D01*
G01Y455909D02*
X1746384D01*
G01X1737874Y451163D02*
X1726100D01*
G01X1737874Y460925D02*
Y451163D01*
G01X1726100D02*
Y460925D01*
G01X1727436Y469326D02*
X1739436D01*
G01X1727436Y463326D02*
Y469326D01*
G01X1739436Y463326D02*
X1727436D01*
G01X1739436Y469326D02*
Y463326D01*
G01X1725337Y497369D02*
Y467810D01*
G01X1740184Y460709D02*
Y463909D01*
G01X1746384Y460709D02*
X1740184D01*
G01Y463909D02*
X1746384D01*
G01X1740184Y459909D02*
X1746384D01*
G01X1726100Y460925D02*
X1737874D01*
G01X1753996Y483629D02*
Y471425D01*
X1738692D01*
Y483629D01*
X1753996D01*
G01X1727193Y478517D02*
Y490517D01*
G01X1733193Y478517D02*
X1727193D01*
G01X1733193Y490517D02*
Y478517D01*
G01X1738060Y490416D02*
X1744260D01*
G01X1738060Y487216D02*
Y490416D01*
G01X1744260Y487216D02*
X1738060D01*
G01X1737186Y480358D02*
X1733986D01*
G01X1737186Y486558D02*
Y480358D01*
G01X1733986Y486558D02*
X1737186D01*
G01X1733986Y480358D02*
Y486558D01*
G01X1734260Y497216D02*
X1746260D01*
G01X1734260Y491216D02*
Y497216D01*
G01X1746260Y491216D02*
X1734260D01*
G01X1727193Y490517D02*
X1733193D01*
G01X1734608Y1135604D02*
X1731408D01*
G01X1734608Y1141804D02*
Y1135604D01*
G01X1731408D02*
Y1141804D01*
G01X1730608Y1135604D02*
X1727408D01*
G01X1730608Y1141804D02*
Y1135604D01*
G01X1727408D02*
Y1141804D01*
G01X1735408Y1135604D02*
Y1141804D01*
G01X1738608Y1135604D02*
X1735408D01*
G01X1738608Y1141804D02*
Y1135604D01*
G01X1726608Y1141804D02*
Y1135604D01*
G01X1734210Y1152405D02*
Y1149643D01*
G01X1731108Y1155405D02*
X1734210Y1152405D01*
G01Y1158507D02*
X1731108Y1155405D01*
G01X1739017Y1145412D02*
X1735817D01*
G01X1739017Y1151612D02*
Y1145412D01*
G01X1735817Y1151612D02*
X1739017D01*
G01X1735817Y1145412D02*
Y1151612D01*
G01X1731408Y1141804D02*
X1734608D01*
G01X1727408D02*
X1730608D01*
G01X1735408D02*
X1738608D01*
G01X1734210Y1161167D02*
Y1158507D01*
G01X1738993Y1163692D02*
X1735793D01*
G01X1738993Y1169892D02*
Y1163692D01*
G01X1735793Y1169892D02*
X1738993D01*
G01X1735793Y1163692D02*
Y1169892D01*
G01X1733715Y1172720D02*
Y1169520D01*
G01X1727515D02*
Y1172720D01*
G01X1733715Y1169520D02*
X1727515D01*
G01X1726716Y1172720D02*
Y1169520D01*
G01X1733399Y1179813D02*
X1736599D01*
G01X1733399Y1173613D02*
Y1179813D01*
G01X1736599Y1173613D02*
X1733399D01*
G01X1736599Y1179813D02*
Y1173613D01*
G01X1727515Y1172720D02*
X1733715D01*
G01X1729399Y1179813D02*
X1732599D01*
G01X1729399Y1173613D02*
Y1179813D01*
G01X1732599Y1173613D02*
X1729399D01*
G01X1732599Y1179813D02*
Y1173613D01*
G01X1729421Y1186726D02*
X1732621D01*
G01X1729421Y1180526D02*
Y1186726D01*
G01X1732621Y1180526D02*
X1729421D01*
G01X1732621Y1186726D02*
Y1180526D01*
G01X1733389Y1186763D02*
X1736589D01*
G01X1733389Y1180563D02*
Y1186763D01*
G01X1736589Y1180563D02*
X1733389D01*
G01X1736589Y1186763D02*
Y1180563D01*
G01X1727274Y1179765D02*
Y1173565D01*
G01X1727302Y1186730D02*
Y1180530D01*
G01X1731262Y1201918D02*
X1728062D01*
G01X1731262Y1208118D02*
Y1201918D01*
G01X1728062D02*
Y1208118D01*
G01X1735262Y1201918D02*
X1732062D01*
G01X1735262Y1208118D02*
Y1201918D01*
G01X1732062D02*
Y1208118D01*
G01X1739260Y1193894D02*
X1736060D01*
G01X1739260Y1200094D02*
Y1193894D01*
G01X1736060Y1200094D02*
X1739260D01*
G01X1736060Y1193894D02*
Y1200094D01*
G01X1731260Y1193894D02*
X1728060D01*
G01X1731260Y1200094D02*
Y1193894D01*
G01X1728060Y1200094D02*
X1731260D01*
G01X1728060Y1193894D02*
Y1200094D01*
G01X1735260Y1193894D02*
X1732060D01*
G01X1735260Y1200094D02*
Y1193894D01*
G01X1732060Y1200094D02*
X1735260D01*
G01X1732060Y1193894D02*
Y1200094D01*
G01X1739262Y1201918D02*
X1736062D01*
G01X1739262Y1208118D02*
Y1201918D01*
G01X1736062D02*
Y1208118D01*
G01X1727262D02*
Y1201918D01*
G01X1727260Y1200094D02*
Y1193894D01*
G01X1728062Y1208118D02*
X1731262D01*
G01X1732062D02*
X1735262D01*
G01X1736062D02*
X1739262D01*
G01X1733086Y1219035D02*
X1728702Y1223419D01*
G01X1735348Y1221297D02*
X1733086Y1219035D01*
G01X1730964Y1225681D02*
X1735348Y1221297D01*
G01X1729690Y1215639D02*
X1727428Y1213377D01*
G01X1725306Y1220023D02*
X1729690Y1215639D01*
G01X1732519Y1218468D02*
X1730257Y1216206D01*
G01X1728135Y1222852D02*
X1732519Y1218468D01*
G01X1725873Y1220590D02*
X1728135Y1222852D01*
G01X1730257Y1216206D02*
X1725873Y1220590D01*
G01X1728702Y1223419D02*
X1730964Y1225681D01*
G01X1738176Y1224125D02*
X1735914Y1221863D01*
G01X1733792Y1228509D02*
X1738176Y1224125D01*
G01X1731530Y1226247D02*
X1733792Y1228509D01*
G01X1735914Y1221863D02*
X1731530Y1226247D01*
G01X1728650Y1227075D02*
X1726388Y1224813D01*
G01X1732398Y1232974D02*
G03X1755708Y1263386I-8187J30414D01*
G01X1735984Y1436969D02*
Y1677520D01*
G01X1745929Y1457499D02*
X1738429D01*
Y1459739D01*
X1738804Y1460486D01*
X1739679Y1461046D01*
X1740679Y1461233D01*
X1741679Y1461046D01*
X1742429Y1460579D01*
X1742804Y1459739D01*
Y1457499D01*
G01X1745929Y1464999D02*
X1738429D01*
Y1467333D01*
X1738804Y1468079D01*
X1739304Y1468546D01*
X1740304Y1468733D01*
X1741304Y1468546D01*
X1741929Y1467986D01*
X1742304Y1467333D01*
Y1464999D01*
G01Y1467333D02*
X1745929Y1468733D01*
G01Y1476233D02*
Y1472499D01*
X1738429D01*
Y1476233D01*
G01X1742054Y1474739D02*
Y1472499D01*
G01X1744929Y1479906D02*
X1745554Y1480653D01*
X1745929Y1481493D01*
Y1482239D01*
X1745554Y1482986D01*
X1744929Y1483546D01*
X1744054Y1483826D01*
X1743179Y1483639D01*
X1742429Y1483173D01*
X1741929Y1482333D01*
X1741679Y1481213D01*
X1741179Y1480559D01*
X1740304Y1480279D01*
X1739429Y1480466D01*
X1738804Y1480933D01*
X1738429Y1481586D01*
Y1482239D01*
X1738679Y1482893D01*
X1739304Y1483453D01*
G01X1744929Y1487406D02*
X1745554Y1488153D01*
X1745929Y1488993D01*
Y1489739D01*
X1745554Y1490486D01*
X1744929Y1491046D01*
X1744054Y1491326D01*
X1743179Y1491139D01*
X1742429Y1490673D01*
X1741929Y1489833D01*
X1741679Y1488713D01*
X1741179Y1488059D01*
X1740304Y1487779D01*
X1739429Y1487966D01*
X1738804Y1488433D01*
X1738429Y1489086D01*
Y1489739D01*
X1738679Y1490393D01*
X1739304Y1490953D01*
G01X1743429Y1495653D02*
Y1498079D01*
G01X1745929Y1502593D02*
X1738429D01*
Y1506139D01*
G01X1742054Y1504833D02*
Y1502593D01*
G01X1738429Y1510746D02*
Y1512986D01*
G01Y1511866D02*
X1745929D01*
G01Y1510746D02*
Y1512986D01*
G01X1738429Y1519366D02*
X1745929D01*
G01X1738429Y1517219D02*
Y1521513D01*
G01X1763045Y1715189D02*
X1728469Y1702076D01*
G01D02*
Y1728302D01*
G01D02*
X1763045Y1715189D01*
G01Y1744208D02*
X1728469Y1731095D01*
G01D02*
Y1757321D01*
G01D02*
X1763045Y1744208D01*
G01X1763038Y1773377D02*
X1728462Y1760264D01*
G01D02*
Y1786490D01*
G01D02*
X1763038Y1773377D01*
G01X1741791Y57756D02*
Y104521D01*
G01X1741495Y58150D02*
Y104521D01*
G01X1753327Y86929D02*
X1750127D01*
G01X1753327Y93129D02*
Y86929D01*
G01X1750127Y93129D02*
X1753327D01*
G01X1750127Y86929D02*
Y93129D01*
G01X1757327Y86929D02*
X1754127D01*
G01X1757327Y93129D02*
Y86929D01*
G01X1754127Y93129D02*
X1757327D01*
G01X1754127Y86929D02*
Y93129D01*
G01X1747323Y97026D02*
Y103226D01*
G01X1750523Y97026D02*
X1747323D01*
G01X1750523Y103226D02*
Y97026D01*
G01X1749327Y86929D02*
X1746127D01*
G01X1749327Y93129D02*
Y86929D01*
G01X1746127Y93129D02*
X1749327D01*
G01X1746127Y86929D02*
Y93129D01*
G01X1753406Y96673D02*
Y102873D01*
G01X1756606Y96673D02*
X1753406D01*
G01X1756606Y102873D02*
Y96673D01*
G01X1741791Y111507D02*
Y107060D01*
G01X1741495Y111507D02*
Y107060D01*
G01Y118680D02*
Y114087D01*
G01X1741791Y118680D02*
Y114087D01*
G01X1747323Y103226D02*
X1750523D01*
G01X1753406Y102873D02*
X1756606D01*
G01X1741495Y132859D02*
Y128325D01*
G01X1741791Y132859D02*
Y128325D01*
G01Y125844D02*
Y121329D01*
G01X1741495Y125844D02*
Y121329D01*
G01Y152756D02*
Y135430D01*
G01X1741791Y153150D02*
Y135430D01*
G01X1748691Y164436D02*
Y195440D01*
G01X1757657Y171473D02*
X1754457D01*
G01Y177673D02*
X1757657D01*
G01X1754457Y171473D02*
Y177673D01*
G01X1753657Y171473D02*
X1750457D01*
G01X1753657Y177673D02*
Y171473D01*
G01X1750457Y177673D02*
X1753657D01*
G01X1750457Y171473D02*
Y177673D01*
G01X1754480Y170297D02*
X1760680D01*
G01X1754480Y167097D02*
Y170297D01*
G01X1760680Y167097D02*
X1754480D01*
G01X1757884Y182730D02*
X1754684D01*
G01Y188930D02*
X1757884D01*
G01X1754684Y182730D02*
Y188930D01*
G01X1754675Y193541D02*
X1760875D01*
G01X1754675Y190341D02*
Y193541D01*
G01X1760875Y190341D02*
X1754675D01*
G01X1746004Y213035D02*
Y225035D01*
G01X1752004Y213035D02*
X1746004D01*
G01X1752004Y225035D02*
Y213035D01*
G01X1743942Y233011D02*
Y203452D01*
G01X1746004Y225035D02*
X1752004D01*
G01X1752844Y226621D02*
Y232621D01*
G01X1764844Y226621D02*
X1752844D01*
G01X1756823Y215082D02*
X1753623D01*
G01X1756823Y221282D02*
Y215082D01*
G01X1753623Y221282D02*
X1756823D01*
G01X1753623Y215082D02*
Y221282D01*
G01X1756644Y225921D02*
X1762844D01*
G01X1756644Y222721D02*
Y225921D01*
G01X1762844Y222721D02*
X1756644D01*
G01X1752844Y232621D02*
X1764844D01*
G01X1745287Y250325D02*
Y234813D01*
G01D02*
X1776379D01*
G01X1743711Y292303D02*
Y262744D01*
G01X1745466Y251936D02*
Y255036D01*
X1746386D01*
X1746693Y254881D01*
X1746923Y254519D01*
X1747000Y254106D01*
X1746923Y253693D01*
X1746731Y253383D01*
X1746386Y253228D01*
X1745466D01*
G01X1748490Y251936D02*
Y255036D01*
X1749256D01*
X1749563Y254881D01*
X1749793Y254674D01*
X1749985Y254364D01*
X1750138Y254003D01*
X1750176Y253486D01*
X1750138Y252969D01*
X1749985Y252608D01*
X1749793Y252298D01*
X1749563Y252091D01*
X1749256Y251936D01*
X1748490D01*
G01X1752893D02*
Y255036D01*
X1751475Y252814D01*
X1753391D01*
G01X1755533Y255036D02*
X1755226Y254933D01*
X1754996Y254674D01*
X1754843Y254364D01*
X1754728Y253951D01*
X1754690Y253486D01*
X1754728Y253021D01*
X1754843Y252608D01*
X1754996Y252298D01*
X1755226Y252039D01*
X1755533Y251936D01*
X1755840Y252039D01*
X1756070Y252298D01*
X1756223Y252608D01*
X1756338Y253021D01*
X1756376Y253486D01*
X1756338Y253951D01*
X1756223Y254364D01*
X1756070Y254674D01*
X1755840Y254933D01*
X1755533Y255036D01*
G01X1776379Y250325D02*
X1745287D01*
G01X1753512Y258010D02*
Y264210D01*
G01X1756712Y258010D02*
X1753512D01*
G01X1756712Y264210D02*
Y258010D01*
G01X1745582Y271655D02*
Y283655D01*
G01X1751582Y271655D02*
X1745582D01*
G01X1751582Y283655D02*
Y271655D01*
G01X1753512Y264210D02*
X1756712D01*
G01X1754471Y267653D02*
Y279427D01*
G01X1764233Y267653D02*
X1754471D01*
G01X1745582Y283655D02*
X1751582D01*
G01X1755765Y283383D02*
X1752565D01*
G01X1755765Y289583D02*
Y283383D01*
G01X1752565Y289583D02*
X1755765D01*
G01X1752565Y283383D02*
Y289583D01*
G01X1759765Y283383D02*
X1756565D01*
G01Y289583D02*
X1759765D01*
G01X1756565Y283383D02*
Y289583D01*
G01X1754471Y279427D02*
X1764233D01*
G01X1749263Y351915D02*
Y355015D01*
G01X1750873D02*
Y351915D01*
G01Y353465D02*
X1749263D01*
G01X1753091Y351915D02*
X1753168Y352587D01*
X1753283Y353155D01*
X1753436Y353672D01*
X1753628Y354240D01*
X1753935Y355015D01*
X1752401D01*
G01X1756268D02*
X1755961Y354912D01*
X1755731Y354653D01*
X1755578Y354343D01*
X1755463Y353930D01*
X1755425Y353465D01*
X1755463Y353000D01*
X1755578Y352587D01*
X1755731Y352277D01*
X1755961Y352018D01*
X1756268Y351915D01*
X1756575Y352018D01*
X1756805Y352277D01*
X1756958Y352587D01*
X1757073Y353000D01*
X1757111Y353465D01*
X1757073Y353930D01*
X1756958Y354343D01*
X1756805Y354653D01*
X1756575Y354912D01*
X1756268Y355015D01*
G01X1750897Y371954D02*
Y378154D01*
G01X1754097Y371954D02*
X1750897D01*
G01X1754097Y378154D02*
Y371954D01*
G01X1750097Y372155D02*
X1746897D01*
G01X1750097Y378355D02*
Y372155D01*
G01X1746897D02*
Y378355D01*
G01X1758097Y378154D02*
Y371954D01*
X1754897D01*
Y378154D01*
X1758097D01*
G01X1746124Y377279D02*
Y371079D01*
X1742924D01*
Y377279D01*
X1746124D01*
G01X1750897Y378154D02*
X1754097D01*
G01X1746897Y378355D02*
X1750097D01*
G01X1743346Y384248D02*
Y378048D01*
G01X1747253Y387041D02*
X1744153D01*
Y387961D01*
X1744308Y388268D01*
X1744670Y388498D01*
X1745083Y388575D01*
X1745496Y388498D01*
X1745806Y388306D01*
X1745961Y387961D01*
Y387041D01*
G01X1744153Y390065D02*
X1746375D01*
X1746840Y390218D01*
X1747150Y390525D01*
X1747253Y390908D01*
X1747150Y391291D01*
X1746840Y391598D01*
X1746375Y391751D01*
X1744153D01*
G01X1744670Y393280D02*
X1744360Y393510D01*
X1744205Y393778D01*
X1744153Y394085D01*
X1744256Y394468D01*
X1744515Y394736D01*
X1744825Y394813D01*
X1745135Y394775D01*
X1745393Y394621D01*
X1745910Y393855D01*
X1746271Y393510D01*
X1746788Y393280D01*
X1747253Y393203D01*
Y394813D01*
G01X1746891Y396456D02*
X1747150Y396725D01*
X1747253Y397031D01*
X1747150Y397338D01*
X1746840Y397606D01*
X1746375Y397798D01*
X1745910Y397875D01*
X1745341D01*
X1744876Y397798D01*
X1744463Y397606D01*
X1744256Y397376D01*
X1744153Y397108D01*
X1744256Y396801D01*
X1744463Y396571D01*
X1744773Y396418D01*
X1745186Y396341D01*
X1745548Y396418D01*
X1745910Y396610D01*
X1746116Y396840D01*
X1746168Y397108D01*
X1746065Y397415D01*
X1745806Y397645D01*
X1745341Y397875D01*
G01X1761744Y381986D02*
X1749540D01*
Y397290D01*
X1761744D01*
Y381986D01*
G01X1754527Y405142D02*
Y411142D01*
G01X1766527Y405142D02*
X1754527D01*
G01X1747309Y412052D02*
X1749735D01*
G01X1756574Y400323D02*
Y403523D01*
G01X1762774Y400323D02*
X1756574D01*
G01Y403523D02*
X1762774D01*
G01X1741447Y408141D02*
Y401941D01*
G01X1754527Y411142D02*
X1766527D01*
G01X1742712Y415040D02*
Y429840D01*
G01X1744077Y425971D02*
Y429071D01*
X1744997D01*
X1745304Y428916D01*
X1745534Y428554D01*
X1745611Y428141D01*
X1745534Y427728D01*
X1745342Y427418D01*
X1744997Y427263D01*
X1744077D01*
G01X1747101Y425971D02*
Y429071D01*
X1747867D01*
X1748174Y428916D01*
X1748404Y428709D01*
X1748596Y428399D01*
X1748749Y428038D01*
X1748787Y427521D01*
X1748749Y427004D01*
X1748596Y426643D01*
X1748404Y426333D01*
X1748174Y426126D01*
X1747867Y425971D01*
X1747101D01*
G01X1751044D02*
Y429071D01*
X1750584Y428451D01*
G01Y425971D02*
X1751504D01*
G01X1753492Y426333D02*
X1753761Y426074D01*
X1754067Y425971D01*
X1754374Y426074D01*
X1754642Y426384D01*
X1754834Y426849D01*
X1754911Y427314D01*
Y427883D01*
X1754834Y428348D01*
X1754642Y428761D01*
X1754412Y428968D01*
X1754144Y429071D01*
X1753837Y428968D01*
X1753607Y428761D01*
X1753454Y428451D01*
X1753377Y428038D01*
X1753454Y427676D01*
X1753646Y427314D01*
X1753876Y427108D01*
X1754144Y427056D01*
X1754451Y427159D01*
X1754681Y427418D01*
X1754911Y427883D01*
G01X1744944Y413204D02*
Y424700D01*
G01X1774503Y413204D02*
X1744944D01*
G01Y424700D02*
X1774503D01*
G01X1748179Y438502D02*
Y450502D01*
G01X1754179Y438502D02*
X1748179D01*
G01X1754179Y450502D02*
Y438502D01*
G01X1746179Y450502D02*
Y438502D01*
G01X1754334Y433685D02*
Y436111D01*
G01X1767583Y429160D02*
X1756087D01*
G01D02*
Y458719D01*
G01X1748179Y450502D02*
X1754179D01*
G01X1746384Y459909D02*
Y456709D01*
G01Y455909D02*
Y452709D01*
G01X1761435Y462360D02*
Y460120D01*
G01X1763060Y461333D02*
X1759810D01*
G01X1756087Y458719D02*
X1767583D01*
G01X1746384Y463909D02*
Y460709D01*
G01X1742893Y464850D02*
Y467950D01*
X1743813D01*
X1744120Y467795D01*
X1744350Y467433D01*
X1744427Y467020D01*
X1744350Y466607D01*
X1744158Y466297D01*
X1743813Y466142D01*
X1742893D01*
G01X1745917Y467950D02*
Y465728D01*
X1746070Y465263D01*
X1746377Y464953D01*
X1746760Y464850D01*
X1747143Y464953D01*
X1747450Y465263D01*
X1747603Y465728D01*
Y467950D01*
G01X1749017Y465315D02*
X1749247Y465057D01*
X1749515Y464902D01*
X1749860Y464850D01*
X1750205Y464953D01*
X1750473Y465160D01*
X1750665Y465522D01*
X1750703Y465935D01*
X1750627Y466348D01*
X1750435Y466607D01*
X1750167Y466813D01*
X1749898Y466865D01*
X1749630Y466813D01*
X1749285Y466607D01*
X1749400Y467950D01*
X1750435D01*
G01X1752117Y465470D02*
X1752347Y465108D01*
X1752653Y464902D01*
X1752998Y464850D01*
X1753305Y464902D01*
X1753612Y465160D01*
X1753803Y465470D01*
X1753842Y465780D01*
X1753765Y466142D01*
X1753497Y466400D01*
X1753228Y466503D01*
X1752883D01*
G01X1753228D02*
X1753458Y466658D01*
X1753650Y466917D01*
X1753727Y467227D01*
X1753650Y467537D01*
X1753458Y467795D01*
X1753113Y467950D01*
X1752768Y467898D01*
X1752423Y467692D01*
G01X1744260Y490416D02*
Y487216D01*
G01X1746260Y497216D02*
Y491216D01*
G01X1754707Y877599D02*
X1748507D01*
Y880799D01*
X1754707D01*
Y877599D01*
G01X1755523Y873808D02*
X1758623D01*
X1758003Y874268D01*
G01X1755523D02*
Y873348D01*
G01X1756815Y871436D02*
X1757176Y871168D01*
X1757383Y870938D01*
X1757486Y870631D01*
X1757383Y870363D01*
X1757176Y870171D01*
X1756866Y870018D01*
X1756505Y869980D01*
X1756195Y870018D01*
X1755885Y870171D01*
X1755626Y870401D01*
X1755523Y870670D01*
X1755626Y870976D01*
X1755936Y871245D01*
X1756401Y871398D01*
X1756918Y871436D01*
X1757590Y871360D01*
X1757951Y871245D01*
X1758313Y871053D01*
X1758571Y870785D01*
X1758623Y870516D01*
X1758520Y870248D01*
X1758261Y870056D01*
G01X1748508Y886249D02*
X1754708D01*
Y883049D01*
X1748508D01*
Y886249D01*
G01X1754762Y895679D02*
X1748562D01*
Y898879D01*
X1754762D01*
Y895679D01*
G01X1756900Y892447D02*
X1760900D01*
G01X1743967Y901214D02*
Y911414D01*
X1748567D01*
Y901214D01*
X1743967D01*
G01X1749300Y903300D02*
Y909500D01*
X1752500D01*
Y903300D01*
X1749300D01*
G01X1747742Y917051D02*
X1753942D01*
Y913851D01*
X1747742D01*
Y917051D01*
G01X1758800Y933500D02*
X1752600D01*
Y936700D01*
X1758800D01*
Y933500D01*
G01X1752600Y932700D02*
X1758800D01*
Y929500D01*
X1752600D01*
Y932700D01*
G01X1761574Y1007450D02*
Y997250D01*
X1756974D01*
Y1007450D01*
X1761574D01*
G01X1757897Y1020152D02*
Y1013952D01*
X1754697D01*
Y1020152D01*
X1757897D01*
G01X1747821Y1151129D02*
X1750043D01*
X1750508Y1151282D01*
X1750818Y1151589D01*
X1750921Y1151972D01*
X1750818Y1152355D01*
X1750508Y1152662D01*
X1750043Y1152815D01*
X1747821D01*
G01X1750301Y1154229D02*
X1750663Y1154459D01*
X1750869Y1154765D01*
X1750921Y1155110D01*
X1750869Y1155417D01*
X1750611Y1155724D01*
X1750301Y1155915D01*
X1749991Y1155954D01*
X1749629Y1155877D01*
X1749371Y1155609D01*
X1749268Y1155340D01*
Y1154995D01*
G01Y1155340D02*
X1749113Y1155570D01*
X1748854Y1155762D01*
X1748544Y1155839D01*
X1748234Y1155762D01*
X1747976Y1155570D01*
X1747821Y1155225D01*
X1747873Y1154880D01*
X1748079Y1154535D01*
G01X1750921Y1158172D02*
X1747821D01*
X1748441Y1157712D01*
G01X1750921D02*
Y1158632D01*
G01X1749629Y1160544D02*
X1749268Y1160812D01*
X1749061Y1161042D01*
X1748958Y1161349D01*
X1749061Y1161617D01*
X1749268Y1161809D01*
X1749578Y1161962D01*
X1749939Y1162000D01*
X1750249Y1161962D01*
X1750559Y1161809D01*
X1750818Y1161579D01*
X1750921Y1161310D01*
X1750818Y1161004D01*
X1750508Y1160735D01*
X1750043Y1160582D01*
X1749526Y1160544D01*
X1748854Y1160620D01*
X1748493Y1160735D01*
X1748131Y1160927D01*
X1747873Y1161195D01*
X1747821Y1161464D01*
X1747924Y1161732D01*
X1748183Y1161924D01*
G01X1752372Y1230971D02*
Y1234071D01*
G01X1753982D02*
Y1230971D01*
G01Y1232521D02*
X1752372D01*
G01X1756277Y1230971D02*
Y1234071D01*
X1755817Y1233451D01*
G01Y1230971D02*
X1756737D01*
G01X1758534Y1231591D02*
X1758764Y1231229D01*
X1759070Y1231023D01*
X1759415Y1230971D01*
X1759722Y1231023D01*
X1760029Y1231281D01*
X1760220Y1231591D01*
X1760259Y1231901D01*
X1760182Y1232263D01*
X1759914Y1232521D01*
X1759645Y1232624D01*
X1759300D01*
G01X1759645D02*
X1759875Y1232779D01*
X1760067Y1233038D01*
X1760144Y1233348D01*
X1760067Y1233658D01*
X1759875Y1233916D01*
X1759530Y1234071D01*
X1759185Y1234019D01*
X1758840Y1233813D01*
G01X1762937Y1230971D02*
Y1234071D01*
X1761519Y1231849D01*
X1763435D01*
G01X1747795Y1689331D02*
Y1425158D01*
G01X1756477Y1601216D02*
X1776163D01*
G01X1756477Y1608947D02*
Y1601216D01*
G01X1762320Y1614790D02*
X1756477Y1608947D01*
G01X1751621Y1623179D02*
X1754821D01*
G01X1751621Y1616979D02*
Y1623179D01*
G01X1754821Y1616979D02*
X1751621D01*
G01X1754821Y1623179D02*
Y1616979D01*
G01X1756477Y1620633D02*
X1762320Y1614790D01*
G01X1756477Y1628364D02*
Y1620633D01*
G01X1758022Y1633204D02*
X1754822D01*
G01Y1639404D02*
X1758022D01*
G01X1754822Y1633204D02*
Y1639404D01*
G01X1776163Y1628364D02*
X1756477D01*
G01X1768382Y66981D02*
Y70181D01*
G01X1774582Y66981D02*
X1768382D01*
G01X1757716Y78540D02*
Y81740D01*
G01X1763916Y78540D02*
X1757716D01*
G01X1763916Y81740D02*
Y78540D01*
G01X1757716Y81740D02*
X1763916D01*
G01X1757716Y74540D02*
Y77740D01*
G01X1763916Y74540D02*
X1757716D01*
G01X1763916Y77740D02*
Y74540D01*
G01X1757716Y77740D02*
X1763916D01*
G01X1757716Y82540D02*
Y85740D01*
G01X1763916Y82540D02*
X1757716D01*
G01X1763916Y85740D02*
Y82540D01*
G01X1768382Y70181D02*
X1774582D01*
G01X1768427Y70987D02*
Y74187D01*
G01X1774627Y70987D02*
X1768427D01*
G01Y74187D02*
X1774627D01*
G01X1768427Y74987D02*
Y78187D01*
G01X1774627Y74987D02*
X1768427D01*
G01Y78187D02*
X1774627D01*
G01X1768382Y82181D02*
X1774582D01*
G01X1768382Y78981D02*
Y82181D01*
G01X1774582Y78981D02*
X1768382D01*
G01X1757716Y85740D02*
X1763916D01*
G01X1761336Y86929D02*
X1758136D01*
G01X1761336Y93129D02*
Y86929D01*
G01X1758136Y93129D02*
X1761336D01*
G01X1758136Y86929D02*
Y93129D01*
G01X1762910Y95950D02*
Y102150D01*
G01X1766110Y95950D02*
X1762910D01*
G01X1766110Y102150D02*
Y95950D01*
G01X1757406Y96673D02*
Y102873D01*
G01X1760606Y96673D02*
X1757406D01*
G01X1760606Y102873D02*
Y96673D01*
G01X1767574Y95913D02*
Y111267D01*
G01X1780055Y95913D02*
X1767574D01*
G01X1762910Y102150D02*
X1766110D01*
G01X1762910Y109762D02*
X1766110D01*
G01X1762910Y103562D02*
Y109762D01*
G01X1766110Y103562D02*
X1762910D01*
G01X1766110Y109762D02*
Y103562D01*
G01X1757406Y102873D02*
X1760606D01*
G01X1767574Y111267D02*
X1780252D01*
G01X1762457Y174900D02*
Y172678D01*
X1762610Y172213D01*
X1762917Y171903D01*
X1763300Y171800D01*
X1763683Y171903D01*
X1763990Y172213D01*
X1764143Y172678D01*
Y174900D01*
G01X1766323Y171800D02*
X1766400Y172472D01*
X1766515Y173040D01*
X1766668Y173557D01*
X1766860Y174125D01*
X1767167Y174900D01*
X1765633D01*
G01X1769500Y171800D02*
X1769768Y171852D01*
X1770075Y172007D01*
X1770267Y172265D01*
X1770343Y172627D01*
X1770267Y172988D01*
X1770037Y173298D01*
X1769692Y173453D01*
X1769308D01*
X1769078Y173557D01*
X1768887Y173815D01*
X1768810Y174177D01*
X1768925Y174538D01*
X1769193Y174797D01*
X1769500Y174900D01*
X1769807Y174797D01*
X1770075Y174538D01*
X1770190Y174177D01*
X1770113Y173815D01*
X1769922Y173557D01*
X1769692Y173453D01*
X1769308D01*
X1768963Y173298D01*
X1768733Y172988D01*
X1768657Y172627D01*
X1768733Y172265D01*
X1768925Y172007D01*
X1769232Y171852D01*
X1769500Y171800D01*
G01X1774197Y176944D02*
X1772244D01*
G01X1762385D02*
Y178897D01*
G01X1764338Y176944D02*
X1762385D01*
G01X1757657Y177673D02*
Y171473D01*
G01X1770189Y170313D02*
X1776389D01*
G01X1770189Y167113D02*
Y170313D01*
G01X1776389Y167113D02*
X1770189D01*
G01X1760680Y170297D02*
Y167097D01*
G01X1772244Y188756D02*
X1774197D01*
G01X1762385D02*
X1764338D01*
G01X1762385Y186803D02*
Y188756D01*
G01X1757884Y188930D02*
Y182730D01*
G01X1760875Y193541D02*
Y190341D01*
G01X1771244Y195020D02*
Y198220D01*
G01X1777444Y195020D02*
X1771244D01*
G01Y198220D02*
X1777444D01*
G01X1760157Y201329D02*
Y204429D01*
X1761077D01*
X1761384Y204274D01*
X1761614Y203912D01*
X1761691Y203499D01*
X1761614Y203086D01*
X1761422Y202776D01*
X1761077Y202621D01*
X1760157D01*
G01X1763181Y204429D02*
Y202207D01*
X1763334Y201742D01*
X1763641Y201432D01*
X1764024Y201329D01*
X1764407Y201432D01*
X1764714Y201742D01*
X1764867Y202207D01*
Y204429D01*
G01X1767584Y201329D02*
Y204429D01*
X1766166Y202207D01*
X1768082D01*
G01X1769381Y201794D02*
X1769611Y201536D01*
X1769879Y201381D01*
X1770224Y201329D01*
X1770569Y201432D01*
X1770837Y201639D01*
X1771029Y202001D01*
X1771067Y202414D01*
X1770991Y202827D01*
X1770799Y203086D01*
X1770531Y203292D01*
X1770262Y203344D01*
X1769994Y203292D01*
X1769649Y203086D01*
X1769764Y204429D01*
X1770799D01*
G01X1775160Y220252D02*
Y208048D01*
X1759856D01*
Y220252D01*
X1775160D01*
G01X1764844Y232621D02*
Y226621D01*
G01X1762844Y225921D02*
Y222721D01*
G01X1761512Y258010D02*
Y264210D01*
G01X1764712Y258010D02*
X1761512D01*
G01X1764712Y264210D02*
Y258010D01*
G01X1760712D02*
X1757512D01*
G01X1760712Y264210D02*
Y258010D01*
G01X1757512D02*
Y264210D01*
G01X1771423Y264635D02*
X1786935D01*
G01X1771423Y295727D02*
Y264635D01*
G01X1761512Y264210D02*
X1764712D01*
G01X1769791Y273701D02*
X1766591D01*
G01X1769791Y279901D02*
Y273701D01*
G01X1766591D02*
Y279901D01*
G01X1757512Y264210D02*
X1760712D01*
G01X1764233Y279427D02*
Y267653D01*
G01X1766591Y279901D02*
X1769791D01*
G01X1759765Y289583D02*
Y283383D01*
G01X1760565D02*
Y289583D01*
X1763765D01*
Y283383D01*
X1760565D01*
G01X1768400Y282633D02*
X1765300D01*
Y283553D01*
X1765455Y283860D01*
X1765817Y284090D01*
X1766230Y284167D01*
X1766643Y284090D01*
X1766953Y283898D01*
X1767108Y283553D01*
Y282633D01*
G01X1765300Y285657D02*
X1767522D01*
X1767987Y285810D01*
X1768297Y286117D01*
X1768400Y286500D01*
X1768297Y286883D01*
X1767987Y287190D01*
X1767522Y287343D01*
X1765300D01*
G01X1768400Y289600D02*
X1765300D01*
X1765920Y289140D01*
G01X1768400D02*
Y290060D01*
G01Y292700D02*
X1765300D01*
X1765920Y292240D01*
G01X1768400D02*
Y293160D01*
G01Y295800D02*
X1768348Y296068D01*
X1768193Y296375D01*
X1767935Y296567D01*
X1767573Y296643D01*
X1767212Y296567D01*
X1766902Y296337D01*
X1766747Y295992D01*
Y295608D01*
X1766643Y295378D01*
X1766385Y295187D01*
X1766023Y295110D01*
X1765662Y295225D01*
X1765403Y295493D01*
X1765300Y295800D01*
X1765403Y296107D01*
X1765662Y296375D01*
X1766023Y296490D01*
X1766385Y296413D01*
X1766643Y296222D01*
X1766747Y295992D01*
Y295608D01*
X1766902Y295263D01*
X1767212Y295033D01*
X1767573Y294957D01*
X1767935Y295033D01*
X1768193Y295225D01*
X1768348Y295532D01*
X1768400Y295800D01*
G01X1786935Y295727D02*
X1771423D01*
G01X1763897Y371956D02*
Y378156D01*
G01X1767097Y371956D02*
X1763897D01*
G01X1767097Y378156D02*
Y371956D01*
G01X1758897Y371954D02*
Y378154D01*
G01X1762097Y371954D02*
X1758897D01*
G01X1762097Y378154D02*
Y371954D01*
G01X1771097Y371956D02*
X1767897D01*
G01X1771097Y378156D02*
Y371956D01*
G01X1767897D02*
Y378156D01*
G01X1768113Y389302D02*
Y401302D01*
G01X1774113Y389302D02*
X1768113D01*
G01X1763897Y378156D02*
X1767097D01*
G01X1758897Y378154D02*
X1762097D01*
G01X1767413Y391302D02*
X1764213D01*
G01X1767413Y397502D02*
Y391302D01*
G01X1764213D02*
Y397502D01*
G01X1767897Y378156D02*
X1771097D01*
G01X1766527Y411142D02*
Y405142D01*
G01X1768113Y401302D02*
X1774113D01*
G01X1772239Y411000D02*
X1769999D01*
G01X1771212Y409375D02*
Y412625D01*
G01X1762774Y403523D02*
Y400323D01*
G01X1764213Y397502D02*
X1767413D01*
G01X1772000Y430183D02*
X1768900D01*
Y431103D01*
X1769055Y431410D01*
X1769417Y431640D01*
X1769830Y431717D01*
X1770243Y431640D01*
X1770553Y431448D01*
X1770708Y431103D01*
Y430183D01*
G01X1772000Y433207D02*
X1768900D01*
Y433973D01*
X1769055Y434280D01*
X1769262Y434510D01*
X1769572Y434702D01*
X1769933Y434855D01*
X1770450Y434893D01*
X1770967Y434855D01*
X1771328Y434702D01*
X1771638Y434510D01*
X1771845Y434280D01*
X1772000Y433973D01*
Y433207D01*
G01X1771638Y436498D02*
X1771897Y436767D01*
X1772000Y437073D01*
X1771897Y437380D01*
X1771587Y437648D01*
X1771122Y437840D01*
X1770657Y437917D01*
X1770088D01*
X1769623Y437840D01*
X1769210Y437648D01*
X1769003Y437418D01*
X1768900Y437150D01*
X1769003Y436843D01*
X1769210Y436613D01*
X1769520Y436460D01*
X1769933Y436383D01*
X1770295Y436460D01*
X1770657Y436652D01*
X1770863Y436882D01*
X1770915Y437150D01*
X1770812Y437457D01*
X1770553Y437687D01*
X1770088Y437917D01*
G01X1771638Y439598D02*
X1771897Y439867D01*
X1772000Y440173D01*
X1771897Y440480D01*
X1771587Y440748D01*
X1771122Y440940D01*
X1770657Y441017D01*
X1770088D01*
X1769623Y440940D01*
X1769210Y440748D01*
X1769003Y440518D01*
X1768900Y440250D01*
X1769003Y439943D01*
X1769210Y439713D01*
X1769520Y439560D01*
X1769933Y439483D01*
X1770295Y439560D01*
X1770657Y439752D01*
X1770863Y439982D01*
X1770915Y440250D01*
X1770812Y440557D01*
X1770553Y440787D01*
X1770088Y441017D01*
G01X1767583Y458719D02*
Y429160D01*
G01X1774025Y443937D02*
X1770825D01*
G01Y450137D02*
X1774025D01*
G01X1770825Y443937D02*
Y450137D01*
G01X1757828Y464809D02*
Y468009D01*
G01X1764028Y464809D02*
X1757828D01*
G01X1764028Y468009D02*
Y464809D01*
G01X1757828Y468009D02*
X1764028D01*
G01Y471982D02*
Y468782D01*
G01X1757828Y471982D02*
X1764028D01*
G01X1757828Y468782D02*
Y471982D01*
G01X1764028Y468782D02*
X1757828D01*
G01X1769461Y473160D02*
X1775661D01*
G01X1769461Y469960D02*
Y473160D01*
G01X1775661Y469960D02*
X1769461D01*
G01Y465960D02*
Y469160D01*
G01X1775661Y465960D02*
X1769461D01*
G01Y469160D02*
X1775661D01*
G01X1757828Y472782D02*
Y475982D01*
G01X1764028Y472782D02*
X1757828D01*
G01X1764028Y475982D02*
Y472782D01*
G01X1769461Y473960D02*
Y477160D01*
G01X1775661Y473960D02*
X1769461D01*
G01X1757828Y485782D02*
Y488982D01*
G01X1764028Y485782D02*
X1757828D01*
G01X1764028Y488982D02*
Y485782D01*
G01X1757828Y488982D02*
X1764028D01*
G01X1757828Y480782D02*
Y483982D01*
G01X1764028Y480782D02*
X1757828D01*
G01X1764028Y483982D02*
Y480782D01*
G01X1757828Y483982D02*
X1764028D01*
G01X1757828Y475982D02*
X1764028D01*
G01X1769461Y481160D02*
X1775661D01*
G01X1769461Y477960D02*
Y481160D01*
G01X1775661Y477960D02*
X1769461D01*
G01Y477160D02*
X1775661D01*
G01X1757828Y479982D02*
X1764028D01*
Y476782D01*
X1757828D01*
Y479982D01*
G01X1762807Y786031D02*
Y789131D01*
G01X1764417D02*
Y786031D01*
G01Y787581D02*
X1762807D01*
G01X1765869Y786496D02*
X1766099Y786238D01*
X1766367Y786083D01*
X1766712Y786031D01*
X1767057Y786134D01*
X1767325Y786341D01*
X1767517Y786703D01*
X1767555Y787116D01*
X1767479Y787529D01*
X1767287Y787788D01*
X1767019Y787994D01*
X1766750Y788046D01*
X1766482Y787994D01*
X1766137Y787788D01*
X1766252Y789131D01*
X1767287D01*
G01X1769084Y787323D02*
X1769352Y787684D01*
X1769582Y787891D01*
X1769889Y787994D01*
X1770157Y787891D01*
X1770349Y787684D01*
X1770502Y787374D01*
X1770540Y787013D01*
X1770502Y786703D01*
X1770349Y786393D01*
X1770119Y786134D01*
X1769850Y786031D01*
X1769544Y786134D01*
X1769275Y786444D01*
X1769122Y786909D01*
X1769084Y787426D01*
X1769160Y788098D01*
X1769275Y788459D01*
X1769467Y788821D01*
X1769735Y789079D01*
X1770004Y789131D01*
X1770272Y789028D01*
X1770464Y788769D01*
G01X1765607Y825983D02*
Y823742D01*
G01Y819283D02*
Y821361D01*
G01X1760507Y822483D02*
X1764637D01*
G01X1760507Y822783D02*
X1764637D01*
G01X1759407Y825983D02*
Y823841D01*
G01Y819283D02*
Y821182D01*
G01Y825983D02*
X1765607D01*
G01Y819283D02*
X1759407D01*
G01X1762324Y870107D02*
Y873207D01*
X1761864Y872587D01*
G01Y870107D02*
X1762784D01*
G01X1765347D02*
X1765424Y870779D01*
X1765539Y871347D01*
X1765692Y871864D01*
X1765884Y872432D01*
X1766191Y873207D01*
X1764657D01*
G01X1763283Y879500D02*
Y877683D01*
G01D02*
X1765100D01*
G01X1772142Y875600D02*
Y871600D01*
G01X1761000Y882605D02*
X1759000D01*
G01X1760203Y914977D02*
X1760471Y915338D01*
X1760701Y915545D01*
X1761008Y915648D01*
X1761276Y915545D01*
X1761468Y915338D01*
X1761621Y915028D01*
X1761659Y914667D01*
X1761621Y914357D01*
X1761468Y914047D01*
X1761238Y913788D01*
X1760969Y913685D01*
X1760663Y913788D01*
X1760394Y914098D01*
X1760241Y914563D01*
X1760203Y915080D01*
X1760279Y915752D01*
X1760394Y916113D01*
X1760586Y916475D01*
X1760854Y916733D01*
X1761123Y916785D01*
X1761391Y916682D01*
X1761583Y916423D01*
G01X1764491Y913685D02*
Y916785D01*
X1763073Y914563D01*
X1764989D01*
G01X1765100Y913117D02*
X1763283D01*
Y911300D01*
G01X1761000Y902290D02*
X1759000D01*
G01X1772792Y1007450D02*
Y997250D01*
X1768192D01*
Y1007450D01*
X1772792D01*
G01X1767299D02*
Y997250D01*
X1762699D01*
Y1007450D01*
X1767299D01*
G01X1766731Y1020152D02*
Y1013952D01*
X1763531D01*
Y1020152D01*
X1766731D01*
G01X1762087D02*
Y1013952D01*
X1758887D01*
Y1020152D01*
X1762087D01*
G01X1773592D02*
Y1013952D01*
X1770392D01*
Y1020152D01*
X1773592D01*
G01X1767913Y1031518D02*
X1785615D01*
G01X1767913Y1044470D02*
Y1031518D01*
G01Y1070818D02*
Y1057784D01*
G01X1766621Y1055618D02*
X1786907D01*
G01X1766621Y1046718D02*
Y1055618D01*
G01X1786907Y1046718D02*
X1766621D01*
G01X1785615Y1070818D02*
X1767913D01*
G01X1772039Y1076196D02*
X1786839D01*
G01X1772039Y1107200D02*
Y1076196D01*
G01X1786839Y1107200D02*
X1772039D01*
G01X1769794Y1122422D02*
Y1115295D01*
X1788448D01*
X1791448Y1118295D01*
Y1122422D01*
G01X1788448Y1136949D02*
X1769794D01*
Y1129822D01*
G01X1767708Y1141881D02*
Y1195817D01*
G01X1785302Y1141881D02*
X1767708D01*
G01Y1195817D02*
X1785302D01*
G01X1775939Y1445210D02*
Y1439010D01*
X1772739D01*
Y1445210D01*
X1775939D01*
G01X1775816Y1477400D02*
Y1471200D01*
X1772616D01*
Y1477400D01*
X1775816D01*
G01X1762672Y1591667D02*
X1759472D01*
G01X1762672Y1597867D02*
Y1591667D01*
G01X1759472D02*
Y1597867D01*
G01X1766672Y1591667D02*
X1763472D01*
G01X1766672Y1597867D02*
Y1591667D01*
G01X1763472D02*
Y1597867D01*
G01X1761400Y1586600D02*
X1764600D01*
G01X1761400Y1580400D02*
Y1586600D01*
G01X1764600Y1580400D02*
X1761400D01*
G01X1764600Y1586600D02*
Y1580400D01*
G01X1759472Y1597867D02*
X1762672D01*
G01X1763472D02*
X1766672D01*
G01X1758022Y1639404D02*
Y1633204D01*
G01X1774022D02*
X1770822D01*
G01Y1639404D02*
X1774022D01*
G01X1770822Y1633204D02*
Y1639404D01*
G01X1770022Y1633204D02*
X1766822D01*
G01X1770022Y1639404D02*
Y1633204D01*
G01X1766822Y1639404D02*
X1770022D01*
G01X1766822Y1633204D02*
Y1639404D01*
G01X1762022Y1633204D02*
X1758822D01*
G01X1762022Y1639404D02*
Y1633204D01*
G01X1758822Y1639404D02*
X1762022D01*
G01X1758822Y1633204D02*
Y1639404D01*
G01X1766022Y1633204D02*
X1762822D01*
G01X1766022Y1639404D02*
Y1633204D01*
G01X1762822Y1639404D02*
X1766022D01*
G01X1762822Y1633204D02*
Y1639404D01*
G01X1788592Y-98915D02*
Y-95815D01*
X1789512D01*
X1789819Y-95970D01*
X1790049Y-96332D01*
X1790126Y-96745D01*
X1790049Y-97158D01*
X1789857Y-97468D01*
X1789512Y-97623D01*
X1788592D01*
G01X1791769Y-99018D02*
X1793149Y-95815D01*
G01X1794677Y-98915D02*
Y-95815D01*
X1796441Y-98915D01*
Y-95815D01*
G01X1798659Y-99018D02*
X1798582Y-98967D01*
Y-98863D01*
X1798659Y-98812D01*
X1798736Y-98863D01*
Y-98967D01*
X1798659Y-99018D01*
G01Y-97623D02*
X1798582Y-97572D01*
Y-97468D01*
X1798659Y-97417D01*
X1798736Y-97468D01*
Y-97572D01*
X1798659Y-97623D01*
G01X1800916Y-98915D02*
Y-95815D01*
X1801682D01*
X1801989Y-95970D01*
X1802219Y-96177D01*
X1802411Y-96487D01*
X1802564Y-96848D01*
X1802602Y-97365D01*
X1802564Y-97882D01*
X1802411Y-98243D01*
X1802219Y-98553D01*
X1801989Y-98760D01*
X1801682Y-98915D01*
X1800916D01*
G01X1803901D02*
X1804859Y-95815D01*
X1805817Y-98915D01*
G01X1805472Y-97830D02*
X1804246D01*
G01X1807959Y-95815D02*
X1807652Y-95918D01*
X1807422Y-96177D01*
X1807269Y-96487D01*
X1807154Y-96900D01*
X1807116Y-97365D01*
X1807154Y-97830D01*
X1807269Y-98243D01*
X1807422Y-98553D01*
X1807652Y-98812D01*
X1807959Y-98915D01*
X1808266Y-98812D01*
X1808496Y-98553D01*
X1808649Y-98243D01*
X1808764Y-97830D01*
X1808802Y-97365D01*
X1808764Y-96900D01*
X1808649Y-96487D01*
X1808496Y-96177D01*
X1808266Y-95918D01*
X1807959Y-95815D01*
G01X1810331Y-98915D02*
Y-95815D01*
X1811787D01*
G01X1811251Y-97313D02*
X1810331D01*
G01X1814159Y-95815D02*
X1813852Y-95918D01*
X1813622Y-96177D01*
X1813469Y-96487D01*
X1813354Y-96900D01*
X1813316Y-97365D01*
X1813354Y-97830D01*
X1813469Y-98243D01*
X1813622Y-98553D01*
X1813852Y-98812D01*
X1814159Y-98915D01*
X1814466Y-98812D01*
X1814696Y-98553D01*
X1814849Y-98243D01*
X1814964Y-97830D01*
X1815002Y-97365D01*
X1814964Y-96900D01*
X1814849Y-96487D01*
X1814696Y-96177D01*
X1814466Y-95918D01*
X1814159Y-95815D01*
G01X1817259D02*
Y-98915D01*
G01X1816377Y-95815D02*
X1818141D01*
G01X1821126Y-98915D02*
X1819592D01*
Y-95815D01*
X1821126D01*
G01X1820512Y-97313D02*
X1819592D01*
G01X1823766Y-97262D02*
X1823919Y-97107D01*
X1824034Y-96848D01*
X1824111Y-96487D01*
X1824034Y-96177D01*
X1823881Y-95970D01*
X1823612Y-95815D01*
X1822577D01*
Y-98915D01*
X1823842D01*
X1824111Y-98708D01*
X1824264Y-98398D01*
X1824341Y-98037D01*
X1824264Y-97675D01*
X1824034Y-97365D01*
X1823766Y-97262D01*
X1822577D01*
G01X1826099Y-95815D02*
X1827019D01*
G01X1826559D02*
Y-98915D01*
G01X1826099D02*
X1827019D01*
G01X1828931D02*
Y-95815D01*
X1830387D01*
G01X1829851Y-97313D02*
X1828931D01*
G01X1832759Y-95815D02*
X1832452Y-95918D01*
X1832222Y-96177D01*
X1832069Y-96487D01*
X1831954Y-96900D01*
X1831916Y-97365D01*
X1831954Y-97830D01*
X1832069Y-98243D01*
X1832222Y-98553D01*
X1832452Y-98812D01*
X1832759Y-98915D01*
X1833066Y-98812D01*
X1833296Y-98553D01*
X1833449Y-98243D01*
X1833564Y-97830D01*
X1833602Y-97365D01*
X1833564Y-96900D01*
X1833449Y-96487D01*
X1833296Y-96177D01*
X1833066Y-95918D01*
X1832759Y-95815D01*
G01X1774888Y44022D02*
Y47122D01*
G01X1776498D02*
Y44022D01*
G01Y45572D02*
X1774888D01*
G01X1779253Y44022D02*
Y47122D01*
X1777835Y44900D01*
X1779751D01*
G01X1781893Y44022D02*
X1782161Y44074D01*
X1782468Y44229D01*
X1782660Y44487D01*
X1782736Y44849D01*
X1782660Y45210D01*
X1782430Y45520D01*
X1782085Y45675D01*
X1781701D01*
X1781471Y45779D01*
X1781280Y46037D01*
X1781203Y46399D01*
X1781318Y46760D01*
X1781586Y47019D01*
X1781893Y47122D01*
X1782200Y47019D01*
X1782468Y46760D01*
X1782583Y46399D01*
X1782506Y46037D01*
X1782315Y45779D01*
X1782085Y45675D01*
X1781701D01*
X1781356Y45520D01*
X1781126Y45210D01*
X1781050Y44849D01*
X1781126Y44487D01*
X1781318Y44229D01*
X1781625Y44074D01*
X1781893Y44022D01*
G01X1789214Y67523D02*
X1777010D01*
G01X1789214Y79047D02*
Y67523D01*
G01X1777010D02*
Y70183D01*
G01X1783907Y59613D02*
Y56413D01*
G01X1777707Y59613D02*
X1783907D01*
G01X1777707Y56413D02*
Y59613D01*
G01X1783907Y56413D02*
X1777707D01*
G01X1774582Y70181D02*
Y66981D01*
G01X1777010Y79047D02*
X1789214D01*
G01X1777010Y76285D02*
Y79047D01*
G01X1780112Y73285D02*
X1777010Y76285D01*
G01Y70183D02*
X1780112Y73285D01*
G01X1774627Y74187D02*
Y70987D01*
G01Y78187D02*
Y74987D01*
G01X1774582Y82181D02*
Y78981D01*
G01X1775417Y93476D02*
X1778617D01*
G01X1775417Y87276D02*
Y93476D01*
G01X1778617Y87276D02*
X1775417D01*
G01X1778617Y93476D02*
Y87276D01*
G01X1784117D02*
X1780917D01*
G01X1784117Y93476D02*
Y87276D01*
G01X1780917Y93476D02*
X1784117D01*
G01X1780917Y87276D02*
Y93476D01*
G01X1788066Y87204D02*
X1784866D01*
G01X1788066Y93404D02*
Y87204D01*
G01X1784866Y93404D02*
X1788066D01*
G01X1784866Y87204D02*
Y93404D01*
G01X1791973Y87299D02*
X1788773D01*
G01Y93499D02*
X1791973D01*
G01X1788773Y87299D02*
Y93499D01*
G01X1781900Y98307D02*
X1784122D01*
X1784587Y98460D01*
X1784897Y98767D01*
X1785000Y99150D01*
X1784897Y99533D01*
X1784587Y99840D01*
X1784122Y99993D01*
X1781900D01*
G01X1785000Y102710D02*
X1781900D01*
X1784122Y101292D01*
Y103208D01*
G01X1781900Y105350D02*
X1782003Y105043D01*
X1782262Y104813D01*
X1782572Y104660D01*
X1782985Y104545D01*
X1783450Y104507D01*
X1783915Y104545D01*
X1784328Y104660D01*
X1784638Y104813D01*
X1784897Y105043D01*
X1785000Y105350D01*
X1784897Y105657D01*
X1784638Y105887D01*
X1784328Y106040D01*
X1783915Y106155D01*
X1783450Y106193D01*
X1782985Y106155D01*
X1782572Y106040D01*
X1782262Y105887D01*
X1782003Y105657D01*
X1781900Y105350D01*
G01X1785000Y108373D02*
X1784328Y108450D01*
X1783760Y108565D01*
X1783243Y108718D01*
X1782675Y108910D01*
X1781900Y109217D01*
Y107683D01*
G01X1780252Y111267D02*
Y95913D01*
G01X1780125Y116088D02*
Y112888D01*
G01X1773925Y116088D02*
X1780125D01*
G01X1773925Y112888D02*
Y116088D01*
G01X1780125Y112888D02*
X1773925D01*
G01X1774197Y178897D02*
Y176944D01*
G01X1776389Y170313D02*
Y167113D01*
G01X1778568Y167065D02*
Y170265D01*
G01X1784768Y167065D02*
X1778568D01*
G01X1784768Y170265D02*
Y167065D01*
G01X1778568Y170265D02*
X1784768D01*
G01X1778568Y175065D02*
Y178265D01*
G01X1784768Y175065D02*
X1778568D01*
G01X1784768Y178265D02*
Y175065D01*
G01X1778568Y178265D02*
X1784768D01*
G01X1778568Y171065D02*
Y174265D01*
G01X1784768Y171065D02*
X1778568D01*
G01X1784768Y174265D02*
Y171065D01*
G01X1778568Y174265D02*
X1784768D01*
G01X1778568Y179065D02*
Y182265D01*
G01X1784768Y179065D02*
X1778568D01*
G01X1784768Y182265D02*
Y179065D01*
G01X1774197Y188756D02*
Y186803D01*
G01X1777444Y198220D02*
Y195020D01*
G01X1778568Y182265D02*
X1784768D01*
G01X1778568Y183065D02*
Y186265D01*
G01X1784768Y183065D02*
X1778568D01*
G01X1784768Y186265D02*
Y183065D01*
G01X1778568Y186265D02*
X1784768D01*
G01Y198265D02*
Y195065D01*
G01X1778568D02*
Y198265D01*
G01X1784768Y195065D02*
X1778568D01*
G01X1784768Y194265D02*
Y191065D01*
G01X1778568Y194265D02*
X1784768D01*
G01X1778568Y191065D02*
Y194265D01*
G01X1784768Y191065D02*
X1778568D01*
G01Y187065D02*
Y190265D01*
G01X1784768Y187065D02*
X1778568D01*
G01X1784768Y190265D02*
Y187065D01*
G01X1778568Y190265D02*
X1784768D01*
G01X1788088Y194931D02*
Y198131D01*
G01X1794288Y194931D02*
X1788088D01*
G01X1778663Y202464D02*
X1784863D01*
Y199264D01*
X1778663D01*
Y202464D01*
G01X1778568Y198265D02*
X1784768D01*
G01X1778663Y207264D02*
Y210464D01*
G01X1784863Y207264D02*
X1778663D01*
G01X1784863Y210464D02*
Y207264D01*
G01X1778663Y210464D02*
X1784863D01*
G01Y206464D02*
Y203264D01*
G01X1778663Y206464D02*
X1784863D01*
G01X1778663Y203264D02*
Y206464D01*
G01X1784863Y203264D02*
X1778663D01*
G01X1788062Y202316D02*
X1794262D01*
G01X1788062Y199116D02*
Y202316D01*
G01X1794262Y199116D02*
X1788062D01*
G01X1788088Y198131D02*
X1794288D01*
G01X1778663Y214464D02*
X1784863D01*
Y211264D01*
X1778663D01*
Y214464D01*
G01Y215264D02*
Y218464D01*
G01X1784863Y215264D02*
X1778663D01*
G01X1784863Y218464D02*
Y215264D01*
G01X1778663Y218464D02*
X1784863D01*
G01X1778663Y220264D02*
Y223464D01*
G01X1784863Y220264D02*
X1778663D01*
G01X1784863Y223464D02*
Y220264D01*
G01X1778663Y223464D02*
X1784863D01*
G01X1778660Y227319D02*
X1784860D01*
Y224119D01*
X1778660D01*
Y227319D01*
G01X1776379Y234813D02*
Y250325D01*
G01X1791600Y265383D02*
X1788500D01*
Y266303D01*
X1788655Y266610D01*
X1789017Y266840D01*
X1789430Y266917D01*
X1789843Y266840D01*
X1790153Y266648D01*
X1790308Y266303D01*
Y265383D01*
G01X1791600Y268407D02*
X1788500D01*
Y269173D01*
X1788655Y269480D01*
X1788862Y269710D01*
X1789172Y269902D01*
X1789533Y270055D01*
X1790050Y270093D01*
X1790567Y270055D01*
X1790928Y269902D01*
X1791238Y269710D01*
X1791445Y269480D01*
X1791600Y269173D01*
Y268407D01*
G01Y272350D02*
X1788500D01*
X1789120Y271890D01*
G01X1791600D02*
Y272810D01*
G01X1789017Y274722D02*
X1788707Y274952D01*
X1788552Y275220D01*
X1788500Y275527D01*
X1788603Y275910D01*
X1788862Y276178D01*
X1789172Y276255D01*
X1789482Y276217D01*
X1789740Y276063D01*
X1790257Y275297D01*
X1790618Y274952D01*
X1791135Y274722D01*
X1791600Y274645D01*
Y276255D01*
G01X1788500Y278550D02*
X1788603Y278243D01*
X1788862Y278013D01*
X1789172Y277860D01*
X1789585Y277745D01*
X1790050Y277707D01*
X1790515Y277745D01*
X1790928Y277860D01*
X1791238Y278013D01*
X1791497Y278243D01*
X1791600Y278550D01*
X1791497Y278857D01*
X1791238Y279087D01*
X1790928Y279240D01*
X1790515Y279355D01*
X1790050Y279393D01*
X1789585Y279355D01*
X1789172Y279240D01*
X1788862Y279087D01*
X1788603Y278857D01*
X1788500Y278550D01*
G01X1786935Y264635D02*
Y295727D01*
G01X1776305Y373767D02*
X1791817D01*
G01X1776305Y404859D02*
Y373767D01*
G01X1774113Y401302D02*
Y389302D01*
G01X1791817Y404859D02*
X1776305D01*
G01X1778239Y422140D02*
Y406628D01*
G01D02*
X1809331D01*
G01X1774503Y424700D02*
Y413204D01*
G01X1809331Y422140D02*
X1778239D01*
G01X1785293Y423813D02*
Y427013D01*
G01X1791493Y423813D02*
X1785293D01*
G01Y427013D02*
X1791493D01*
G01X1781507Y433937D02*
X1784707D01*
G01X1781507Y427737D02*
Y433937D01*
G01X1784707Y427737D02*
X1781507D01*
G01X1784707Y433937D02*
Y427737D01*
G01X1785883Y427594D02*
X1785633Y427754D01*
X1785508Y427941D01*
X1785466Y428154D01*
X1785549Y428421D01*
X1785758Y428608D01*
X1786008Y428661D01*
X1786258Y428634D01*
X1786466Y428528D01*
X1786883Y427994D01*
X1787174Y427754D01*
X1787591Y427594D01*
X1787966Y427541D01*
Y428661D01*
G01X1785466Y430301D02*
X1785549Y430088D01*
X1785758Y429928D01*
X1786008Y429821D01*
X1786341Y429741D01*
X1786716Y429714D01*
X1787091Y429741D01*
X1787424Y429821D01*
X1787674Y429928D01*
X1787883Y430088D01*
X1787966Y430301D01*
X1787883Y430514D01*
X1787674Y430674D01*
X1787424Y430781D01*
X1787091Y430861D01*
X1786716Y430888D01*
X1786341Y430861D01*
X1786008Y430781D01*
X1785758Y430674D01*
X1785549Y430514D01*
X1785466Y430301D01*
G01X1780400Y431183D02*
X1777300D01*
Y432103D01*
X1777455Y432410D01*
X1777817Y432640D01*
X1778230Y432717D01*
X1778643Y432640D01*
X1778953Y432448D01*
X1779108Y432103D01*
Y431183D01*
G01X1777300Y434207D02*
X1779522D01*
X1779987Y434360D01*
X1780297Y434667D01*
X1780400Y435050D01*
X1780297Y435433D01*
X1779987Y435740D01*
X1779522Y435893D01*
X1777300D01*
G01X1780400Y438150D02*
X1777300D01*
X1777920Y437690D01*
G01X1780400D02*
Y438610D01*
G01X1777300Y441250D02*
X1777403Y440943D01*
X1777662Y440713D01*
X1777972Y440560D01*
X1778385Y440445D01*
X1778850Y440407D01*
X1779315Y440445D01*
X1779728Y440560D01*
X1780038Y440713D01*
X1780297Y440943D01*
X1780400Y441250D01*
X1780297Y441557D01*
X1780038Y441787D01*
X1779728Y441940D01*
X1779315Y442055D01*
X1778850Y442093D01*
X1778385Y442055D01*
X1777972Y441940D01*
X1777662Y441787D01*
X1777403Y441557D01*
X1777300Y441250D01*
G01X1779108Y443622D02*
X1778747Y443890D01*
X1778540Y444120D01*
X1778437Y444427D01*
X1778540Y444695D01*
X1778747Y444887D01*
X1779057Y445040D01*
X1779418Y445078D01*
X1779728Y445040D01*
X1780038Y444887D01*
X1780297Y444657D01*
X1780400Y444388D01*
X1780297Y444082D01*
X1779987Y443813D01*
X1779522Y443660D01*
X1779005Y443622D01*
X1778333Y443698D01*
X1777972Y443813D01*
X1777610Y444005D01*
X1777352Y444273D01*
X1777300Y444542D01*
X1777403Y444810D01*
X1777662Y445002D01*
G01X1788831Y431227D02*
Y430062D01*
G01D02*
X1791972D01*
G01X1779733Y447001D02*
X1775133D01*
G01X1779733Y457201D02*
Y447001D01*
G01X1775133Y457201D02*
X1779733D01*
G01X1775133Y447001D02*
Y457201D01*
G01X1780633D02*
X1785233D01*
G01X1780633Y447001D02*
Y457201D01*
G01X1785233Y447001D02*
X1780633D01*
G01X1785233Y457201D02*
Y447001D01*
G01X1774025Y450137D02*
Y443937D01*
G01X1787833Y457501D02*
Y460701D01*
G01X1794033Y457501D02*
X1787833D01*
G01Y456901D02*
X1794033D01*
G01X1787833Y453701D02*
Y456901D01*
G01X1794033Y453701D02*
X1787833D01*
G01X1788993Y450704D02*
Y453204D01*
X1788673Y452704D01*
G01Y450704D02*
X1789313D01*
G01X1791193D02*
Y453204D01*
X1790873Y452704D01*
G01Y450704D02*
X1791513D01*
G01X1786007Y442835D02*
X1783507D01*
X1784007Y442515D01*
G01X1786007D02*
Y443155D01*
G01X1783924Y444528D02*
X1783674Y444688D01*
X1783549Y444875D01*
X1783507Y445088D01*
X1783590Y445355D01*
X1783799Y445542D01*
X1784049Y445595D01*
X1784299Y445568D01*
X1784507Y445462D01*
X1784924Y444928D01*
X1785215Y444688D01*
X1785632Y444528D01*
X1786007Y444475D01*
Y445595D01*
G01X1788831Y450140D02*
Y448975D01*
G01X1791965Y450140D02*
X1788831D01*
G01X1778143Y466836D02*
Y476284D01*
G01X1788979Y466836D02*
X1778143D01*
G01X1788979Y476284D02*
Y466836D01*
G01X1775661Y473160D02*
Y469960D01*
G01Y469160D02*
Y465960D01*
G01X1787833Y460701D02*
X1794033D01*
G01X1787833Y464701D02*
X1794033D01*
G01X1787833Y461501D02*
Y464701D01*
G01X1794033Y461501D02*
X1787833D01*
G01X1775661Y477160D02*
Y473960D01*
G01X1780672Y477685D02*
X1780365Y477737D01*
X1780097Y477943D01*
X1779867Y478253D01*
X1779714Y478615D01*
X1779637Y479028D01*
Y479442D01*
X1779714Y479855D01*
X1779867Y480217D01*
X1780097Y480527D01*
X1780365Y480733D01*
X1780672Y480785D01*
X1780979Y480733D01*
X1781247Y480527D01*
X1781477Y480217D01*
X1781630Y479855D01*
X1781707Y479442D01*
Y479028D01*
X1781630Y478615D01*
X1781477Y478253D01*
X1781247Y477943D01*
X1780979Y477737D01*
X1780672Y477685D01*
G01X1780979Y478512D02*
X1781439Y477685D01*
G01X1783044Y480268D02*
X1783274Y480578D01*
X1783542Y480733D01*
X1783849Y480785D01*
X1784232Y480682D01*
X1784500Y480423D01*
X1784577Y480113D01*
X1784539Y479803D01*
X1784385Y479545D01*
X1783619Y479028D01*
X1783274Y478667D01*
X1783044Y478150D01*
X1782967Y477685D01*
X1784577D01*
G01X1786872D02*
Y480785D01*
X1786412Y480165D01*
G01Y477685D02*
X1787332D01*
G01X1789320Y478047D02*
X1789589Y477788D01*
X1789895Y477685D01*
X1790202Y477788D01*
X1790470Y478098D01*
X1790662Y478563D01*
X1790739Y479028D01*
Y479597D01*
X1790662Y480062D01*
X1790470Y480475D01*
X1790240Y480682D01*
X1789972Y480785D01*
X1789665Y480682D01*
X1789435Y480475D01*
X1789282Y480165D01*
X1789205Y479752D01*
X1789282Y479390D01*
X1789474Y479028D01*
X1789704Y478822D01*
X1789972Y478770D01*
X1790279Y478873D01*
X1790509Y479132D01*
X1790739Y479597D01*
G01X1785561Y476284D02*
X1788979D01*
G01X1783561Y474560D02*
X1785561Y476284D01*
G01X1781561D02*
X1783561Y474560D01*
G01X1778143Y476284D02*
X1781561D01*
G01X1775661Y481160D02*
Y477960D01*
G01X1774025Y813261D02*
Y811039D01*
X1774178Y810574D01*
X1774485Y810264D01*
X1774868Y810161D01*
X1775251Y810264D01*
X1775558Y810574D01*
X1775711Y811039D01*
Y813261D01*
G01X1777968Y810161D02*
Y813261D01*
X1777508Y812641D01*
G01Y810161D02*
X1778428D01*
G01X1781068Y813261D02*
X1780761Y813158D01*
X1780531Y812899D01*
X1780378Y812589D01*
X1780263Y812176D01*
X1780225Y811711D01*
X1780263Y811246D01*
X1780378Y810833D01*
X1780531Y810523D01*
X1780761Y810264D01*
X1781068Y810161D01*
X1781375Y810264D01*
X1781605Y810523D01*
X1781758Y810833D01*
X1781873Y811246D01*
X1781911Y811711D01*
X1781873Y812176D01*
X1781758Y812589D01*
X1781605Y812899D01*
X1781375Y813158D01*
X1781068Y813261D01*
G01X1784168Y810161D02*
X1784436Y810213D01*
X1784743Y810368D01*
X1784935Y810626D01*
X1785011Y810988D01*
X1784935Y811349D01*
X1784705Y811659D01*
X1784360Y811814D01*
X1783976D01*
X1783746Y811918D01*
X1783555Y812176D01*
X1783478Y812538D01*
X1783593Y812899D01*
X1783861Y813158D01*
X1784168Y813261D01*
X1784475Y813158D01*
X1784743Y812899D01*
X1784858Y812538D01*
X1784781Y812176D01*
X1784590Y811918D01*
X1784360Y811814D01*
X1783976D01*
X1783631Y811659D01*
X1783401Y811349D01*
X1783325Y810988D01*
X1783401Y810626D01*
X1783593Y810368D01*
X1783900Y810213D01*
X1784168Y810161D01*
G01X1782744Y820596D02*
X1784303D01*
G01X1785637Y823378D02*
Y821729D01*
G01X1782596Y824670D02*
X1784492D01*
G01X1773825Y820596D02*
X1780293D01*
G01X1773825Y824670D02*
X1780324D01*
G01X1773825D02*
Y823803D01*
G01Y820596D02*
Y821442D01*
G01X1777671Y831794D02*
X1774471D01*
G01X1777671Y837994D02*
Y831794D01*
G01X1774471Y837994D02*
X1777671D01*
G01X1774471Y831794D02*
Y837994D01*
G01X1781984Y875600D02*
Y873600D01*
G01X1775050Y931549D02*
X1785250D01*
Y926949D01*
X1775050D01*
Y931549D01*
G01X1776868Y926146D02*
X1783068D01*
Y922946D01*
X1776868D01*
Y926146D01*
G01X1787937Y922977D02*
Y929177D01*
X1791137D01*
Y922977D01*
X1787937D01*
G01X1774110Y919300D02*
Y915300D01*
G01X1783953Y917400D02*
Y915400D01*
G01X1785263Y966160D02*
X1779263D01*
Y978160D01*
X1785263D01*
Y966160D01*
G01X1791063Y967850D02*
Y961650D01*
X1787863D01*
Y967850D01*
X1791063D01*
G01X1789859Y969552D02*
X1801867D01*
G01X1789859Y970356D02*
Y969552D01*
X1792163D01*
G01X1787963Y986660D02*
X1794163D01*
Y983460D01*
X1787963D01*
Y986660D01*
G01X1794163Y988060D02*
X1787963D01*
Y991260D01*
X1794163D01*
Y988060D01*
G01X1789859Y981560D02*
X1801867D01*
G01X1791963D02*
X1789859D01*
Y980756D01*
G01X1789079Y1007450D02*
Y997250D01*
X1784479D01*
Y1007450D01*
X1789079D01*
G01X1778248D02*
Y997250D01*
X1773648D01*
Y1007450D01*
X1778248D01*
G01X1783689D02*
Y997250D01*
X1779089D01*
Y1007450D01*
X1783689D01*
G01X1785745Y1020152D02*
Y1013952D01*
X1782545D01*
Y1020152D01*
X1785745D01*
G01X1791635D02*
Y1013952D01*
X1788435D01*
Y1020152D01*
X1791635D01*
G01X1779642D02*
Y1013952D01*
X1776442D01*
Y1020152D01*
X1779642D01*
G01X1785615Y1031518D02*
Y1044470D01*
G01X1789646Y1031210D02*
X1807348D01*
G01X1789646Y1044210D02*
Y1031210D01*
G01X1785615Y1058216D02*
Y1070818D01*
G01X1789646Y1070510D02*
Y1058303D01*
G01X1786907Y1055618D02*
Y1046718D01*
G01X1788354D02*
Y1055618D01*
G01X1808640Y1046718D02*
X1788354D01*
G01Y1055618D02*
X1808640D01*
G01X1807348Y1070510D02*
X1789646D01*
G01X1786839Y1076196D02*
Y1107200D01*
G01X1788277Y1086261D02*
Y1089461D01*
G01X1794477Y1086261D02*
X1788277D01*
G01Y1089461D02*
X1794477D01*
G01X1791448Y1129822D02*
Y1133949D01*
X1788448Y1136949D01*
G01X1777895Y1198075D02*
Y1201175D01*
X1778815D01*
X1779122Y1201020D01*
X1779352Y1200658D01*
X1779429Y1200245D01*
X1779352Y1199832D01*
X1779160Y1199522D01*
X1778815Y1199367D01*
X1777895D01*
G01X1780919Y1201175D02*
Y1198953D01*
X1781072Y1198488D01*
X1781379Y1198178D01*
X1781762Y1198075D01*
X1782145Y1198178D01*
X1782452Y1198488D01*
X1782605Y1198953D01*
Y1201175D01*
G01X1784862Y1198075D02*
Y1201175D01*
X1784402Y1200555D01*
G01Y1198075D02*
X1785322D01*
G01X1787310Y1198437D02*
X1787579Y1198178D01*
X1787885Y1198075D01*
X1788192Y1198178D01*
X1788460Y1198488D01*
X1788652Y1198953D01*
X1788729Y1199418D01*
Y1199987D01*
X1788652Y1200452D01*
X1788460Y1200865D01*
X1788230Y1201072D01*
X1787962Y1201175D01*
X1787655Y1201072D01*
X1787425Y1200865D01*
X1787272Y1200555D01*
X1787195Y1200142D01*
X1787272Y1199780D01*
X1787464Y1199418D01*
X1787694Y1199212D01*
X1787962Y1199160D01*
X1788269Y1199263D01*
X1788499Y1199522D01*
X1788729Y1199987D01*
G01X1785328Y1204134D02*
X1782828D01*
X1783328Y1203814D01*
G01X1785328D02*
Y1204454D01*
G01X1785036Y1205881D02*
X1785245Y1206067D01*
X1785328Y1206281D01*
X1785245Y1206494D01*
X1784995Y1206681D01*
X1784620Y1206814D01*
X1784245Y1206867D01*
X1783786D01*
X1783411Y1206814D01*
X1783078Y1206681D01*
X1782911Y1206521D01*
X1782828Y1206334D01*
X1782911Y1206121D01*
X1783078Y1205961D01*
X1783328Y1205854D01*
X1783661Y1205801D01*
X1783953Y1205854D01*
X1784245Y1205987D01*
X1784411Y1206147D01*
X1784453Y1206334D01*
X1784370Y1206547D01*
X1784161Y1206707D01*
X1783786Y1206867D01*
G01X1782374Y1206588D02*
X1779174D01*
G01X1782374Y1212788D02*
Y1206588D01*
G01X1779174Y1212788D02*
X1782374D01*
G01X1779174Y1206588D02*
Y1212788D01*
G01X1783123Y1214823D02*
X1780623D01*
X1781123Y1214503D01*
G01X1783123D02*
Y1215143D01*
G01Y1217023D02*
X1780623D01*
X1781123Y1216703D01*
G01X1783123D02*
Y1217343D01*
G01X1783956Y1218423D02*
Y1220023D01*
G01X1783123Y1221423D02*
X1780623D01*
X1781123Y1221103D01*
G01X1783123D02*
Y1221743D01*
G01Y1223623D02*
X1783081Y1223810D01*
X1782956Y1224023D01*
X1782748Y1224156D01*
X1782456Y1224210D01*
X1782165Y1224156D01*
X1781915Y1223996D01*
X1781790Y1223756D01*
Y1223490D01*
X1781706Y1223330D01*
X1781498Y1223196D01*
X1781206Y1223143D01*
X1780915Y1223223D01*
X1780706Y1223410D01*
X1780623Y1223623D01*
X1780706Y1223836D01*
X1780915Y1224023D01*
X1781206Y1224103D01*
X1781498Y1224050D01*
X1781706Y1223916D01*
X1781790Y1223756D01*
Y1223490D01*
X1781915Y1223250D01*
X1782165Y1223090D01*
X1782456Y1223036D01*
X1782748Y1223090D01*
X1782956Y1223223D01*
X1783081Y1223436D01*
X1783123Y1223623D01*
G01X1785788Y1207523D02*
Y1207252D01*
X1789590D01*
G01X1793897Y1233977D02*
X1781897D01*
G01D02*
Y1239977D01*
G01X1793897Y1227077D02*
X1781897D01*
G01Y1233077D02*
X1793897D01*
G01X1781897Y1227077D02*
Y1233077D01*
G01X1791890Y1223394D02*
X1785788D01*
Y1222923D01*
G01X1781897Y1239977D02*
X1793897D01*
G01Y1240877D02*
X1781897D01*
G01Y1246877D02*
X1793897D01*
G01X1781897Y1240877D02*
Y1246877D01*
G01X1793897Y1247777D02*
X1781897D01*
G01Y1253777D02*
X1793897D01*
G01X1781897Y1247777D02*
Y1253777D01*
G01X1789574Y1259537D02*
X1795774D01*
G01X1789574Y1256337D02*
Y1259537D01*
G01X1795774Y1256337D02*
X1789574D01*
G01X1791734Y1429356D02*
X1785534D01*
Y1432556D01*
X1791734D01*
Y1429356D01*
G01X1779471Y1449382D02*
X1779164Y1449434D01*
X1778896Y1449640D01*
X1778666Y1449950D01*
X1778513Y1450312D01*
X1778436Y1450725D01*
Y1451139D01*
X1778513Y1451552D01*
X1778666Y1451914D01*
X1778896Y1452224D01*
X1779164Y1452430D01*
X1779471Y1452482D01*
X1779778Y1452430D01*
X1780046Y1452224D01*
X1780276Y1451914D01*
X1780429Y1451552D01*
X1780506Y1451139D01*
Y1450725D01*
X1780429Y1450312D01*
X1780276Y1449950D01*
X1780046Y1449640D01*
X1779778Y1449434D01*
X1779471Y1449382D01*
G01X1779778Y1450209D02*
X1780238Y1449382D01*
G01X1781843Y1451965D02*
X1782073Y1452275D01*
X1782341Y1452430D01*
X1782648Y1452482D01*
X1783031Y1452379D01*
X1783299Y1452120D01*
X1783376Y1451810D01*
X1783338Y1451500D01*
X1783184Y1451242D01*
X1782418Y1450725D01*
X1782073Y1450364D01*
X1781843Y1449847D01*
X1781766Y1449382D01*
X1783376D01*
G01X1786131D02*
Y1452482D01*
X1784713Y1450260D01*
X1786629D01*
G01X1789231Y1449382D02*
Y1452482D01*
X1787813Y1450260D01*
X1789729D01*
G01X1792139Y1448439D02*
Y1438991D01*
X1781303D01*
Y1448439D01*
X1784721D01*
X1786721Y1446715D01*
X1788721Y1448439D01*
X1792139D01*
G01X1776627Y1439008D02*
Y1445208D01*
X1779827D01*
Y1439008D01*
X1776627D01*
G01X1781530Y1464300D02*
X1787730D01*
Y1461100D01*
X1781530D01*
Y1464300D01*
G01X1779348Y1481572D02*
X1779041Y1481624D01*
X1778773Y1481830D01*
X1778543Y1482140D01*
X1778390Y1482502D01*
X1778313Y1482915D01*
Y1483329D01*
X1778390Y1483742D01*
X1778543Y1484104D01*
X1778773Y1484414D01*
X1779041Y1484620D01*
X1779348Y1484672D01*
X1779655Y1484620D01*
X1779923Y1484414D01*
X1780153Y1484104D01*
X1780306Y1483742D01*
X1780383Y1483329D01*
Y1482915D01*
X1780306Y1482502D01*
X1780153Y1482140D01*
X1779923Y1481830D01*
X1779655Y1481624D01*
X1779348Y1481572D01*
G01X1779655Y1482399D02*
X1780115Y1481572D01*
G01X1781720Y1484155D02*
X1781950Y1484465D01*
X1782218Y1484620D01*
X1782525Y1484672D01*
X1782908Y1484569D01*
X1783176Y1484310D01*
X1783253Y1484000D01*
X1783215Y1483690D01*
X1783061Y1483432D01*
X1782295Y1482915D01*
X1781950Y1482554D01*
X1781720Y1482037D01*
X1781643Y1481572D01*
X1783253D01*
G01X1786008D02*
Y1484672D01*
X1784590Y1482450D01*
X1786506D01*
G01X1787805Y1482192D02*
X1788035Y1481830D01*
X1788341Y1481624D01*
X1788686Y1481572D01*
X1788993Y1481624D01*
X1789300Y1481882D01*
X1789491Y1482192D01*
X1789530Y1482502D01*
X1789453Y1482864D01*
X1789185Y1483122D01*
X1788916Y1483225D01*
X1788571D01*
G01X1788916D02*
X1789146Y1483380D01*
X1789338Y1483639D01*
X1789415Y1483949D01*
X1789338Y1484259D01*
X1789146Y1484517D01*
X1788801Y1484672D01*
X1788456Y1484620D01*
X1788111Y1484414D01*
G01X1792016Y1480629D02*
Y1471181D01*
X1781180D01*
Y1480629D01*
X1784598D01*
X1786598Y1478905D01*
X1788598Y1480629D01*
X1792016D01*
G01X1776504Y1471198D02*
Y1477398D01*
X1779704D01*
Y1471198D01*
X1776504D01*
G01X1806297Y1517889D02*
G02I-9450J0D01*
G01X1787292Y1530845D02*
Y1533945D01*
G01X1788902D02*
Y1530845D01*
G01Y1532395D02*
X1787292D01*
G01X1791657Y1530845D02*
Y1533945D01*
X1790239Y1531723D01*
X1792155D01*
G01X1793454Y1531465D02*
X1793684Y1531103D01*
X1793990Y1530897D01*
X1794335Y1530845D01*
X1794642Y1530897D01*
X1794949Y1531155D01*
X1795140Y1531465D01*
X1795179Y1531775D01*
X1795102Y1532137D01*
X1794834Y1532395D01*
X1794565Y1532498D01*
X1794220D01*
G01X1794565D02*
X1794795Y1532653D01*
X1794987Y1532912D01*
X1795064Y1533222D01*
X1794987Y1533532D01*
X1794795Y1533790D01*
X1794450Y1533945D01*
X1794105Y1533893D01*
X1793760Y1533687D01*
G01X1779655Y1610195D02*
X1781877D01*
X1782342Y1610348D01*
X1782652Y1610655D01*
X1782755Y1611038D01*
X1782652Y1611421D01*
X1782342Y1611728D01*
X1781877Y1611881D01*
X1779655D01*
G01X1782135Y1613295D02*
X1782497Y1613525D01*
X1782703Y1613831D01*
X1782755Y1614176D01*
X1782703Y1614483D01*
X1782445Y1614790D01*
X1782135Y1614981D01*
X1781825Y1615020D01*
X1781463Y1614943D01*
X1781205Y1614675D01*
X1781102Y1614406D01*
Y1614061D01*
G01Y1614406D02*
X1780947Y1614636D01*
X1780688Y1614828D01*
X1780378Y1614905D01*
X1780068Y1614828D01*
X1779810Y1614636D01*
X1779655Y1614291D01*
X1779707Y1613946D01*
X1779913Y1613601D01*
G01X1780172Y1616510D02*
X1779862Y1616740D01*
X1779707Y1617008D01*
X1779655Y1617315D01*
X1779758Y1617698D01*
X1780017Y1617966D01*
X1780327Y1618043D01*
X1780637Y1618005D01*
X1780895Y1617851D01*
X1781412Y1617085D01*
X1781773Y1616740D01*
X1782290Y1616510D01*
X1782755Y1616433D01*
Y1618043D01*
G01X1782393Y1619686D02*
X1782652Y1619955D01*
X1782755Y1620261D01*
X1782652Y1620568D01*
X1782342Y1620836D01*
X1781877Y1621028D01*
X1781412Y1621105D01*
X1780843D01*
X1780378Y1621028D01*
X1779965Y1620836D01*
X1779758Y1620606D01*
X1779655Y1620338D01*
X1779758Y1620031D01*
X1779965Y1619801D01*
X1780275Y1619648D01*
X1780688Y1619571D01*
X1781050Y1619648D01*
X1781412Y1619840D01*
X1781618Y1620070D01*
X1781670Y1620338D01*
X1781567Y1620645D01*
X1781308Y1620875D01*
X1780843Y1621105D01*
G01X1776163Y1601216D02*
Y1628364D01*
G01X1774022Y1639404D02*
Y1633204D01*
G01X1778022D02*
X1774822D01*
G01X1778022Y1639404D02*
Y1633204D01*
G01X1774822Y1639404D02*
X1778022D01*
G01X1774822Y1633204D02*
Y1639404D01*
G01X1802892Y-40488D02*
Y-23888D01*
X1812492D01*
Y-40488D01*
X1802892D01*
G01X1797107Y-21200D02*
Y-18100D01*
X1797873D01*
X1798180Y-18255D01*
X1798410Y-18462D01*
X1798602Y-18772D01*
X1798755Y-19133D01*
X1798793Y-19650D01*
X1798755Y-20167D01*
X1798602Y-20528D01*
X1798410Y-20838D01*
X1798180Y-21045D01*
X1797873Y-21200D01*
X1797107D01*
G01X1801817D02*
X1800283D01*
Y-18100D01*
X1801817D01*
G01X1801203Y-19598D02*
X1800283D01*
G01X1804150Y-21200D02*
Y-18100D01*
X1803690Y-18720D01*
G01Y-21200D02*
X1804610D01*
G01X1806407Y-20735D02*
X1806637Y-20993D01*
X1806905Y-21148D01*
X1807250Y-21200D01*
X1807595Y-21097D01*
X1807863Y-20890D01*
X1808055Y-20528D01*
X1808093Y-20115D01*
X1808017Y-19702D01*
X1807825Y-19443D01*
X1807557Y-19237D01*
X1807288Y-19185D01*
X1807020Y-19237D01*
X1806675Y-19443D01*
X1806790Y-18100D01*
X1807825D01*
G01X1810350D02*
Y-21200D01*
G01X1809468Y-18100D02*
X1811232D01*
G01X1812300Y-22233D02*
X1814600D01*
G01X1816550Y-21200D02*
Y-18100D01*
X1816090Y-18720D01*
G01Y-21200D02*
X1817010D01*
G01X1792300Y69107D02*
X1794522D01*
X1794987Y69260D01*
X1795297Y69567D01*
X1795400Y69950D01*
X1795297Y70333D01*
X1794987Y70640D01*
X1794522Y70793D01*
X1792300D01*
G01X1795400Y73050D02*
X1792300D01*
X1792920Y72590D01*
G01X1795400D02*
Y73510D01*
G01Y76610D02*
X1792300D01*
X1794522Y75192D01*
Y77108D01*
G01X1795400Y79250D02*
X1792300D01*
X1792920Y78790D01*
G01X1795400D02*
Y79710D01*
G01X1791973Y93499D02*
Y87299D01*
G01X1819333Y120792D02*
G02I-9450J0D01*
G01X1795545Y129400D02*
Y132500D01*
G01X1797155D02*
Y129400D01*
G01Y130950D02*
X1795545D01*
G01X1799910Y129400D02*
Y132500D01*
X1798492Y130278D01*
X1800408D01*
G01X1803010Y129400D02*
Y132500D01*
X1801592Y130278D01*
X1803508D01*
G01X1794288Y198131D02*
Y194931D01*
G01X1794262Y202316D02*
Y199116D01*
G01X1796400Y374183D02*
X1793300D01*
Y375103D01*
X1793455Y375410D01*
X1793817Y375640D01*
X1794230Y375717D01*
X1794643Y375640D01*
X1794953Y375448D01*
X1795108Y375103D01*
Y374183D01*
G01X1796400Y377207D02*
X1793300D01*
Y377973D01*
X1793455Y378280D01*
X1793662Y378510D01*
X1793972Y378702D01*
X1794333Y378855D01*
X1794850Y378893D01*
X1795367Y378855D01*
X1795728Y378702D01*
X1796038Y378510D01*
X1796245Y378280D01*
X1796400Y377973D01*
Y377207D01*
G01Y381150D02*
X1793300D01*
X1793920Y380690D01*
G01X1796400D02*
Y381610D01*
G01X1795780Y383407D02*
X1796142Y383637D01*
X1796348Y383943D01*
X1796400Y384288D01*
X1796348Y384595D01*
X1796090Y384902D01*
X1795780Y385093D01*
X1795470Y385132D01*
X1795108Y385055D01*
X1794850Y384787D01*
X1794747Y384518D01*
Y384173D01*
G01Y384518D02*
X1794592Y384748D01*
X1794333Y384940D01*
X1794023Y385017D01*
X1793713Y384940D01*
X1793455Y384748D01*
X1793300Y384403D01*
X1793352Y384058D01*
X1793558Y383713D01*
G01X1791817Y373767D02*
Y404859D01*
G01X1791493Y427013D02*
Y423813D01*
G01X1795721Y426877D02*
X1795881Y427127D01*
X1796068Y427252D01*
X1796281Y427294D01*
X1796548Y427211D01*
X1796735Y427002D01*
X1796788Y426752D01*
X1796761Y426502D01*
X1796655Y426294D01*
X1796121Y425877D01*
X1795881Y425586D01*
X1795721Y425169D01*
X1795668Y424794D01*
X1796788D01*
G01X1798428D02*
Y427294D01*
X1798108Y426794D01*
G01Y424794D02*
X1798748D01*
G01X1799828Y423961D02*
X1801428D01*
G01X1802321Y426877D02*
X1802481Y427127D01*
X1802668Y427252D01*
X1802881Y427294D01*
X1803148Y427211D01*
X1803335Y427002D01*
X1803388Y426752D01*
X1803361Y426502D01*
X1803255Y426294D01*
X1802721Y425877D01*
X1802481Y425586D01*
X1802321Y425169D01*
X1802268Y424794D01*
X1803388D01*
G01X1804521Y426877D02*
X1804681Y427127D01*
X1804868Y427252D01*
X1805081Y427294D01*
X1805348Y427211D01*
X1805535Y427002D01*
X1805588Y426752D01*
X1805561Y426502D01*
X1805455Y426294D01*
X1804921Y425877D01*
X1804681Y425586D01*
X1804521Y425169D01*
X1804468Y424794D01*
X1805588D01*
G01X1808434Y437439D02*
X1805234D01*
G01D02*
Y443639D01*
G01X1793983Y430062D02*
X1795883D01*
G01X1801035D02*
Y431235D01*
G01X1797894Y430062D02*
X1801035D01*
G01X1802533Y454501D02*
X1799333D01*
G01X1802533Y460701D02*
Y454501D01*
G01X1799333D02*
Y460701D01*
G01X1806533Y454501D02*
X1803333D01*
G01D02*
Y460701D01*
G01X1795333Y454501D02*
Y460701D01*
G01X1798533Y454501D02*
X1795333D01*
G01X1798533Y460701D02*
Y454501D01*
G01X1794033Y460701D02*
Y457501D01*
G01Y456901D02*
Y453701D01*
G01X1805234Y443639D02*
X1808434D01*
G01X1803067Y448762D02*
X1803253Y448553D01*
X1803467Y448470D01*
X1803680Y448553D01*
X1803867Y448803D01*
X1804000Y449178D01*
X1804053Y449553D01*
Y450012D01*
X1804000Y450387D01*
X1803867Y450720D01*
X1803707Y450887D01*
X1803520Y450970D01*
X1803307Y450887D01*
X1803147Y450720D01*
X1803040Y450470D01*
X1802987Y450137D01*
X1803040Y449845D01*
X1803173Y449553D01*
X1803333Y449387D01*
X1803520Y449345D01*
X1803733Y449428D01*
X1803893Y449637D01*
X1804053Y450012D01*
G01X1799052Y451193D02*
Y453693D01*
X1798732Y453193D01*
G01Y451193D02*
X1799372D01*
G01X1801252Y453693D02*
X1801039Y453610D01*
X1800879Y453401D01*
X1800772Y453151D01*
X1800692Y452818D01*
X1800665Y452443D01*
X1800692Y452068D01*
X1800772Y451735D01*
X1800879Y451485D01*
X1801039Y451276D01*
X1801252Y451193D01*
X1801465Y451276D01*
X1801625Y451485D01*
X1801732Y451735D01*
X1801812Y452068D01*
X1801839Y452443D01*
X1801812Y452818D01*
X1801732Y453151D01*
X1801625Y453401D01*
X1801465Y453610D01*
X1801252Y453693D01*
G01X1795901Y450140D02*
X1793965D01*
G01X1801035D02*
X1797901D01*
G01X1801035Y448975D02*
Y450140D01*
G01X1799333Y460701D02*
X1802533D01*
G01X1803333D02*
X1806533D01*
G01X1795333D02*
X1798533D01*
G01X1794033Y464701D02*
Y461501D01*
G01X1797661Y476160D02*
Y472960D01*
G01X1791461D02*
Y476160D01*
G01X1797661Y472960D02*
X1791461D01*
G01Y476160D02*
X1797661D01*
G01X1805847Y808150D02*
X1794035D01*
G01X1805847Y819798D02*
Y808150D01*
G01X1794035D02*
Y809198D01*
G01Y830398D02*
Y831198D01*
G01X1805847Y839646D02*
Y827998D01*
G01X1794035Y816598D02*
Y817398D01*
G01Y839646D02*
X1805847D01*
G01X1794035Y838598D02*
Y839646D01*
G01X1796107Y872987D02*
X1796337Y872625D01*
X1796643Y872419D01*
X1796988Y872367D01*
X1797295Y872419D01*
X1797602Y872677D01*
X1797793Y872987D01*
X1797832Y873297D01*
X1797755Y873659D01*
X1797487Y873917D01*
X1797218Y874020D01*
X1796873D01*
G01X1797218D02*
X1797448Y874175D01*
X1797640Y874434D01*
X1797717Y874744D01*
X1797640Y875054D01*
X1797448Y875312D01*
X1797103Y875467D01*
X1796758Y875415D01*
X1796413Y875209D01*
G01X1799322Y874950D02*
X1799552Y875260D01*
X1799820Y875415D01*
X1800127Y875467D01*
X1800510Y875364D01*
X1800778Y875105D01*
X1800855Y874795D01*
X1800817Y874485D01*
X1800663Y874227D01*
X1799897Y873710D01*
X1799552Y873349D01*
X1799322Y872832D01*
X1799245Y872367D01*
X1800855D01*
G01X1801587Y880793D02*
X1801225Y880563D01*
X1801019Y880257D01*
X1800967Y879912D01*
X1801019Y879605D01*
X1801277Y879298D01*
X1801587Y879107D01*
X1801897Y879068D01*
X1802259Y879145D01*
X1802517Y879413D01*
X1802620Y879682D01*
Y880027D01*
G01Y879682D02*
X1802775Y879452D01*
X1803034Y879260D01*
X1803344Y879183D01*
X1803654Y879260D01*
X1803912Y879452D01*
X1804067Y879797D01*
X1804015Y880142D01*
X1803809Y880487D01*
G01X1801587Y877693D02*
X1801225Y877463D01*
X1801019Y877157D01*
X1800967Y876812D01*
X1801019Y876505D01*
X1801277Y876198D01*
X1801587Y876007D01*
X1801897Y875968D01*
X1802259Y876045D01*
X1802517Y876313D01*
X1802620Y876582D01*
Y876927D01*
G01Y876582D02*
X1802775Y876352D01*
X1803034Y876160D01*
X1803344Y876083D01*
X1803654Y876160D01*
X1803912Y876352D01*
X1804067Y876697D01*
X1804015Y877042D01*
X1803809Y877387D01*
G01X1796900Y877683D02*
X1798717D01*
Y879500D01*
G01X1791827Y875500D02*
Y871500D01*
G01X1800800Y894416D02*
X1804800D01*
G01X1802800Y884573D02*
X1800800D01*
G01X1798717Y911300D02*
Y913117D01*
X1796900D01*
G01X1802800Y904258D02*
X1800800D01*
G01X1795074Y929086D02*
Y922886D01*
X1791874D01*
Y929086D01*
X1795074D01*
G01X1795774Y922849D02*
Y929049D01*
X1798974D01*
Y922849D01*
X1795774D01*
G01X1800256Y915143D02*
Y918243D01*
X1798838Y916021D01*
X1800754D01*
G01X1802244Y915505D02*
X1802513Y915246D01*
X1802819Y915143D01*
X1803126Y915246D01*
X1803394Y915556D01*
X1803586Y916021D01*
X1803663Y916486D01*
Y917055D01*
X1803586Y917520D01*
X1803394Y917933D01*
X1803164Y918140D01*
X1802896Y918243D01*
X1802589Y918140D01*
X1802359Y917933D01*
X1802206Y917623D01*
X1802129Y917210D01*
X1802206Y916848D01*
X1802398Y916486D01*
X1802628Y916280D01*
X1802896Y916228D01*
X1803203Y916331D01*
X1803433Y916590D01*
X1803663Y917055D01*
G01X1804618Y916654D02*
X1807718D01*
X1805496Y918072D01*
Y916156D01*
G01X1804618Y914014D02*
X1804670Y913746D01*
X1804825Y913439D01*
X1805083Y913247D01*
X1805445Y913171D01*
X1805806Y913247D01*
X1806116Y913477D01*
X1806271Y913822D01*
Y914206D01*
X1806375Y914436D01*
X1806633Y914627D01*
X1806995Y914704D01*
X1807356Y914589D01*
X1807615Y914321D01*
X1807718Y914014D01*
X1807615Y913707D01*
X1807356Y913439D01*
X1806995Y913324D01*
X1806633Y913401D01*
X1806375Y913592D01*
X1806271Y913822D01*
Y914206D01*
X1806116Y914551D01*
X1805806Y914781D01*
X1805445Y914857D01*
X1805083Y914781D01*
X1804825Y914589D01*
X1804670Y914282D01*
X1804618Y914014D01*
G01X1793795Y919300D02*
Y915300D01*
G01X1791229Y958949D02*
Y956727D01*
X1791382Y956262D01*
X1791689Y955952D01*
X1792072Y955849D01*
X1792455Y955952D01*
X1792762Y956262D01*
X1792915Y956727D01*
Y958949D01*
G01X1795632Y955849D02*
Y958949D01*
X1794214Y956727D01*
X1796130D01*
G01X1797429Y956469D02*
X1797659Y956107D01*
X1797965Y955901D01*
X1798310Y955849D01*
X1798617Y955901D01*
X1798924Y956159D01*
X1799115Y956469D01*
X1799154Y956779D01*
X1799077Y957141D01*
X1798809Y957399D01*
X1798540Y957502D01*
X1798195D01*
G01X1798540D02*
X1798770Y957657D01*
X1798962Y957916D01*
X1799039Y958226D01*
X1798962Y958536D01*
X1798770Y958794D01*
X1798425Y958949D01*
X1798080Y958897D01*
X1797735Y958691D01*
G01X1800529Y956469D02*
X1800759Y956107D01*
X1801065Y955901D01*
X1801410Y955849D01*
X1801717Y955901D01*
X1802024Y956159D01*
X1802215Y956469D01*
X1802254Y956779D01*
X1802177Y957141D01*
X1801909Y957399D01*
X1801640Y957502D01*
X1801295D01*
G01X1801640D02*
X1801870Y957657D01*
X1802062Y957916D01*
X1802139Y958226D01*
X1802062Y958536D01*
X1801870Y958794D01*
X1801525Y958949D01*
X1801180Y958897D01*
X1800835Y958691D01*
G01X1793963Y961560D02*
Y967560D01*
X1805963D01*
Y961560D01*
X1793963D01*
G01X1799263Y969552D02*
X1801867D01*
G01D02*
Y970356D01*
G01X1806649Y983460D02*
X1800449D01*
Y986660D01*
X1806649D01*
Y983460D01*
G01X1801867Y980756D02*
Y981560D01*
X1799363D01*
G01X1794578Y1007450D02*
Y997250D01*
X1789978D01*
Y1007450D01*
X1794578D01*
G01X1800020D02*
Y997250D01*
X1795420D01*
Y1007450D01*
X1800020D01*
G01X1807012Y995358D02*
X1801012D01*
Y1007358D01*
X1807012D01*
Y995358D01*
G01X1797944Y1020152D02*
Y1013952D01*
X1794744D01*
Y1020152D01*
X1797944D01*
G01X1804032D02*
Y1013952D01*
X1800832D01*
Y1020152D01*
X1804032D01*
G01X1800765Y1077988D02*
X1810965D01*
Y1073388D01*
X1800765D01*
Y1077988D01*
G01X1801448Y1088249D02*
Y1090202D01*
G01X1803401Y1088249D02*
X1801448D01*
G01X1802370Y1084473D02*
X1800108Y1082211D01*
G01X1797986Y1088857D02*
X1802370Y1084473D01*
G01X1795724Y1086595D02*
X1797986Y1088857D01*
G01X1800108Y1082211D02*
X1795724Y1086595D01*
G01X1794477Y1089461D02*
Y1086261D01*
G01X1803271Y1083850D02*
X1809471D01*
G01X1803271Y1080650D02*
Y1083850D01*
G01X1809471Y1080650D02*
X1803271D01*
G01X1801448Y1100061D02*
X1803401D01*
G01X1801448Y1098108D02*
Y1100061D01*
G01X1799938Y1104846D02*
Y1101646D01*
G01X1793738Y1104846D02*
X1799938D01*
G01X1793738Y1101646D02*
Y1104846D01*
G01X1799938Y1101646D02*
X1793738D01*
G01X1796947Y1094535D02*
X1793747D01*
G01X1796947Y1100735D02*
Y1094535D01*
G01X1793747Y1100735D02*
X1796947D01*
G01X1793747Y1094535D02*
Y1100735D01*
G01X1823248Y1123289D02*
Y1130416D01*
X1804594D01*
X1801594Y1127416D01*
Y1123289D01*
G01Y1115889D02*
Y1111762D01*
X1804594Y1108762D01*
G01D02*
X1823248D01*
Y1115889D01*
G01X1818496Y1141881D02*
X1800902D01*
G01X1798971Y1200139D02*
Y1203339D01*
G01X1805171Y1200139D02*
X1798971D01*
G01X1805171Y1203339D02*
Y1200139D01*
G01X1798971Y1203339D02*
X1805171D01*
G01X1791932Y1201156D02*
Y1204356D01*
G01X1798132Y1201156D02*
X1791932D01*
G01X1798132Y1204356D02*
Y1201156D01*
G01X1791932Y1204356D02*
X1798132D01*
G01X1803784Y1204794D02*
Y1210994D01*
G01X1806984Y1204794D02*
X1803784D01*
G01X1800902Y1195817D02*
X1818496D01*
G01X1790690Y1205623D02*
Y1202623D01*
G01X1803784Y1210994D02*
X1806984D01*
G01X1806303Y1214753D02*
X1803103D01*
G01Y1220953D02*
X1806303D01*
G01X1803103Y1214753D02*
Y1220953D01*
G01X1794190Y1207252D02*
X1797992D01*
Y1207523D01*
G01X1799690Y1215323D02*
X1801190D01*
G01X1796897Y1234477D02*
X1808897D01*
G01X1796897Y1228477D02*
Y1234477D01*
G01X1808897Y1228477D02*
X1796897D01*
G01Y1235377D02*
Y1241377D01*
G01X1808897Y1235377D02*
X1796897D01*
G01X1793897Y1239977D02*
Y1233977D01*
G01Y1233077D02*
Y1227077D01*
G01X1801458Y1221598D02*
Y1224798D01*
G01X1807658Y1221598D02*
X1801458D01*
G01Y1224798D02*
X1807658D01*
G01X1801931Y1222970D02*
X1802140Y1223156D01*
X1802223Y1223370D01*
X1802140Y1223583D01*
X1801890Y1223770D01*
X1801515Y1223903D01*
X1801140Y1223956D01*
X1800681D01*
X1800306Y1223903D01*
X1799973Y1223770D01*
X1799806Y1223610D01*
X1799723Y1223423D01*
X1799806Y1223210D01*
X1799973Y1223050D01*
X1800223Y1222943D01*
X1800556Y1222890D01*
X1800848Y1222943D01*
X1801140Y1223076D01*
X1801306Y1223236D01*
X1801348Y1223423D01*
X1801265Y1223636D01*
X1801056Y1223796D01*
X1800681Y1223956D01*
G01X1797992Y1223123D02*
Y1223394D01*
G01D02*
X1794190D01*
G01X1793090Y1225023D02*
Y1228023D01*
G01X1796772Y1250008D02*
X1801372D01*
G01Y1260008D02*
Y1250008D01*
G01X1796772D02*
Y1260008D01*
G01X1796897Y1241377D02*
X1808897D01*
G01X1796897Y1248277D02*
X1808897D01*
G01X1796897Y1242277D02*
Y1248277D01*
G01X1808897Y1242277D02*
X1796897D01*
G01X1793897Y1246877D02*
Y1240877D01*
G01Y1253777D02*
Y1247777D01*
G01X1796772Y1260008D02*
X1801372D01*
G01X1801272D02*
X1801372D01*
G01X1795774Y1259537D02*
Y1256337D01*
G01X1805485Y1442240D02*
Y1436040D01*
X1802285D01*
Y1442240D01*
X1805485D01*
G01X1798421Y1446143D02*
X1804621D01*
Y1442943D01*
X1798421D01*
Y1446143D01*
G01X1798446Y1436046D02*
Y1442246D01*
X1801646D01*
Y1436046D01*
X1798446D01*
G01X1805362Y1474430D02*
Y1468230D01*
X1802162D01*
Y1474430D01*
X1805362D01*
G01X1798323Y1468236D02*
Y1474436D01*
X1801523D01*
Y1468236D01*
X1798323D01*
G01X1798298Y1478333D02*
X1804498D01*
Y1475133D01*
X1798298D01*
Y1478333D01*
G01X1803579Y1576751D02*
Y1579851D01*
G01X1805189D02*
Y1576751D01*
G01Y1578301D02*
X1803579D01*
G01X1807407Y1576751D02*
X1807484Y1577423D01*
X1807599Y1577991D01*
X1807752Y1578508D01*
X1807944Y1579076D01*
X1808251Y1579851D01*
X1806717D01*
G01X1809741Y1577216D02*
X1809971Y1576958D01*
X1810239Y1576803D01*
X1810584Y1576751D01*
X1810929Y1576854D01*
X1811197Y1577061D01*
X1811389Y1577423D01*
X1811427Y1577836D01*
X1811351Y1578249D01*
X1811159Y1578508D01*
X1810891Y1578714D01*
X1810622Y1578766D01*
X1810354Y1578714D01*
X1810009Y1578508D01*
X1810124Y1579851D01*
X1811159D01*
G01X1798645Y1623824D02*
Y1626924D01*
G01X1800255D02*
Y1623824D01*
G01Y1625374D02*
X1798645D01*
G01X1801822Y1625116D02*
X1802090Y1625477D01*
X1802320Y1625684D01*
X1802627Y1625787D01*
X1802895Y1625684D01*
X1803087Y1625477D01*
X1803240Y1625167D01*
X1803278Y1624806D01*
X1803240Y1624496D01*
X1803087Y1624186D01*
X1802857Y1623927D01*
X1802588Y1623824D01*
X1802282Y1623927D01*
X1802013Y1624237D01*
X1801860Y1624702D01*
X1801822Y1625219D01*
X1801898Y1625891D01*
X1802013Y1626252D01*
X1802205Y1626614D01*
X1802473Y1626872D01*
X1802742Y1626924D01*
X1803010Y1626821D01*
X1803202Y1626562D01*
G01X1805650Y1623824D02*
Y1626924D01*
X1805190Y1626304D01*
G01Y1623824D02*
X1806110D01*
G01X1809331Y406628D02*
Y422140D01*
G01X1812656Y411937D02*
Y415037D01*
X1813576D01*
X1813883Y414882D01*
X1814113Y414520D01*
X1814190Y414107D01*
X1814113Y413694D01*
X1813921Y413384D01*
X1813576Y413229D01*
X1812656D01*
G01X1815680Y411937D02*
Y415037D01*
X1816446D01*
X1816753Y414882D01*
X1816983Y414675D01*
X1817175Y414365D01*
X1817328Y414004D01*
X1817366Y413487D01*
X1817328Y412970D01*
X1817175Y412609D01*
X1816983Y412299D01*
X1816753Y412092D01*
X1816446Y411937D01*
X1815680D01*
G01X1819623D02*
Y415037D01*
X1819163Y414417D01*
G01Y411937D02*
X1820083D01*
G01X1822646D02*
X1822723Y412609D01*
X1822838Y413177D01*
X1822991Y413694D01*
X1823183Y414262D01*
X1823490Y415037D01*
X1821956D01*
G01X1816533Y426201D02*
Y423001D01*
G01X1810333D02*
Y426201D01*
G01X1816533Y423001D02*
X1810333D01*
G01X1816533Y429701D02*
Y426501D01*
G01X1810333Y429701D02*
X1816533D01*
G01X1810333Y426501D02*
Y429701D01*
G01X1816533Y426501D02*
X1810333D01*
G01Y433501D02*
Y436701D01*
G01X1816533Y433501D02*
X1810333D01*
G01X1816533Y436701D02*
Y433501D01*
G01X1810333Y436701D02*
X1816533D01*
G01X1810333Y441501D02*
Y444701D01*
G01X1816533Y441501D02*
X1810333D01*
G01X1816533Y444701D02*
Y441501D01*
G01X1810333Y426201D02*
X1816533D01*
G01X1810333Y437501D02*
Y440701D01*
G01X1816533Y437501D02*
X1810333D01*
G01X1816533Y440701D02*
Y437501D01*
G01X1810333Y440701D02*
X1816533D01*
G01Y433201D02*
Y430001D01*
G01X1810333Y433201D02*
X1816533D01*
G01X1810333Y430001D02*
Y433201D01*
G01X1816533Y430001D02*
X1810333D01*
G01X1808434Y443639D02*
Y437439D01*
G01X1810333Y444701D02*
X1816533D01*
G01X1810333Y445501D02*
Y448701D01*
G01X1816533Y445501D02*
X1810333D01*
G01X1816533Y448701D02*
Y445501D01*
G01X1810333Y448701D02*
X1816533D01*
G01X1806533Y460701D02*
Y454501D01*
G01X1810333Y451001D02*
Y454201D01*
G01X1816533Y451001D02*
X1810333D01*
G01X1816533Y454201D02*
Y451001D01*
G01X1810333Y454201D02*
X1816533D01*
G01X1820175Y795869D02*
X1812675D01*
Y798109D01*
X1813050Y798856D01*
X1813925Y799416D01*
X1814925Y799603D01*
X1815925Y799416D01*
X1816675Y798949D01*
X1817050Y798109D01*
Y795869D01*
G01X1820175Y807103D02*
Y803369D01*
X1812675D01*
Y807103D01*
G01X1816300Y805609D02*
Y803369D01*
G01X1820175Y810776D02*
X1812675Y814696D01*
G01Y810776D02*
X1820175Y814696D01*
G01Y825683D02*
X1812675D01*
Y827549D01*
X1813050Y828296D01*
X1813550Y828856D01*
X1814300Y829323D01*
X1815175Y829696D01*
X1816425Y829789D01*
X1817675Y829696D01*
X1818550Y829323D01*
X1819300Y828856D01*
X1819800Y828296D01*
X1820175Y827549D01*
Y825683D01*
G01Y837103D02*
Y833369D01*
X1812675D01*
Y837103D01*
G01X1816300Y835609D02*
Y833369D01*
G01X1816175Y843483D02*
X1815800Y843856D01*
X1815175Y844136D01*
X1814300Y844323D01*
X1813550Y844136D01*
X1813050Y843763D01*
X1812675Y843109D01*
Y840589D01*
X1820175D01*
Y843669D01*
X1819675Y844323D01*
X1818925Y844696D01*
X1818050Y844883D01*
X1817175Y844696D01*
X1816425Y844136D01*
X1816175Y843483D01*
Y840589D01*
G01X1812675Y848183D02*
X1818050D01*
X1819175Y848556D01*
X1819925Y849303D01*
X1820175Y850236D01*
X1819925Y851169D01*
X1819175Y851916D01*
X1818050Y852289D01*
X1812675D01*
G01X1816425Y858296D02*
Y860163D01*
X1818675D01*
X1819425Y859603D01*
X1819925Y858949D01*
X1820175Y858016D01*
X1819925Y857083D01*
X1819425Y856429D01*
X1818675Y855869D01*
X1817800Y855496D01*
X1816800Y855309D01*
X1815925D01*
X1815175Y855496D01*
X1814300Y855869D01*
X1813550Y856429D01*
X1813050Y856989D01*
X1812675Y857736D01*
Y858389D01*
X1812925Y859136D01*
X1813425Y859696D01*
G01X1809580Y807983D02*
X1809890Y808175D01*
X1810097Y808405D01*
X1810200Y808673D01*
X1810097Y808980D01*
X1809890Y809210D01*
X1809580Y809440D01*
X1809167Y809517D01*
X1807100D01*
G01X1809735Y811007D02*
X1809993Y811237D01*
X1810148Y811505D01*
X1810200Y811850D01*
X1810097Y812195D01*
X1809890Y812463D01*
X1809528Y812655D01*
X1809115Y812693D01*
X1808702Y812617D01*
X1808443Y812425D01*
X1808237Y812157D01*
X1808185Y811888D01*
X1808237Y811620D01*
X1808443Y811275D01*
X1807100Y811390D01*
Y812425D01*
G01X1810200Y815410D02*
X1807100D01*
X1809322Y813992D01*
Y815908D01*
G01X1807021Y899452D02*
Y897230D01*
X1807174Y896765D01*
X1807481Y896455D01*
X1807864Y896352D01*
X1808247Y896455D01*
X1808554Y896765D01*
X1808707Y897230D01*
Y899452D01*
G01X1811424Y896352D02*
Y899452D01*
X1810006Y897230D01*
X1811922D01*
G01X1813221Y896972D02*
X1813451Y896610D01*
X1813757Y896404D01*
X1814102Y896352D01*
X1814409Y896404D01*
X1814716Y896662D01*
X1814907Y896972D01*
X1814946Y897282D01*
X1814869Y897644D01*
X1814601Y897902D01*
X1814332Y898005D01*
X1813987D01*
G01X1814332D02*
X1814562Y898160D01*
X1814754Y898419D01*
X1814831Y898729D01*
X1814754Y899039D01*
X1814562Y899297D01*
X1814217Y899452D01*
X1813872Y899400D01*
X1813527Y899194D01*
G01X1817624Y896352D02*
Y899452D01*
X1816206Y897230D01*
X1818122D01*
G01X1808100Y905500D02*
Y911700D01*
X1811300D01*
Y905500D01*
X1808100D01*
G01X1806763Y968560D02*
Y974760D01*
X1809963D01*
Y968560D01*
X1806763D01*
G01Y975974D02*
Y982174D01*
X1809963D01*
Y975974D01*
X1806763D01*
G01X1827814Y995395D02*
X1821814D01*
Y1007395D01*
X1827814D01*
Y995395D01*
G01X1820965Y995358D02*
X1814965D01*
Y1007358D01*
X1820965D01*
Y995358D01*
G01X1814133D02*
X1808133D01*
Y1007358D01*
X1814133D01*
Y995358D01*
G01X1809920Y1020152D02*
Y1013952D01*
X1806720D01*
Y1020152D01*
X1809920D01*
G01X1813865D02*
Y1013952D01*
X1810665D01*
Y1020152D01*
X1813865D01*
G01X1817860D02*
Y1013952D01*
X1814660D01*
Y1020152D01*
X1817860D01*
G01X1807348Y1031210D02*
Y1044297D01*
G01Y1058821D02*
Y1070510D01*
G01X1808640Y1055618D02*
Y1046718D01*
G01X1814964Y1073912D02*
Y1071690D01*
X1815117Y1071225D01*
X1815424Y1070915D01*
X1815807Y1070812D01*
X1816190Y1070915D01*
X1816497Y1071225D01*
X1816650Y1071690D01*
Y1073912D01*
G01X1818255Y1071174D02*
X1818524Y1070915D01*
X1818830Y1070812D01*
X1819137Y1070915D01*
X1819405Y1071225D01*
X1819597Y1071690D01*
X1819674Y1072155D01*
Y1072724D01*
X1819597Y1073189D01*
X1819405Y1073602D01*
X1819175Y1073809D01*
X1818907Y1073912D01*
X1818600Y1073809D01*
X1818370Y1073602D01*
X1818217Y1073292D01*
X1818140Y1072879D01*
X1818217Y1072517D01*
X1818409Y1072155D01*
X1818639Y1071949D01*
X1818907Y1071897D01*
X1819214Y1072000D01*
X1819444Y1072259D01*
X1819674Y1072724D01*
G01X1821164Y1071277D02*
X1821394Y1071019D01*
X1821662Y1070864D01*
X1822007Y1070812D01*
X1822352Y1070915D01*
X1822620Y1071122D01*
X1822812Y1071484D01*
X1822850Y1071897D01*
X1822774Y1072310D01*
X1822582Y1072569D01*
X1822314Y1072775D01*
X1822045Y1072827D01*
X1821777Y1072775D01*
X1821432Y1072569D01*
X1821547Y1073912D01*
X1822582D01*
G01X1813260Y1090202D02*
Y1088249D01*
G01D02*
X1811307D01*
G01X1817631Y1075545D02*
Y1078745D01*
G01X1823831Y1075545D02*
X1817631D01*
G01Y1078745D02*
X1823831D01*
G01X1817631Y1079545D02*
Y1082745D01*
G01X1823831Y1079545D02*
X1817631D01*
G01Y1082745D02*
X1823831D01*
G01X1817631Y1087545D02*
Y1090745D01*
G01X1823831Y1087545D02*
X1817631D01*
G01Y1090745D02*
X1823831D01*
G01X1817631Y1083545D02*
Y1086745D01*
G01X1823831Y1083545D02*
X1817631D01*
G01Y1086745D02*
X1823831D01*
G01X1809471Y1083850D02*
Y1080650D01*
G01X1813260Y1100061D02*
Y1098108D01*
G01X1811307Y1100061D02*
X1813260D01*
G01X1817631Y1091545D02*
Y1094745D01*
G01X1823831Y1091545D02*
X1817631D01*
G01Y1094745D02*
X1823831D01*
G01X1817631Y1102745D02*
X1823831D01*
G01X1817631Y1099545D02*
Y1102745D01*
G01X1823831Y1099545D02*
X1817631D01*
G01Y1106745D02*
X1823831D01*
G01X1817631Y1103545D02*
Y1106745D01*
G01X1823831Y1103545D02*
X1817631D01*
G01Y1095545D02*
Y1098745D01*
G01X1823831Y1095545D02*
X1817631D01*
G01Y1098745D02*
X1823831D01*
G01X1808710Y1132812D02*
Y1136012D01*
G01X1814910Y1132812D02*
X1808710D01*
G01X1814910Y1136012D02*
Y1132812D01*
G01X1808710Y1136012D02*
X1814910D01*
G01X1818496Y1195817D02*
Y1141881D01*
G01X1823769Y1184432D02*
X1820669D01*
Y1185352D01*
X1820824Y1185659D01*
X1821186Y1185889D01*
X1821599Y1185966D01*
X1822012Y1185889D01*
X1822322Y1185697D01*
X1822477Y1185352D01*
Y1184432D01*
G01X1820669Y1187532D02*
X1823769D01*
Y1189066D01*
G01X1821186Y1190671D02*
X1820876Y1190901D01*
X1820721Y1191169D01*
X1820669Y1191476D01*
X1820772Y1191859D01*
X1821031Y1192127D01*
X1821341Y1192204D01*
X1821651Y1192166D01*
X1821909Y1192012D01*
X1822426Y1191246D01*
X1822787Y1190901D01*
X1823304Y1190671D01*
X1823769Y1190594D01*
Y1192204D01*
G01Y1194959D02*
X1820669D01*
X1822891Y1193541D01*
Y1195457D01*
G01X1807749Y1203634D02*
Y1209834D01*
G01X1810949Y1203634D02*
X1807749D01*
G01X1810949Y1209834D02*
Y1203634D01*
G01X1806984Y1210994D02*
Y1204794D01*
G01X1807749Y1209834D02*
X1810949D01*
G01X1808332Y1217609D02*
Y1220809D01*
G01X1814532Y1217609D02*
X1808332D01*
G01X1814532Y1220809D02*
Y1217609D01*
G01X1808332Y1220809D02*
X1814532D01*
G01X1810800Y1210624D02*
X1807600D01*
G01X1810800Y1216824D02*
Y1210624D01*
G01X1807600Y1216824D02*
X1810800D01*
G01X1807600Y1210624D02*
Y1216824D01*
G01X1811427Y1216560D02*
X1814627D01*
G01X1811427Y1210360D02*
Y1216560D01*
G01X1814627Y1210360D02*
X1811427D01*
G01X1814627Y1216560D02*
Y1210360D01*
G01X1806303Y1220953D02*
Y1214753D01*
G01X1808897Y1234477D02*
Y1228477D01*
G01Y1241377D02*
Y1235377D01*
G01X1807658Y1224798D02*
Y1221598D01*
G01X1814532Y1224809D02*
Y1221609D01*
G01X1808332Y1224809D02*
X1814532D01*
G01X1808332Y1221609D02*
Y1224809D01*
G01X1814532Y1221609D02*
X1808332D01*
G01X1808897Y1248277D02*
Y1242277D01*
G01X1818368Y1251600D02*
Y1254700D01*
G01X1819978D02*
Y1251600D01*
G01Y1253150D02*
X1818368D01*
G01X1822273Y1251600D02*
Y1254700D01*
X1821813Y1254080D01*
G01Y1251600D02*
X1822733D01*
G01X1824530Y1252220D02*
X1824760Y1251858D01*
X1825066Y1251652D01*
X1825411Y1251600D01*
X1825718Y1251652D01*
X1826025Y1251910D01*
X1826216Y1252220D01*
X1826255Y1252530D01*
X1826178Y1252892D01*
X1825910Y1253150D01*
X1825641Y1253253D01*
X1825296D01*
G01X1825641D02*
X1825871Y1253408D01*
X1826063Y1253667D01*
X1826140Y1253977D01*
X1826063Y1254287D01*
X1825871Y1254545D01*
X1825526Y1254700D01*
X1825181Y1254648D01*
X1824836Y1254442D01*
G01X1828396Y1251600D02*
X1828473Y1252272D01*
X1828588Y1252840D01*
X1828741Y1253357D01*
X1828933Y1253925D01*
X1829240Y1254700D01*
X1827706D01*
G01X1827673Y1567323D02*
G02I-10350J0D01*
G01X1823831Y1078745D02*
Y1075545D01*
G01Y1082745D02*
Y1079545D01*
G01Y1090745D02*
Y1087545D01*
G01Y1086745D02*
Y1083545D01*
G01Y1094745D02*
Y1091545D01*
G01Y1102745D02*
Y1099545D01*
G01Y1106745D02*
Y1103545D01*
G01Y1098745D02*
Y1095545D01*
G01X1826672Y1104471D02*
Y1110671D01*
G01X1829872Y1104471D02*
X1826672D01*
G01X1829872Y1110671D02*
Y1104471D01*
G01X1826672Y1103632D02*
X1829872D01*
G01X1826672Y1097432D02*
Y1103632D01*
G01X1829872Y1097432D02*
X1826672D01*
G01X1829872Y1103632D02*
Y1097432D01*
G01X1826672Y1110671D02*
X1829872D01*
M02*
